(kicad_pcb
	(version 20240108)
	(generator "pcbnew")
	(generator_version "8.0")
	(general
		(thickness 1.6)
		(legacy_teardrops no)
	)
	(paper "A4")
	(title_block
		(title "Jetson Orin Baseboard OCuLink Expansion")
		(date "2025-03-18")
		(rev "1.1.0")
		(company "Antmicro Ltd")
		(comment 1 "www.antmicro.com")
	)
	(layers
		(0 "F.Cu" signal)
		(1 "In1.Cu" signal)
		(2 "In2.Cu" signal)
		(31 "B.Cu" signal)
		(32 "B.Adhes" user "B.Adhesive")
		(33 "F.Adhes" user "F.Adhesive")
		(34 "B.Paste" user)
		(35 "F.Paste" user)
		(36 "B.SilkS" user "B.Silkscreen")
		(37 "F.SilkS" user "F.Silkscreen")
		(38 "B.Mask" user)
		(39 "F.Mask" user)
		(40 "Dwgs.User" user "User.Drawings")
		(41 "Cmts.User" user "User.Comments")
		(42 "Eco1.User" user "User.Eco1")
		(43 "Eco2.User" user "User.Eco2")
		(44 "Edge.Cuts" user)
		(45 "Margin" user)
		(46 "B.CrtYd" user "B.Courtyard")
		(47 "F.CrtYd" user "F.Courtyard")
		(48 "B.Fab" user)
		(49 "F.Fab" user)
	)
	(setup
		(stackup
			(layer "F.SilkS"
				(type "Top Silk Screen")
				(color "White")
			)
			(layer "F.Paste"
				(type "Top Solder Paste")
			)
			(layer "F.Mask"
				(type "Top Solder Mask")
				(color "Black")
				(thickness 0.01)
			)
			(layer "F.Cu"
				(type "copper")
				(thickness 0.035)
			)
			(layer "dielectric 1"
				(type "prepreg")
				(color "FR4 natural")
				(thickness 0.12)
				(material "FR4")
				(epsilon_r 4.5)
				(loss_tangent 0.02)
			)
			(layer "In1.Cu"
				(type "copper")
				(thickness 0.035)
			)
			(layer "dielectric 2"
				(type "core")
				(color "FR4 natural")
				(thickness 1.2)
				(material "FR4")
				(epsilon_r 4.5)
				(loss_tangent 0.02)
			)
			(layer "In2.Cu"
				(type "copper")
				(thickness 0.035)
			)
			(layer "dielectric 3"
				(type "prepreg")
				(color "FR4 natural")
				(thickness 0.12)
				(material "FR4")
				(epsilon_r 4.5)
				(loss_tangent 0.02)
			)
			(layer "B.Cu"
				(type "copper")
				(thickness 0.035)
			)
			(layer "B.Mask"
				(type "Bottom Solder Mask")
				(color "Black")
				(thickness 0.01)
			)
			(layer "B.Paste"
				(type "Bottom Solder Paste")
			)
			(layer "B.SilkS"
				(type "Bottom Silk Screen")
				(color "White")
			)
			(copper_finish "None")
			(dielectric_constraints no)
		)
		(pad_to_mask_clearance 0)
		(allow_soldermask_bridges_in_footprints no)
		(grid_origin 194 114)
		(pcbplotparams
			(layerselection 0x00010fc_ffffffff)
			(plot_on_all_layers_selection 0x0000000_00000000)
			(disableapertmacros no)
			(usegerberextensions no)
			(usegerberattributes yes)
			(usegerberadvancedattributes yes)
			(creategerberjobfile yes)
			(dashed_line_dash_ratio 12.000000)
			(dashed_line_gap_ratio 3.000000)
			(svgprecision 4)
			(plotframeref no)
			(viasonmask no)
			(mode 1)
			(useauxorigin no)
			(hpglpennumber 1)
			(hpglpenspeed 20)
			(hpglpendiameter 15.000000)
			(pdf_front_fp_property_popups yes)
			(pdf_back_fp_property_popups yes)
			(dxfpolygonmode yes)
			(dxfimperialunits yes)
			(dxfusepcbnewfont yes)
			(psnegative no)
			(psa4output no)
			(plotreference yes)
			(plotvalue yes)
			(plotfptext yes)
			(plotinvisibletext no)
			(sketchpadsonfab no)
			(subtractmaskfromsilk no)
			(outputformat 1)
			(mirror no)
			(drillshape 0)
			(scaleselection 1)
			(outputdirectory "gerber/")
		)
	)
	(net 0 "")
	(net 1 "unconnected-(J1-PET3--PadB19)")
	(net 2 "unconnected-(J1-PER3+-PadA18)")
	(net 3 "unconnected-(J1-PER3--PadA19)")
	(net 4 "unconnected-(J1-PET2+-PadB15)")
	(net 5 "unconnected-(J1-PER2+-PadA15)")
	(net 6 "unconnected-(J1-NC-PadA9)")
	(net 7 "unconnected-(J1-PER2--PadA16)")
	(net 8 "unconnected-(J1-PET3+-PadB18)")
	(net 9 "unconnected-(J1-PET2--PadB16)")
	(net 10 "unconnected-(J2-Pad53)")
	(net 11 "unconnected-(J2-Pad24)")
	(net 12 "unconnected-(J2-Pad58)")
	(net 13 "unconnected-(J2-Pad23)")
	(net 14 "unconnected-(J2-Pad26)")
	(net 15 "unconnected-(J2-Pad18)")
	(net 16 "unconnected-(J2-Pad68)")
	(net 17 "unconnected-(J2-Pad59)")
	(net 18 "unconnected-(J2-Pad54)")
	(net 19 "unconnected-(J2-Pad47)")
	(net 20 "+1V8")
	(net 21 "unconnected-(J2-Pad57)")
	(net 22 "unconnected-(J2-Pad51)")
	(net 23 "+3V3")
	(net 24 "unconnected-(J2-Pad43)")
	(net 25 "unconnected-(J2-Pad55)")
	(net 26 "unconnected-(J2-Pad40)")
	(net 27 "unconnected-(J2-Pad31)")
	(net 28 "unconnected-(J2-Pad52)")
	(net 29 "unconnected-(J2-Pad42)")
	(net 30 "unconnected-(J2-Pad70)")
	(net 31 "/PCIE_{O}_C.TX0-")
	(net 32 "unconnected-(J2-Pad64)")
	(net 33 "unconnected-(J2-Pad30)")
	(net 34 "unconnected-(J2-Pad56)")
	(net 35 "unconnected-(J2-Pad21)")
	(net 36 "unconnected-(J2-Pad80)")
	(net 37 "unconnected-(J2-Pad78)")
	(net 38 "unconnected-(J2-Pad39)")
	(net 39 "unconnected-(J2-Pad45)")
	(net 40 "unconnected-(J2-Pad41)")
	(net 41 "unconnected-(J2-Pad60)")
	(net 42 "unconnected-(J2-Pad44)")
	(net 43 "unconnected-(J2-Pad48)")
	(net 44 "unconnected-(J2-Pad74)")
	(net 45 "unconnected-(J2-Pad36)")
	(net 46 "unconnected-(J2-Pad29)")
	(net 47 "unconnected-(J2-Pad66)")
	(net 48 "unconnected-(J2-Pad20)")
	(net 49 "unconnected-(J2-Pad46)")
	(net 50 "unconnected-(J2-Pad32)")
	(net 51 "GND")
	(net 52 "+5V")
	(net 53 "/PCIE_CLK+")
	(net 54 "Net-(J1-~{CWAKE})")
	(net 55 "/PCIE_CLK-")
	(net 56 "/PCIE_{O}_TX0-")
	(net 57 "/PCIE_{O}_C.TX1+")
	(net 58 "/PCIE_{O}_TX1+")
	(net 59 "/~{PCIE_RST}")
	(net 60 "/PCIE_{O}_C.TX1-")
	(net 61 "/I2C_SDA")
	(net 62 "/PCIE_{O}_TX1-")
	(net 63 "/PCIE_{O}_C.TX0+")
	(net 64 "/I2C_SCL")
	(net 65 "/JOB_GPIO09")
	(net 66 "Net-(J1-~{CPRSNT})")
	(net 67 "/JOB_GPIO07")
	(net 68 "unconnected-(J2-Pad34)")
	(net 69 "/~{PCIE_CWAKE}")
	(net 70 "Net-(U1-~{THREE_STATE})")
	(net 71 "/~{CPRSNT}")
	(net 72 "/PCIE_{O}_TX0+")
	(net 73 "/PCIE_{I}_C.RX0-")
	(net 74 "/PCIE_{I}_RX0-")
	(net 75 "/PCIE_{I}_RX1-")
	(net 76 "/PCIE_{I}_C.RX1-")
	(net 77 "/PCIE_{I}_C.RX0+")
	(net 78 "/PCIE_{I}_RX0+")
	(net 79 "/PCIE_{I}_RX1+")
	(net 80 "/PCIE_{I}_C.RX1+")
	(net 81 "/PCIE_{O}_RX0+")
	(net 82 "/PCIE_{O}_RX1+")
	(net 83 "/PCIE_{O}_RX0-")
	(net 84 "/PCIE_{O}_RX1-")
	(net 85 "/PCIE_{I}_TX0-")
	(net 86 "/PCIE_{I}_TX1+")
	(net 87 "/PCIE_{I}_TX1-")
	(net 88 "/PCIE_{I}_TX0+")
	(net 89 "/RX_EQ0")
	(net 90 "/RX_EQ1")
	(net 91 "/RX_EQ2")
	(net 92 "/RX_FG0")
	(net 93 "/RX_FG1")
	(net 94 "/RX_SW")
	(net 95 "Net-(U2-SDA)")
	(net 96 "/TX_EQ0")
	(net 97 "Net-(U2-RXDET)")
	(net 98 "/TX_EQ1")
	(net 99 "/TX_EQ2")
	(net 100 "/TX_FG0")
	(net 101 "/TX_FG1")
	(net 102 "/TX_SW")
	(net 103 "Net-(U2-EN_{I2C})")
	(net 104 "Net-(U3-RXDET)")
	(net 105 "Net-(U3-EN_{I2C})")
	(net 106 "Net-(U2-SCL)")
	(net 107 "Net-(U3-SDA)")
	(net 108 "Net-(U3-SCL)")
	(net 109 "Net-(U2-I2C_{DONE})")
	(net 110 "Net-(U2-~{I2C_{RESET}})")
	(net 111 "Net-(U3-I2C_{DONE})")
	(net 112 "Net-(U3-~{I2C_{RESET}})")
	(net 113 "unconnected-(U2-A2RX--Pad11)")
	(net 114 "unconnected-(U2-A3RX--Pad14)")
	(net 115 "unconnected-(U2-A3TX--Pad25)")
	(net 116 "unconnected-(U2-A2TX+-Pad29)")
	(net 117 "unconnected-(U2-A2TX--Pad28)")
	(net 118 "unconnected-(U2-A2RX+-Pad10)")
	(net 119 "unconnected-(U3-A2TX--Pad28)")
	(net 120 "unconnected-(U3-A2TX+-Pad29)")
	(net 121 "unconnected-(U3-A3TX--Pad25)")
	(net 122 "unconnected-(U3-A2RX+-Pad10)")
	(net 123 "unconnected-(U3-A3RX--Pad14)")
	(net 124 "unconnected-(U3-A2RX--Pad11)")
	(net 125 "Net-(J1-SDA)")
	(net 126 "Net-(J1-SCL)")
	(net 127 "unconnected-(U2-A3RX+-Pad13)")
	(net 128 "unconnected-(U2-A3TX+-Pad26)")
	(net 129 "unconnected-(U3-A3TX+-Pad26)")
	(net 130 "unconnected-(U3-AD1-Pad17)")
	(net 131 "unconnected-(U3-A3RX+-Pad13)")
	(net 132 "+3V3_OCU")
	(net 133 "+5V_OCU")
	(net 134 "Net-(U4-OUT)")
	(net 135 "Net-(U5-OUT)")
	(net 136 "Net-(U4-FLG)")
	(net 137 "Net-(U4-ISET)")
	(net 138 "Net-(U5-FLG)")
	(net 139 "Net-(U5-ISET)")
	(footprint "antmicro-footprints:R_0402_1005Metric"
		(layer "F.Cu")
		(at 121.73 136.96 -90)
		(descr "Resistor SMD 0402")
		(tags "resistor SMD 0402")
		(property "Reference" "R35"
			(at -1.13 -1.66 90)
			(layer "F.SilkS")
			(effects
				(font
					(size 0.7 0.7)
					(thickness 0.15)
				)
				(justify right top)
			)
		)
		(property "Value" "R_0R_0402"
			(at -1.011843 1.772047 90)
			(layer "F.Fab")
			(effects
				(font
					(size 0.7 0.7)
					(thickness 0.15)
				)
				(justify right top)
			)
		)
		(property "Footprint" "antmicro-footprints:R_0402_1005Metric"
			(at 0 0 90)
			(layer "F.Fab")
			(hide yes)
			(effects
				(font
					(size 1.27 1.27)
					(thickness 0.15)
				)
			)
		)
		(property "Datasheet" "https://industrial.panasonic.com/cdbs/www-data/pdf/RDA0000/AOA0000C301.pdf"
			(at 0 0 90)
			(layer "F.Fab")
			(hide yes)
			(effects
				(font
					(size 1.27 1.27)
					(thickness 0.15)
				)
			)
		)
		(property "Description" "SMD Chip Resistor, Jumper, 0 ohm, 100 mW, 0402 [1005 Metric], Thick Film, General Purpose"
			(at 0 0 90)
			(layer "F.Fab")
			(hide yes)
			(effects
				(font
					(size 1.27 1.27)
					(thickness 0.15)
				)
			)
		)
		(property "MPN" "ERJ2GE0R00X"
			(at 0 0 -90)
			(unlocked yes)
			(layer "F.Fab")
			(hide yes)
			(effects
				(font
					(size 1 1)
					(thickness 0.15)
				)
			)
		)
		(property "Manufacturer" "Panasonic"
			(at 0 0 -90)
			(unlocked yes)
			(layer "F.Fab")
			(hide yes)
			(effects
				(font
					(size 1 1)
					(thickness 0.15)
				)
			)
		)
		(property "License" "Apache-2.0"
			(at 0 0 -90)
			(unlocked yes)
			(layer "F.Fab")
			(hide yes)
			(effects
				(font
					(size 1 1)
					(thickness 0.15)
				)
			)
		)
		(property "Author" "Antmicro"
			(at 0 0 -90)
			(unlocked yes)
			(layer "F.Fab")
			(hide yes)
			(effects
				(font
					(size 1 1)
					(thickness 0.15)
				)
			)
		)
		(property "Val" "0R"
			(at 0 0 -90)
			(unlocked yes)
			(layer "F.Fab")
			(hide yes)
			(effects
				(font
					(size 1 1)
					(thickness 0.15)
				)
			)
		)
		(property "Tolerance" ""
			(at 0 0 -90)
			(unlocked yes)
			(layer "F.Fab")
			(hide yes)
			(effects
				(font
					(size 1 1)
					(thickness 0.15)
				)
			)
		)
		(property "Current" "1A"
			(at 0 0 -90)
			(unlocked yes)
			(layer "F.Fab")
			(hide yes)
			(effects
				(font
					(size 1 1)
					(thickness 0.15)
				)
			)
		)
		(sheetname "Root")
		(sheetfile "jetson-orin-baseboard-oculink-expansion.kicad_sch")
		(attr smd)
		(fp_rect
			(start -0.925 -0.47)
			(end 0.925 0.47)
			(stroke
				(width 0.05)
				(type default)
			)
			(fill none)
			(layer "F.CrtYd")
		)
		(fp_rect
			(start -0.5 -0.25)
			(end 0.5 0.25)
			(stroke
				(width 0.15)
				(type solid)
			)
			(fill none)
			(layer "F.Fab")
		)
		(fp_text user "Author: Antmicro"
			(at -0.95 4.169 90)
			(layer "F.Fab")
			(hide yes)
			(effects
				(font
					(size 0.7 0.7)
					(thickness 0.15)
				)
				(justify right top)
			)
		)
		(fp_text user "${REFERENCE}"
			(at -0.95 3.168 90)
			(layer "F.Fab")
			(hide yes)
			(effects
				(font
					(size 0.7 0.7)
					(thickness 0.15)
				)
				(justify right top)
			)
		)
		(fp_text user "License: Apache-2.0"
			(at -0.95 5.169 90)
			(layer "F.Fab")
			(hide yes)
			(effects
				(font
					(size 0.7 0.7)
					(thickness 0.15)
				)
				(justify right top)
			)
		)
		(pad "1" smd roundrect
			(at -0.48 0 270)
			(size 0.59 0.64)
			(layers "F.Cu" "F.Paste" "F.Mask")
			(roundrect_rratio 0.25)
			(net 61 "/I2C_SDA")
			(pintype "passive")
		)
		(pad "2" smd roundrect
			(at 0.48 0 270)
			(size 0.59 0.64)
			(layers "F.Cu" "F.Paste" "F.Mask")
			(roundrect_rratio 0.25)
			(net 125 "Net-(J1-SDA)")
			(pintype "passive")
		)
	)
	(footprint "antmicro-footprints:R_0402_1005Metric"
		(layer "F.Cu")
		(at 142.3 145.4 -90)
		(descr "Resistor SMD 0402")
		(tags "resistor SMD 0402")
		(property "Reference" "R1"
			(at 1.863 0.308 90)
			(layer "F.SilkS")
			(effects
				(font
					(size 0.7 0.7)
					(thickness 0.15)
				)
				(justify right top)
			)
		)
		(property "Value" "R_0R_0402"
			(at -1.011843 1.772047 90)
			(layer "F.Fab")
			(hide yes)
			(effects
				(font
					(size 0.7 0.7)
					(thickness 0.15)
				)
				(justify right top)
			)
		)
		(property "Footprint" "antmicro-footprints:R_0402_1005Metric"
			(at 0 0 90)
			(layer "F.Fab")
			(hide yes)
			(effects
				(font
					(size 1.27 1.27)
					(thickness 0.15)
				)
			)
		)
		(property "Datasheet" "https://industrial.panasonic.com/cdbs/www-data/pdf/RDA0000/AOA0000C301.pdf"
			(at 0 0 90)
			(layer "F.Fab")
			(hide yes)
			(effects
				(font
					(size 1.27 1.27)
					(thickness 0.15)
				)
			)
		)
		(property "Description" "SMD Chip Resistor, Jumper, 0 ohm, 100 mW, 0402 [1005 Metric], Thick Film, General Purpose"
			(at 0 0 90)
			(layer "F.Fab")
			(hide yes)
			(effects
				(font
					(size 1.27 1.27)
					(thickness 0.15)
				)
			)
		)
		(property "MPN" "ERJ2GE0R00X"
			(at 0 0 -90)
			(unlocked yes)
			(layer "F.Fab")
			(hide yes)
			(effects
				(font
					(size 1 1)
					(thickness 0.15)
				)
			)
		)
		(property "Manufacturer" "Panasonic"
			(at 0 0 -90)
			(unlocked yes)
			(layer "F.Fab")
			(hide yes)
			(effects
				(font
					(size 1 1)
					(thickness 0.15)
				)
			)
		)
		(property "License" "Apache-2.0"
			(at 0 0 -90)
			(unlocked yes)
			(layer "F.Fab")
			(hide yes)
			(effects
				(font
					(size 1 1)
					(thickness 0.15)
				)
			)
		)
		(property "Author" "Antmicro"
			(at 0 0 -90)
			(unlocked yes)
			(layer "F.Fab")
			(hide yes)
			(effects
				(font
					(size 1 1)
					(thickness 0.15)
				)
			)
		)
		(property "Val" "0R"
			(at 0 0 -90)
			(unlocked yes)
			(layer "F.Fab")
			(hide yes)
			(effects
				(font
					(size 1 1)
					(thickness 0.15)
				)
			)
		)
		(property "Tolerance" ""
			(at 0 0 -90)
			(unlocked yes)
			(layer "F.Fab")
			(hide yes)
			(effects
				(font
					(size 1 1)
					(thickness 0.15)
				)
			)
		)
		(property "Current" "1A"
			(at 0 0 -90)
			(unlocked yes)
			(layer "F.Fab")
			(hide yes)
			(effects
				(font
					(size 1 1)
					(thickness 0.15)
				)
			)
		)
		(sheetname "Root")
		(sheetfile "jetson-orin-baseboard-oculink-expansion.kicad_sch")
		(attr smd)
		(fp_rect
			(start -0.925 -0.47)
			(end 0.925 0.47)
			(stroke
				(width 0.05)
				(type default)
			)
			(fill none)
			(layer "F.CrtYd")
		)
		(fp_rect
			(start -0.5 -0.25)
			(end 0.5 0.25)
			(stroke
				(width 0.15)
				(type solid)
			)
			(fill none)
			(layer "F.Fab")
		)
		(fp_text user "Author: Antmicro"
			(at -0.95 4.169 90)
			(layer "F.Fab")
			(hide yes)
			(effects
				(font
					(size 0.7 0.7)
					(thickness 0.15)
				)
				(justify right top)
			)
		)
		(fp_text user "License: Apache-2.0"
			(at -0.95 5.169 90)
			(layer "F.Fab")
			(hide yes)
			(effects
				(font
					(size 0.7 0.7)
					(thickness 0.15)
				)
				(justify right top)
			)
		)
		(fp_text user "${REFERENCE}"
			(at -0.95 3.168 90)
			(layer "F.Fab")
			(hide yes)
			(effects
				(font
					(size 0.7 0.7)
					(thickness 0.15)
				)
				(justify right top)
			)
		)
		(pad "1" smd roundrect
			(at -0.48 0 270)
			(size 0.59 0.64)
			(layers "F.Cu" "F.Paste" "F.Mask")
			(roundrect_rratio 0.25)
			(net 71 "/~{CPRSNT}")
			(pintype "passive")
		)
		(pad "2" smd roundrect
			(at 0.48 0 270)
			(size 0.59 0.64)
			(layers "F.Cu" "F.Paste" "F.Mask")
			(roundrect_rratio 0.25)
			(net 66 "Net-(J1-~{CPRSNT})")
			(pintype "passive")
		)
	)
	(footprint "antmicro-footprints:TSOT23-6"
		(layer "F.Cu")
		(at 144 124.201 -90)
		(property "Reference" "U5"
			(at 1.199 -1.55 90)
			(layer "F.SilkS")
			(effects
				(font
					(size 0.7 0.7)
					(thickness 0.15)
				)
				(justify right top)
			)
		)
		(property "Value" "~"
			(at 0 2.6 90)
			(layer "F.Fab")
			(effects
				(font
					(size 0.7 0.7)
					(thickness 0.15)
				)
				(justify right top)
			)
		)
		(property "Footprint" "antmicro-footprints:TSOT23-6"
			(at 0 0 90)
			(layer "F.Fab")
			(hide yes)
			(effects
				(font
					(size 1.27 1.27)
					(thickness 0.15)
				)
			)
		)
		(property "Datasheet" "https://www.mouser.com/datasheet/2/115/DIOD_S_A0008958405_1-2543193.pdf"
			(at 0 0 90)
			(layer "F.Fab")
			(hide yes)
			(effects
				(font
					(size 1.27 1.27)
					(thickness 0.15)
				)
			)
		)
		(property "Description" "Power Load Distribution Switch, High Side, Active High, 1 Output, 5.5 V, 3.6 A, 0.04 ohm, TSOT-26-6"
			(at 0 0 90)
			(layer "F.Fab")
			(hide yes)
			(effects
				(font
					(size 1.27 1.27)
					(thickness 0.15)
				)
			)
		)
		(property "MPN" "AP22615AWU-7"
			(at 0 0 -90)
			(unlocked yes)
			(layer "F.Fab")
			(hide yes)
			(effects
				(font
					(size 1 1)
					(thickness 0.15)
				)
			)
		)
		(property "Manufacturer" "Diodes Incorporated"
			(at 0 0 -90)
			(unlocked yes)
			(layer "F.Fab")
			(hide yes)
			(effects
				(font
					(size 1 1)
					(thickness 0.15)
				)
			)
		)
		(property "Author" "Antmicro"
			(at 0 0 -90)
			(unlocked yes)
			(layer "F.Fab")
			(hide yes)
			(effects
				(font
					(size 1 1)
					(thickness 0.15)
				)
			)
		)
		(property "License" "Apache-2.0"
			(at 0 0 -90)
			(unlocked yes)
			(layer "F.Fab")
			(hide yes)
			(effects
				(font
					(size 1 1)
					(thickness 0.15)
				)
			)
		)
		(sheetname "Root")
		(sheetfile "jetson-orin-baseboard-oculink-expansion.kicad_sch")
		(attr smd)
		(fp_line
			(start -1 1.55)
			(end -1 1.4)
			(stroke
				(width 0.15)
				(type solid)
			)
			(layer "F.SilkS")
		)
		(fp_line
			(start 1 1.55)
			(end -1 1.55)
			(stroke
				(width 0.15)
				(type solid)
			)
			(layer "F.SilkS")
		)
		(fp_line
			(start 1 1.55)
			(end 1 1.4)
			(stroke
				(width 0.15)
				(type solid)
			)
			(layer "F.SilkS")
		)
		(fp_line
			(start 1 -1.497)
			(end 1 -1.375)
			(stroke
				(width 0.15)
				(type solid)
			)
			(layer "F.SilkS")
		)
		(fp_line
			(start 1 -1.497)
			(end -1 -1.5)
			(stroke
				(width 0.15)
				(type solid)
			)
			(layer "F.SilkS")
		)
		(fp_line
			(start -1 -1.5)
			(end -1 -1.375)
			(stroke
				(width 0.15)
				(type solid)
			)
			(layer "F.SilkS")
		)
		(fp_circle
			(center -1.44 -1.5)
			(end -1.39 -1.5)
			(stroke
				(width 0.15)
				(type solid)
			)
			(fill solid)
			(layer "F.SilkS")
		)
		(fp_rect
			(start 1.93 -1.7)
			(end -1.93 1.7)
			(stroke
				(width 0.05)
				(type solid)
			)
			(fill none)
			(layer "F.CrtYd")
		)
		(fp_line
			(start -0.45 -1.521)
			(end -0.876 -1.096)
			(stroke
				(width 0.15)
				(type solid)
			)
			(layer "F.Fab")
		)
		(fp_rect
			(start 0.875 1.528)
			(end -0.875 -1.525)
			(stroke
				(width 0.15)
				(type solid)
			)
			(fill none)
			(layer "F.Fab")
		)
		(fp_text user "License: Apache-2.0"
			(at -1.93 6.199 90)
			(layer "F.Fab")
			(hide yes)
			(effects
				(font
					(size 0.7 0.7)
					(thickness 0.15)
				)
				(justify right top)
			)
		)
		(fp_text user "${REFERENCE}"
			(at -1.93 3.8 90)
			(layer "F.Fab")
			(hide yes)
			(effects
				(font
					(size 0.7 0.7)
					(thickness 0.15)
				)
				(justify right top)
			)
		)
		(fp_text user "Author: Antmicro"
			(at -1.93 5 90)
			(layer "F.Fab")
			(hide yes)
			(effects
				(font
					(size 0.7 0.7)
					(thickness 0.15)
				)
				(justify right top)
			)
		)
		(pad "1" smd rect
			(at -1.301 -0.947 180)
			(size 0.7 1.2)
			(layers "F.Cu" "F.Paste" "F.Mask")
			(net 135 "Net-(U5-OUT)")
			(pinfunction "OUT")
			(pintype "power_out")
		)
		(pad "2" smd rect
			(at -1.301 0.004 180)
			(size 0.7 1.2)
			(layers "F.Cu" "F.Paste" "F.Mask")
			(net 51 "GND")
			(pinfunction "GND")
			(pintype "power_in")
		)
		(pad "3" smd rect
			(at -1.301 0.954 180)
			(size 0.7 1.2)
			(layers "F.Cu" "F.Paste" "F.Mask")
			(net 138 "Net-(U5-FLG)")
			(pinfunction "FLG")
			(pintype "output")
		)
		(pad "4" smd rect
			(at 1.299 0.954 180)
			(size 0.7 1.2)
			(layers "F.Cu" "F.Paste" "F.Mask")
			(net 52 "+5V")
			(pinfunction "EN")
			(pintype "input")
		)
		(pad "5" smd rect
			(at 1.299 0.004 180)
			(size 0.7 1.2)
			(layers "F.Cu" "F.Paste" "F.Mask")
			(net 139 "Net-(U5-ISET)")
			(pinfunction "ISET")
			(pintype "passive")
		)
		(pad "6" smd rect
			(at 1.299 -0.947 180)
			(size 0.7 1.2)
			(layers "F.Cu" "F.Paste" "F.Mask")
			(net 52 "+5V")
			(pinfunction "IN")
			(pintype "power_in")
		)
	)
	(footprint "antmicro-footprints:R_0402_1005Metric"
		(layer "F.Cu")
		(at 128.48 112.36)
		(descr "Resistor SMD 0402")
		(tags "resistor SMD 0402")
		(property "Reference" "R18"
			(at -1.122484 -0.563751 0)
			(layer "F.SilkS")
			(effects
				(font
					(size 0.7 0.7)
					(thickness 0.15)
				)
				(justify left bottom)
			)
		)
		(property "Value" "R_0R_0402"
			(at -1.011843 1.772047 0)
			(layer "F.Fab")
			(effects
				(font
					(size 0.7 0.7)
					(thickness 0.15)
				)
				(justify left bottom)
			)
		)
		(property "Footprint" "antmicro-footprints:R_0402_1005Metric"
			(at 0 0 0)
			(layer "F.Fab")
			(hide yes)
			(effects
				(font
					(size 1.27 1.27)
					(thickness 0.15)
				)
			)
		)
		(property "Datasheet" "https://industrial.panasonic.com/cdbs/www-data/pdf/RDA0000/AOA0000C301.pdf"
			(at 0 0 0)
			(layer "F.Fab")
			(hide yes)
			(effects
				(font
					(size 1.27 1.27)
					(thickness 0.15)
				)
			)
		)
		(property "Description" "SMD Chip Resistor, Jumper, 0 ohm, 100 mW, 0402 [1005 Metric], Thick Film, General Purpose"
			(at 0 0 0)
			(layer "F.Fab")
			(hide yes)
			(effects
				(font
					(size 1.27 1.27)
					(thickness 0.15)
				)
			)
		)
		(property "MPN" "ERJ2GE0R00X"
			(at 0 0 0)
			(unlocked yes)
			(layer "F.Fab")
			(hide yes)
			(effects
				(font
					(size 1 1)
					(thickness 0.15)
				)
			)
		)
		(property "Manufacturer" "Panasonic"
			(at 0 0 0)
			(unlocked yes)
			(layer "F.Fab")
			(hide yes)
			(effects
				(font
					(size 1 1)
					(thickness 0.15)
				)
			)
		)
		(property "License" "Apache-2.0"
			(at 0 0 0)
			(unlocked yes)
			(layer "F.Fab")
			(hide yes)
			(effects
				(font
					(size 1 1)
					(thickness 0.15)
				)
			)
		)
		(property "Author" "Antmicro"
			(at 0 0 0)
			(unlocked yes)
			(layer "F.Fab")
			(hide yes)
			(effects
				(font
					(size 1 1)
					(thickness 0.15)
				)
			)
		)
		(property "Val" "0R"
			(at 0 0 0)
			(unlocked yes)
			(layer "F.Fab")
			(hide yes)
			(effects
				(font
					(size 1 1)
					(thickness 0.15)
				)
			)
		)
		(property "Tolerance" ""
			(at 0 0 0)
			(unlocked yes)
			(layer "F.Fab")
			(hide yes)
			(effects
				(font
					(size 1 1)
					(thickness 0.15)
				)
			)
		)
		(property "Current" "1A"
			(at 0 0 0)
			(unlocked yes)
			(layer "F.Fab")
			(hide yes)
			(effects
				(font
					(size 1 1)
					(thickness 0.15)
				)
			)
		)
		(property "Public" "False"
			(at 0 0 0)
			(unlocked yes)
			(layer "F.Fab")
			(hide yes)
			(effects
				(font
					(size 1 1)
					(thickness 0.15)
				)
			)
		)
		(sheetname "Root")
		(sheetfile "jetson-orin-baseboard-oculink-expansion.kicad_sch")
		(attr smd)
		(fp_rect
			(start -0.925 -0.47)
			(end 0.925 0.47)
			(stroke
				(width 0.05)
				(type default)
			)
			(fill none)
			(layer "F.CrtYd")
		)
		(fp_rect
			(start -0.5 -0.25)
			(end 0.5 0.25)
			(stroke
				(width 0.15)
				(type solid)
			)
			(fill none)
			(layer "F.Fab")
		)
		(fp_text user "License: Apache-2.0"
			(at -0.95 5.169 0)
			(layer "F.Fab")
			(hide yes)
			(effects
				(font
					(size 0.7 0.7)
					(thickness 0.15)
				)
				(justify left bottom)
			)
		)
		(fp_text user "Author: Antmicro"
			(at -0.95 4.169 0)
			(layer "F.Fab")
			(hide yes)
			(effects
				(font
					(size 0.7 0.7)
					(thickness 0.15)
				)
				(justify left bottom)
			)
		)
		(fp_text user "${REFERENCE}"
			(at -0.95 3.168 0)
			(layer "F.Fab")
			(hide yes)
			(effects
				(font
					(size 0.7 0.7)
					(thickness 0.15)
				)
				(justify left bottom)
			)
		)
		(pad "1" smd roundrect
			(at -0.48 0)
			(size 0.59 0.64)
			(layers "F.Cu" "F.Paste" "F.Mask")
			(roundrect_rratio 0.25)
			(net 23 "+3V3")
			(pintype "passive")
		)
		(pad "2" smd roundrect
			(at 0.48 0)
			(size 0.59 0.64)
			(layers "F.Cu" "F.Paste" "F.Mask")
			(roundrect_rratio 0.25)
			(net 97 "Net-(U2-RXDET)")
			(pintype "passive")
		)
	)
	(footprint "antmicro-footprints:TP_SMD_0.75mm"
		(layer "F.Cu")
		(at 130.45 118.29 180)
		(property "Reference" "TP17"
			(at -1.34 -0.45 0)
			(layer "F.SilkS")
			(effects
				(font
					(size 0.7 0.7)
					(thickness 0.15)
				)
				(justify right top)
			)
		)
		(property "Value" "TP_0.75mm_SMD"
			(at 0 1.2 0)
			(layer "F.Fab")
			(effects
				(font
					(size 0.7 0.7)
					(thickness 0.15)
				)
				(justify right top)
			)
		)
		(property "Footprint" "antmicro-footprints:TP_SMD_0.75mm"
			(at 0 0 0)
			(layer "F.Fab")
			(hide yes)
			(effects
				(font
					(size 1.27 1.27)
					(thickness 0.15)
				)
			)
		)
		(property "Description" "SMT test point"
			(at 0 0 0)
			(layer "F.Fab")
			(hide yes)
			(effects
				(font
					(size 1.27 1.27)
					(thickness 0.15)
				)
			)
		)
		(property "MPN" ""
			(at 0 0 180)
			(unlocked yes)
			(layer "F.Fab")
			(hide yes)
			(effects
				(font
					(size 1 1)
					(thickness 0.15)
				)
			)
		)
		(property "Manufacturer" ""
			(at 0 0 180)
			(unlocked yes)
			(layer "F.Fab")
			(hide yes)
			(effects
				(font
					(size 1 1)
					(thickness 0.15)
				)
			)
		)
		(property "Author" "Antmicro"
			(at 0 0 180)
			(unlocked yes)
			(layer "F.Fab")
			(hide yes)
			(effects
				(font
					(size 1 1)
					(thickness 0.15)
				)
			)
		)
		(property "License" "Apache-2.0"
			(at 0 0 180)
			(unlocked yes)
			(layer "F.Fab")
			(hide yes)
			(effects
				(font
					(size 1 1)
					(thickness 0.15)
				)
			)
		)
		(property "Public" "False"
			(at 0 0 180)
			(unlocked yes)
			(layer "F.Fab")
			(hide yes)
			(effects
				(font
					(size 1 1)
					(thickness 0.15)
				)
			)
		)
		(sheetname "Root")
		(sheetfile "jetson-orin-baseboard-oculink-expansion.kicad_sch")
		(attr exclude_from_pos_files exclude_from_bom)
		(fp_circle
			(center 0 0)
			(end 0.475 0)
			(stroke
				(width 0.05)
				(type default)
			)
			(fill none)
			(layer "F.CrtYd")
		)
		(fp_text user "${REFERENCE}"
			(at -0.4 2.7 0)
			(layer "F.Fab")
			(hide yes)
			(effects
				(font
					(size 0.7 0.7)
					(thickness 0.15)
				)
				(justify right top)
			)
		)
		(fp_text user "License: Apache-2.0"
			(at -0.4 5.101 0)
			(layer "F.Fab")
			(hide yes)
			(effects
				(font
					(size 0.7 0.7)
					(thickness 0.15)
				)
				(justify right top)
			)
		)
		(fp_text user "Author: Antmicro"
			(at -0.4 3.901 0)
			(layer "F.Fab")
			(hide yes)
			(effects
				(font
					(size 0.7 0.7)
					(thickness 0.15)
				)
				(justify right top)
			)
		)
		(pad "1" smd circle
			(at 0 0 180)
			(size 0.75 0.75)
			(layers "F.Cu" "F.Mask")
			(net 95 "Net-(U2-SDA)")
			(pinfunction "1")
			(pintype "passive")
		)
	)
	(footprint "antmicro-footprints:R_0402_1005Metric"
		(layer "F.Cu")
		(at 143.046 121.191 -90)
		(descr "Resistor SMD 0402")
		(tags "resistor SMD 0402")
		(property "Reference" "R47"
			(at -1.091 1.346 90)
			(layer "F.SilkS")
			(effects
				(font
					(size 0.7 0.7)
					(thickness 0.15)
				)
				(justify right top)
			)
		)
		(property "Value" "R_10k_0402"
			(at -1.011843 1.772047 90)
			(layer "F.Fab")
			(effects
				(font
					(size 0.7 0.7)
					(thickness 0.15)
				)
				(justify right top)
			)
		)
		(property "Footprint" "antmicro-footprints:R_0402_1005Metric"
			(at 0 0 90)
			(layer "F.Fab")
			(hide yes)
			(effects
				(font
					(size 1.27 1.27)
					(thickness 0.15)
				)
			)
		)
		(property "Datasheet" "https://www.bourns.com/docs/product-datasheets/cr.pdf"
			(at 0 0 90)
			(layer "F.Fab")
			(hide yes)
			(effects
				(font
					(size 1.27 1.27)
					(thickness 0.15)
				)
			)
		)
		(property "Description" "SMD Chip Resistor, 10 kohm, ± 1%, 62.5 mW, 0402 [1005 Metric], Thick Film, General Purpose"
			(at 0 0 90)
			(layer "F.Fab")
			(hide yes)
			(effects
				(font
					(size 1.27 1.27)
					(thickness 0.15)
				)
			)
		)
		(property "MPN" "CR0402-FX-1002GLF"
			(at 0 0 -90)
			(unlocked yes)
			(layer "F.Fab")
			(hide yes)
			(effects
				(font
					(size 1 1)
					(thickness 0.15)
				)
			)
		)
		(property "Manufacturer" "Bourns"
			(at 0 0 -90)
			(unlocked yes)
			(layer "F.Fab")
			(hide yes)
			(effects
				(font
					(size 1 1)
					(thickness 0.15)
				)
			)
		)
		(property "License" "Apache-2.0"
			(at 0 0 -90)
			(unlocked yes)
			(layer "F.Fab")
			(hide yes)
			(effects
				(font
					(size 1 1)
					(thickness 0.15)
				)
			)
		)
		(property "Author" "Antmicro"
			(at 0 0 -90)
			(unlocked yes)
			(layer "F.Fab")
			(hide yes)
			(effects
				(font
					(size 1 1)
					(thickness 0.15)
				)
			)
		)
		(property "Val" "10k"
			(at 0 0 -90)
			(unlocked yes)
			(layer "F.Fab")
			(hide yes)
			(effects
				(font
					(size 1 1)
					(thickness 0.15)
				)
			)
		)
		(property "Tolerance" "1%"
			(at 0 0 -90)
			(unlocked yes)
			(layer "F.Fab")
			(hide yes)
			(effects
				(font
					(size 1 1)
					(thickness 0.15)
				)
			)
		)
		(sheetname "Root")
		(sheetfile "jetson-orin-baseboard-oculink-expansion.kicad_sch")
		(attr smd)
		(fp_rect
			(start -0.925 -0.47)
			(end 0.925 0.47)
			(stroke
				(width 0.05)
				(type default)
			)
			(fill none)
			(layer "F.CrtYd")
		)
		(fp_rect
			(start -0.5 -0.25)
			(end 0.5 0.25)
			(stroke
				(width 0.15)
				(type solid)
			)
			(fill none)
			(layer "F.Fab")
		)
		(fp_text user "License: Apache-2.0"
			(at -0.95 5.169 90)
			(layer "F.Fab")
			(hide yes)
			(effects
				(font
					(size 0.7 0.7)
					(thickness 0.15)
				)
				(justify right top)
			)
		)
		(fp_text user "${REFERENCE}"
			(at -0.95 3.168 90)
			(layer "F.Fab")
			(hide yes)
			(effects
				(font
					(size 0.7 0.7)
					(thickness 0.15)
				)
				(justify right top)
			)
		)
		(fp_text user "Author: Antmicro"
			(at -0.95 4.169 90)
			(layer "F.Fab")
			(hide yes)
			(effects
				(font
					(size 0.7 0.7)
					(thickness 0.15)
				)
				(justify right top)
			)
		)
		(pad "1" smd roundrect
			(at -0.48 0 270)
			(size 0.59 0.64)
			(layers "F.Cu" "F.Paste" "F.Mask")
			(roundrect_rratio 0.25)
			(net 52 "+5V")
			(pintype "passive")
		)
		(pad "2" smd roundrect
			(at 0.48 0 270)
			(size 0.59 0.64)
			(layers "F.Cu" "F.Paste" "F.Mask")
			(roundrect_rratio 0.25)
			(net 138 "Net-(U5-FLG)")
			(pintype "passive")
		)
	)
	(footprint "antmicro-footprints:R_0402_1005Metric"
		(layer "F.Cu")
		(at 131.46 116.23 180)
		(descr "Resistor SMD 0402")
		(tags "resistor SMD 0402")
		(property "Reference" "R37"
			(at -2.26 1.29 180)
			(layer "F.SilkS")
			(effects
				(font
					(size 0.7 0.7)
					(thickness 0.15)
				)
				(justify right top)
			)
		)
		(property "Value" "R_0R_0402"
			(at -1.011843 1.772047 0)
			(layer "F.Fab")
			(effects
				(font
					(size 0.7 0.7)
					(thickness 0.15)
				)
				(justify right top)
			)
		)
		(property "Footprint" "antmicro-footprints:R_0402_1005Metric"
			(at 0 0 0)
			(layer "F.Fab")
			(hide yes)
			(effects
				(font
					(size 1.27 1.27)
					(thickness 0.15)
				)
			)
		)
		(property "Datasheet" "https://industrial.panasonic.com/cdbs/www-data/pdf/RDA0000/AOA0000C301.pdf"
			(at 0 0 0)
			(layer "F.Fab")
			(hide yes)
			(effects
				(font
					(size 1.27 1.27)
					(thickness 0.15)
				)
			)
		)
		(property "Description" "SMD Chip Resistor, Jumper, 0 ohm, 100 mW, 0402 [1005 Metric], Thick Film, General Purpose"
			(at 0 0 0)
			(layer "F.Fab")
			(hide yes)
			(effects
				(font
					(size 1.27 1.27)
					(thickness 0.15)
				)
			)
		)
		(property "MPN" "ERJ2GE0R00X"
			(at 0 0 180)
			(unlocked yes)
			(layer "F.Fab")
			(hide yes)
			(effects
				(font
					(size 1 1)
					(thickness 0.15)
				)
			)
		)
		(property "Manufacturer" "Panasonic"
			(at 0 0 180)
			(unlocked yes)
			(layer "F.Fab")
			(hide yes)
			(effects
				(font
					(size 1 1)
					(thickness 0.15)
				)
			)
		)
		(property "License" "Apache-2.0"
			(at 0 0 180)
			(unlocked yes)
			(layer "F.Fab")
			(hide yes)
			(effects
				(font
					(size 1 1)
					(thickness 0.15)
				)
			)
		)
		(property "Author" "Antmicro"
			(at 0 0 180)
			(unlocked yes)
			(layer "F.Fab")
			(hide yes)
			(effects
				(font
					(size 1 1)
					(thickness 0.15)
				)
			)
		)
		(property "Val" "0R"
			(at 0 0 180)
			(unlocked yes)
			(layer "F.Fab")
			(hide yes)
			(effects
				(font
					(size 1 1)
					(thickness 0.15)
				)
			)
		)
		(property "Tolerance" ""
			(at 0 0 180)
			(unlocked yes)
			(layer "F.Fab")
			(hide yes)
			(effects
				(font
					(size 1 1)
					(thickness 0.15)
				)
			)
		)
		(property "Current" "1A"
			(at 0 0 180)
			(unlocked yes)
			(layer "F.Fab")
			(hide yes)
			(effects
				(font
					(size 1 1)
					(thickness 0.15)
				)
			)
		)
		(property "Public" "False"
			(at 0 0 180)
			(unlocked yes)
			(layer "F.Fab")
			(hide yes)
			(effects
				(font
					(size 1 1)
					(thickness 0.15)
				)
			)
		)
		(sheetname "Root")
		(sheetfile "jetson-orin-baseboard-oculink-expansion.kicad_sch")
		(attr smd dnp)
		(fp_rect
			(start -0.925 -0.47)
			(end 0.925 0.47)
			(stroke
				(width 0.05)
				(type default)
			)
			(fill none)
			(layer "F.CrtYd")
		)
		(fp_rect
			(start -0.5 -0.25)
			(end 0.5 0.25)
			(stroke
				(width 0.15)
				(type solid)
			)
			(fill none)
			(layer "F.Fab")
		)
		(fp_text user "Author: Antmicro"
			(at -0.95 4.169 0)
			(layer "F.Fab")
			(hide yes)
			(effects
				(font
					(size 0.7 0.7)
					(thickness 0.15)
				)
				(justify right top)
			)
		)
		(fp_text user "${REFERENCE}"
			(at -0.95 3.168 0)
			(layer "F.Fab")
			(hide yes)
			(effects
				(font
					(size 0.7 0.7)
					(thickness 0.15)
				)
				(justify right top)
			)
		)
		(fp_text user "License: Apache-2.0"
			(at -0.95 5.169 0)
			(layer "F.Fab")
			(hide yes)
			(effects
				(font
					(size 0.7 0.7)
					(thickness 0.15)
				)
				(justify right top)
			)
		)
		(pad "1" smd roundrect
			(at -0.48 0 180)
			(size 0.59 0.64)
			(layers "F.Cu" "F.Paste" "F.Mask")
			(roundrect_rratio 0.25)
			(net 64 "/I2C_SCL")
			(pintype "passive")
		)
		(pad "2" smd roundrect
			(at 0.48 0 180)
			(size 0.59 0.64)
			(layers "F.Cu" "F.Paste" "F.Mask")
			(roundrect_rratio 0.25)
			(net 106 "Net-(U2-SCL)")
			(pintype "passive")
		)
	)
	(footprint "antmicro-footprints:C_0402_1005Metric"
		(layer "F.Cu")
		(at 129.2 106.877 180)
		(descr "Capacitor SMD 0402")
		(tags "capacitor SMD 0402")
		(property "Reference" "C37"
			(at 0.92 0.37 0)
			(layer "F.SilkS")
			(effects
				(font
					(size 0.7 0.7)
					(thickness 0.15)
				)
				(justify right top)
			)
		)
		(property "Value" "C_220n_0402"
			(at -1.022927 2.155213 0)
			(layer "F.Fab")
			(effects
				(font
					(size 0.7 0.7)
					(thickness 0.15)
				)
				(justify right top)
			)
		)
		(property "Footprint" "antmicro-footprints:C_0402_1005Metric"
			(at 0 0 0)
			(layer "F.Fab")
			(hide yes)
			(effects
				(font
					(size 1.27 1.27)
					(thickness 0.15)
				)
			)
		)
		(property "Datasheet" "https://www.yageo.com/en/Chart/Download/pdf/CC0402KRX5R6BB224"
			(at 0 0 0)
			(layer "F.Fab")
			(hide yes)
			(effects
				(font
					(size 1.27 1.27)
					(thickness 0.15)
				)
			)
		)
		(property "Description" "SMD Multilayer Ceramic Capacitor, 0.22 µF, 10 V, 0402 [1005 Metric], ± 10%, X5R, CC Series"
			(at 0 0 0)
			(layer "F.Fab")
			(hide yes)
			(effects
				(font
					(size 1.27 1.27)
					(thickness 0.15)
				)
			)
		)
		(property "MPN" "CC0402KRX5R6BB224"
			(at 0 0 180)
			(unlocked yes)
			(layer "F.Fab")
			(hide yes)
			(effects
				(font
					(size 1 1)
					(thickness 0.15)
				)
			)
		)
		(property "Manufacturer" "YAGEO"
			(at 0 0 180)
			(unlocked yes)
			(layer "F.Fab")
			(hide yes)
			(effects
				(font
					(size 1 1)
					(thickness 0.15)
				)
			)
		)
		(property "License" "Apache-2.0"
			(at 0 0 180)
			(unlocked yes)
			(layer "F.Fab")
			(hide yes)
			(effects
				(font
					(size 1 1)
					(thickness 0.15)
				)
			)
		)
		(property "Author" "Antmicro"
			(at 0 0 180)
			(unlocked yes)
			(layer "F.Fab")
			(hide yes)
			(effects
				(font
					(size 1 1)
					(thickness 0.15)
				)
			)
		)
		(property "Val" "220n"
			(at 0 0 180)
			(unlocked yes)
			(layer "F.Fab")
			(hide yes)
			(effects
				(font
					(size 1 1)
					(thickness 0.15)
				)
			)
		)
		(property "Voltage" ""
			(at 0 0 180)
			(unlocked yes)
			(layer "F.Fab")
			(hide yes)
			(effects
				(font
					(size 1 1)
					(thickness 0.15)
				)
			)
		)
		(property "Dielectric" ""
			(at 0 0 180)
			(unlocked yes)
			(layer "F.Fab")
			(hide yes)
			(effects
				(font
					(size 1 1)
					(thickness 0.15)
				)
			)
		)
		(property "Public" "False"
			(at 0 0 180)
			(unlocked yes)
			(layer "F.Fab")
			(hide yes)
			(effects
				(font
					(size 1 1)
					(thickness 0.15)
				)
			)
		)
		(sheetname "Root")
		(sheetfile "jetson-orin-baseboard-oculink-expansion.kicad_sch")
		(attr smd)
		(fp_rect
			(start -0.925 -0.47)
			(end 0.925 0.47)
			(stroke
				(width 0.05)
				(type default)
			)
			(fill none)
			(layer "F.CrtYd")
		)
		(fp_line
			(start 0.504 0.248)
			(end -0.494 0.248)
			(stroke
				(width 0.15)
				(type solid)
			)
			(layer "F.Fab")
		)
		(fp_line
			(start 0.504 -0.25)
			(end 0.504 0.248)
			(stroke
				(width 0.15)
				(type solid)
			)
			(layer "F.Fab")
		)
		(fp_line
			(start -0.494 0.248)
			(end -0.494 -0.25)
			(stroke
				(width 0.15)
				(type solid)
			)
			(layer "F.Fab")
		)
		(fp_line
			(start -0.494 -0.25)
			(end 0.504 -0.25)
			(stroke
				(width 0.15)
				(type solid)
			)
			(layer "F.Fab")
		)
		(fp_text user "${REFERENCE}"
			(at -0.939 4.599 0)
			(layer "F.Fab")
			(hide yes)
			(effects
				(font
					(size 0.7 0.7)
					(thickness 0.15)
				)
				(justify right top)
			)
		)
		(fp_text user "Author: Antmicro"
			(at -0.939 3.399 0)
			(layer "F.Fab")
			(hide yes)
			(effects
				(font
					(size 0.7 0.7)
					(thickness 0.15)
				)
				(justify right top)
			)
		)
		(fp_text user "License: Apache-2.0"
			(at -0.939 5.799 0)
			(layer "F.Fab")
			(hide yes)
			(effects
				(font
					(size 0.7 0.7)
					(thickness 0.15)
				)
				(justify right top)
			)
		)
		(pad "1" smd roundrect
			(at -0.48 0 180)
			(size 0.59 0.64)
			(layers "F.Cu" "F.Paste" "F.Mask")
			(roundrect_rratio 0.25)
			(net 79 "/PCIE_{I}_RX1+")
			(pintype "passive")
		)
		(pad "2" smd roundrect
			(at 0.48 0 180)
			(size 0.59 0.64)
			(layers "F.Cu" "F.Paste" "F.Mask")
			(roundrect_rratio 0.25)
			(net 80 "/PCIE_{I}_C.RX1+")
			(pintype "passive")
		)
	)
	(footprint "antmicro-footprints:R_0402_1005Metric"
		(layer "F.Cu")
		(at 144 127.151 90)
		(descr "Resistor SMD 0402")
		(tags "resistor SMD 0402")
		(property "Reference" "R48"
			(at -1.1 1.4 90)
			(layer "F.SilkS")
			(effects
				(font
					(size 0.7 0.7)
					(thickness 0.15)
				)
				(justify left bottom)
			)
		)
		(property "Value" "R_11k3_0402"
			(at -1.011843 1.772047 90)
			(layer "F.Fab")
			(effects
				(font
					(size 0.7 0.7)
					(thickness 0.15)
				)
				(justify left bottom)
			)
		)
		(property "Footprint" "antmicro-footprints:R_0402_1005Metric"
			(at 0 0 90)
			(layer "F.Fab")
			(hide yes)
			(effects
				(font
					(size 1.27 1.27)
					(thickness 0.15)
				)
			)
		)
		(property "Datasheet" "https://www.bourns.com/docs/product-datasheets/cr.pdf"
			(at 0 0 90)
			(layer "F.Fab")
			(hide yes)
			(effects
				(font
					(size 1.27 1.27)
					(thickness 0.15)
				)
			)
		)
		(property "Description" "SMD Chip Resistor, 11.3 kohm, ± 1%, 62.5 mW, 0402 [1005 Metric], Thick Film, General Purpose"
			(at 0 0 90)
			(layer "F.Fab")
			(hide yes)
			(effects
				(font
					(size 1.27 1.27)
					(thickness 0.15)
				)
			)
		)
		(property "MPN" "CR0402-FX-1132GLF"
			(at 0 0 90)
			(unlocked yes)
			(layer "F.Fab")
			(hide yes)
			(effects
				(font
					(size 1 1)
					(thickness 0.15)
				)
			)
		)
		(property "Manufacturer" "Bourns"
			(at 0 0 90)
			(unlocked yes)
			(layer "F.Fab")
			(hide yes)
			(effects
				(font
					(size 1 1)
					(thickness 0.15)
				)
			)
		)
		(property "License" "Apache-2.0"
			(at 0 0 90)
			(unlocked yes)
			(layer "F.Fab")
			(hide yes)
			(effects
				(font
					(size 1 1)
					(thickness 0.15)
				)
			)
		)
		(property "Author" "Antmicro"
			(at 0 0 90)
			(unlocked yes)
			(layer "F.Fab")
			(hide yes)
			(effects
				(font
					(size 1 1)
					(thickness 0.15)
				)
			)
		)
		(property "Val" "11k3"
			(at 0 0 90)
			(unlocked yes)
			(layer "F.Fab")
			(hide yes)
			(effects
				(font
					(size 1 1)
					(thickness 0.15)
				)
			)
		)
		(property "Tolerance" "1%"
			(at 0 0 90)
			(unlocked yes)
			(layer "F.Fab")
			(hide yes)
			(effects
				(font
					(size 1 1)
					(thickness 0.15)
				)
			)
		)
		(sheetname "Root")
		(sheetfile "jetson-orin-baseboard-oculink-expansion.kicad_sch")
		(attr smd)
		(fp_rect
			(start -0.925 -0.47)
			(end 0.925 0.47)
			(stroke
				(width 0.05)
				(type default)
			)
			(fill none)
			(layer "F.CrtYd")
		)
		(fp_rect
			(start -0.5 -0.25)
			(end 0.5 0.25)
			(stroke
				(width 0.15)
				(type solid)
			)
			(fill none)
			(layer "F.Fab")
		)
		(fp_text user "License: Apache-2.0"
			(at -0.95 5.169 90)
			(layer "F.Fab")
			(hide yes)
			(effects
				(font
					(size 0.7 0.7)
					(thickness 0.15)
				)
				(justify left bottom)
			)
		)
		(fp_text user "${REFERENCE}"
			(at -0.95 3.168 90)
			(layer "F.Fab")
			(hide yes)
			(effects
				(font
					(size 0.7 0.7)
					(thickness 0.15)
				)
				(justify left bottom)
			)
		)
		(fp_text user "Author: Antmicro"
			(at -0.95 4.169 90)
			(layer "F.Fab")
			(hide yes)
			(effects
				(font
					(size 0.7 0.7)
					(thickness 0.15)
				)
				(justify left bottom)
			)
		)
		(pad "1" smd roundrect
			(at -0.48 0 90)
			(size 0.59 0.64)
			(layers "F.Cu" "F.Paste" "F.Mask")
			(roundrect_rratio 0.25)
			(net 51 "GND")
			(pintype "passive")
		)
		(pad "2" smd roundrect
			(at 0.48 0 90)
			(size 0.59 0.64)
			(layers "F.Cu" "F.Paste" "F.Mask")
			(roundrect_rratio 0.25)
			(net 139 "Net-(U5-ISET)")
			(pintype "passive")
		)
	)
	(footprint "antmicro-footprints:C_0402_1005Metric"
		(layer "F.Cu")
		(at 146.708 142.516 90)
		(descr "Capacitor SMD 0402")
		(tags "capacitor SMD 0402")
		(property "Reference" "C5"
			(at 0.916 0.492 90)
			(layer "F.SilkS")
			(effects
				(font
					(size 0.7 0.7)
					(thickness 0.15)
				)
				(justify left bottom)
			)
		)
		(property "Value" "C_100n_0402"
			(at -1.022927 2.155213 90)
			(layer "F.Fab")
			(effects
				(font
					(size 0.7 0.7)
					(thickness 0.15)
				)
				(justify left bottom)
			)
		)
		(property "Footprint" "antmicro-footprints:C_0402_1005Metric"
			(at 0 0 90)
			(layer "F.Fab")
			(hide yes)
			(effects
				(font
					(size 1.27 1.27)
					(thickness 0.15)
				)
			)
		)
		(property "Datasheet" "https://www.murata.com/products/productdetail?partno=GRM155R61H104KE14%23"
			(at 0 0 90)
			(layer "F.Fab")
			(hide yes)
			(effects
				(font
					(size 1.27 1.27)
					(thickness 0.15)
				)
			)
		)
		(property "Description" "SMD Multilayer Ceramic Capacitor, 0.1 µF, 50 V, 0402 [1005 Metric], ± 10%, X5R, GRM Series"
			(at 0 0 90)
			(layer "F.Fab")
			(hide yes)
			(effects
				(font
					(size 1.27 1.27)
					(thickness 0.15)
				)
			)
		)
		(property "MPN" "GRM155R61H104KE14D"
			(at 0 0 90)
			(unlocked yes)
			(layer "F.Fab")
			(hide yes)
			(effects
				(font
					(size 1 1)
					(thickness 0.15)
				)
			)
		)
		(property "Manufacturer" "Murata"
			(at 0 0 90)
			(unlocked yes)
			(layer "F.Fab")
			(hide yes)
			(effects
				(font
					(size 1 1)
					(thickness 0.15)
				)
			)
		)
		(property "License" "Apache-2.0"
			(at 0 0 90)
			(unlocked yes)
			(layer "F.Fab")
			(hide yes)
			(effects
				(font
					(size 1 1)
					(thickness 0.15)
				)
			)
		)
		(property "Author" "Antmicro"
			(at 0 0 90)
			(unlocked yes)
			(layer "F.Fab")
			(hide yes)
			(effects
				(font
					(size 1 1)
					(thickness 0.15)
				)
			)
		)
		(property "Val" "100n"
			(at 0 0 90)
			(unlocked yes)
			(layer "F.Fab")
			(hide yes)
			(effects
				(font
					(size 1 1)
					(thickness 0.15)
				)
			)
		)
		(property "Voltage" "50V"
			(at 0 0 90)
			(unlocked yes)
			(layer "F.Fab")
			(hide yes)
			(effects
				(font
					(size 1 1)
					(thickness 0.15)
				)
			)
		)
		(property "Dielectric" "X5R"
			(at 0 0 90)
			(unlocked yes)
			(layer "F.Fab")
			(hide yes)
			(effects
				(font
					(size 1 1)
					(thickness 0.15)
				)
			)
		)
		(sheetname "Root")
		(sheetfile "jetson-orin-baseboard-oculink-expansion.kicad_sch")
		(attr smd)
		(fp_rect
			(start -0.925 -0.47)
			(end 0.925 0.47)
			(stroke
				(width 0.05)
				(type default)
			)
			(fill none)
			(layer "F.CrtYd")
		)
		(fp_line
			(start 0.504 -0.25)
			(end 0.504 0.248)
			(stroke
				(width 0.15)
				(type solid)
			)
			(layer "F.Fab")
		)
		(fp_line
			(start -0.494 -0.25)
			(end 0.504 -0.25)
			(stroke
				(width 0.15)
				(type solid)
			)
			(layer "F.Fab")
		)
		(fp_line
			(start 0.504 0.248)
			(end -0.494 0.248)
			(stroke
				(width 0.15)
				(type solid)
			)
			(layer "F.Fab")
		)
		(fp_line
			(start -0.494 0.248)
			(end -0.494 -0.25)
			(stroke
				(width 0.15)
				(type solid)
			)
			(layer "F.Fab")
		)
		(fp_text user "${REFERENCE}"
			(at -0.939 4.599 90)
			(layer "F.Fab")
			(hide yes)
			(effects
				(font
					(size 0.7 0.7)
					(thickness 0.15)
				)
				(justify left bottom)
			)
		)
		(fp_text user "Author: Antmicro"
			(at -0.939 3.399 90)
			(layer "F.Fab")
			(hide yes)
			(effects
				(font
					(size 0.7 0.7)
					(thickness 0.15)
				)
				(justify left bottom)
			)
		)
		(fp_text user "License: Apache-2.0"
			(at -0.939 5.799 90)
			(layer "F.Fab")
			(hide yes)
			(effects
				(font
					(size 0.7 0.7)
					(thickness 0.15)
				)
				(justify left bottom)
			)
		)
		(pad "1" smd roundrect
			(at -0.48 0 90)
			(size 0.59 0.64)
			(layers "F.Cu" "F.Paste" "F.Mask")
			(roundrect_rratio 0.25)
			(net 51 "GND")
			(pintype "passive")
		)
		(pad "2" smd roundrect
			(at 0.48 0 90)
			(size 0.59 0.64)
			(layers "F.Cu" "F.Paste" "F.Mask")
			(roundrect_rratio 0.25)
			(net 20 "+1V8")
			(pintype "passive")
		)
	)
	(footprint "antmicro-footprints:TP_SMD_0.75mm"
		(layer "F.Cu")
		(at 114.58 125.2 180)
		(property "Reference" "TP3"
			(at -1.51 1.29 0)
			(layer "F.SilkS")
			(effects
				(font
					(size 0.7 0.7)
					(thickness 0.15)
				)
				(justify right top)
			)
		)
		(property "Value" "TP_0.75mm_SMD"
			(at 0 1.2 0)
			(layer "F.Fab")
			(effects
				(font
					(size 0.7 0.7)
					(thickness 0.15)
				)
				(justify right top)
			)
		)
		(property "Footprint" "antmicro-footprints:TP_SMD_0.75mm"
			(at 0 0 0)
			(layer "F.Fab")
			(hide yes)
			(effects
				(font
					(size 1.27 1.27)
					(thickness 0.15)
				)
			)
		)
		(property "Description" "SMT test point"
			(at 0 0 0)
			(layer "F.Fab")
			(hide yes)
			(effects
				(font
					(size 1.27 1.27)
					(thickness 0.15)
				)
			)
		)
		(property "MPN" ""
			(at 0 0 180)
			(unlocked yes)
			(layer "F.Fab")
			(hide yes)
			(effects
				(font
					(size 1 1)
					(thickness 0.15)
				)
			)
		)
		(property "Manufacturer" ""
			(at 0 0 180)
			(unlocked yes)
			(layer "F.Fab")
			(hide yes)
			(effects
				(font
					(size 1 1)
					(thickness 0.15)
				)
			)
		)
		(property "Author" "Antmicro"
			(at 0 0 180)
			(unlocked yes)
			(layer "F.Fab")
			(hide yes)
			(effects
				(font
					(size 1 1)
					(thickness 0.15)
				)
			)
		)
		(property "License" "Apache-2.0"
			(at 0 0 180)
			(unlocked yes)
			(layer "F.Fab")
			(hide yes)
			(effects
				(font
					(size 1 1)
					(thickness 0.15)
				)
			)
		)
		(property "Public" "False"
			(at 0 0 180)
			(unlocked yes)
			(layer "F.Fab")
			(hide yes)
			(effects
				(font
					(size 1 1)
					(thickness 0.15)
				)
			)
		)
		(sheetname "Root")
		(sheetfile "jetson-orin-baseboard-oculink-expansion.kicad_sch")
		(attr exclude_from_pos_files exclude_from_bom)
		(fp_circle
			(center 0 0)
			(end 0.475 0)
			(stroke
				(width 0.05)
				(type default)
			)
			(fill none)
			(layer "F.CrtYd")
		)
		(fp_text user "Author: Antmicro"
			(at -0.4 3.901 0)
			(layer "F.Fab")
			(hide yes)
			(effects
				(font
					(size 0.7 0.7)
					(thickness 0.15)
				)
				(justify right top)
			)
		)
		(fp_text user "${REFERENCE}"
			(at -0.4 2.7 0)
			(layer "F.Fab")
			(hide yes)
			(effects
				(font
					(size 0.7 0.7)
					(thickness 0.15)
				)
				(justify right top)
			)
		)
		(fp_text user "License: Apache-2.0"
			(at -0.4 5.101 0)
			(layer "F.Fab")
			(hide yes)
			(effects
				(font
					(size 0.7 0.7)
					(thickness 0.15)
				)
				(justify right top)
			)
		)
		(pad "1" smd circle
			(at 0 0 180)
			(size 0.75 0.75)
			(layers "F.Cu" "F.Mask")
			(net 107 "Net-(U3-SDA)")
			(pinfunction "1")
			(pintype "passive")
		)
	)
	(footprint "antmicro-footprints:C_0402_1005Metric"
		(layer "F.Cu")
		(at 145.554 108.6 -90)
		(descr "Capacitor SMD 0402")
		(tags "capacitor SMD 0402")
		(property "Reference" "C16"
			(at -1.1 -0.546 90)
			(layer "F.SilkS")
			(effects
				(font
					(size 0.7 0.7)
					(thickness 0.15)
				)
				(justify right top)
			)
		)
		(property "Value" "C_10u_0402"
			(at -1.022927 2.155213 90)
			(layer "F.Fab")
			(effects
				(font
					(size 0.7 0.7)
					(thickness 0.15)
				)
				(justify right top)
			)
		)
		(property "Footprint" "antmicro-footprints:C_0402_1005Metric"
			(at 0 0 90)
			(layer "F.Fab")
			(hide yes)
			(effects
				(font
					(size 1.27 1.27)
					(thickness 0.15)
				)
			)
		)
		(property "Datasheet" "https://www.yageo.com/en/Chart/Download/pdf/CC0402MRX5R5BB106"
			(at 0 0 90)
			(layer "F.Fab")
			(hide yes)
			(effects
				(font
					(size 1.27 1.27)
					(thickness 0.15)
				)
			)
		)
		(property "Description" "SMD Multilayer Ceramic Capacitor, 10 µF, 6.3 V, 0402 [1005 Metric], ± 20%, X5R, CC Series"
			(at 0 0 90)
			(layer "F.Fab")
			(hide yes)
			(effects
				(font
					(size 1.27 1.27)
					(thickness 0.15)
				)
			)
		)
		(property "MPN" "CC0402MRX5R5BB106"
			(at 0 0 -90)
			(unlocked yes)
			(layer "F.Fab")
			(hide yes)
			(effects
				(font
					(size 1 1)
					(thickness 0.15)
				)
			)
		)
		(property "Manufacturer" "YAGEO"
			(at 0 0 -90)
			(unlocked yes)
			(layer "F.Fab")
			(hide yes)
			(effects
				(font
					(size 1 1)
					(thickness 0.15)
				)
			)
		)
		(property "License" "Apache-2.0"
			(at 0 0 -90)
			(unlocked yes)
			(layer "F.Fab")
			(hide yes)
			(effects
				(font
					(size 1 1)
					(thickness 0.15)
				)
			)
		)
		(property "Author" "Antmicro"
			(at 0 0 -90)
			(unlocked yes)
			(layer "F.Fab")
			(hide yes)
			(effects
				(font
					(size 1 1)
					(thickness 0.15)
				)
			)
		)
		(property "Val" "10u"
			(at 0 0 -90)
			(unlocked yes)
			(layer "F.Fab")
			(hide yes)
			(effects
				(font
					(size 1 1)
					(thickness 0.15)
				)
			)
		)
		(property "Voltage" ""
			(at 0 0 -90)
			(unlocked yes)
			(layer "F.Fab")
			(hide yes)
			(effects
				(font
					(size 1 1)
					(thickness 0.15)
				)
			)
		)
		(property "Dielectric" ""
			(at 0 0 -90)
			(unlocked yes)
			(layer "F.Fab")
			(hide yes)
			(effects
				(font
					(size 1 1)
					(thickness 0.15)
				)
			)
		)
		(sheetname "Root")
		(sheetfile "jetson-orin-baseboard-oculink-expansion.kicad_sch")
		(attr smd)
		(fp_rect
			(start -0.925 -0.47)
			(end 0.925 0.47)
			(stroke
				(width 0.05)
				(type default)
			)
			(fill none)
			(layer "F.CrtYd")
		)
		(fp_line
			(start -0.494 0.248)
			(end -0.494 -0.25)
			(stroke
				(width 0.15)
				(type solid)
			)
			(layer "F.Fab")
		)
		(fp_line
			(start 0.504 0.248)
			(end -0.494 0.248)
			(stroke
				(width 0.15)
				(type solid)
			)
			(layer "F.Fab")
		)
		(fp_line
			(start -0.494 -0.25)
			(end 0.504 -0.25)
			(stroke
				(width 0.15)
				(type solid)
			)
			(layer "F.Fab")
		)
		(fp_line
			(start 0.504 -0.25)
			(end 0.504 0.248)
			(stroke
				(width 0.15)
				(type solid)
			)
			(layer "F.Fab")
		)
		(fp_text user "Author: Antmicro"
			(at -0.939 3.399 90)
			(layer "F.Fab")
			(hide yes)
			(effects
				(font
					(size 0.7 0.7)
					(thickness 0.15)
				)
				(justify right top)
			)
		)
		(fp_text user "${REFERENCE}"
			(at -0.939 4.599 90)
			(layer "F.Fab")
			(hide yes)
			(effects
				(font
					(size 0.7 0.7)
					(thickness 0.15)
				)
				(justify right top)
			)
		)
		(fp_text user "License: Apache-2.0"
			(at -0.939 5.799 90)
			(layer "F.Fab")
			(hide yes)
			(effects
				(font
					(size 0.7 0.7)
					(thickness 0.15)
				)
				(justify right top)
			)
		)
		(pad "1" smd roundrect
			(at -0.48 0 270)
			(size 0.59 0.64)
			(layers "F.Cu" "F.Paste" "F.Mask")
			(roundrect_rratio 0.25)
			(net 51 "GND")
			(pintype "passive")
		)
		(pad "2" smd roundrect
			(at 0.48 0 270)
			(size 0.59 0.64)
			(layers "F.Cu" "F.Paste" "F.Mask")
			(roundrect_rratio 0.25)
			(net 23 "+3V3")
			(pintype "passive")
		)
	)
	(footprint "antmicro-footprints:WQFN-42-1EP_3.5x9mm_P0.5mm"
		(layer "F.Cu")
		(at 121.275 126.854 -90)
		(descr "WQFN, 42 Pin (http://www.ti.com/lit/ds/symlink/ts3l501e.pdf#page=23), generated with kicad-footprint-generator ipc_noLead_generator.py")
		(tags "WQFN NoLead")
		(property "Reference" "U3"
			(at -3.824 4.995 90)
			(layer "F.SilkS")
			(effects
				(font
					(size 0.7 0.7)
					(thickness 0.15)
				)
				(justify right top)
			)
		)
		(property "Value" "PI3EQX16904GL"
			(at 0 5.82 90)
			(layer "F.Fab")
			(effects
				(font
					(size 0.7 0.7)
					(thickness 0.15)
				)
				(justify right top)
			)
		)
		(property "Footprint" "antmicro-footprints:WQFN-42-1EP_3.5x9mm_P0.5mm"
			(at 0 0 90)
			(layer "F.Fab")
			(hide yes)
			(effects
				(font
					(size 1.27 1.27)
					(thickness 0.15)
				)
			)
		)
		(property "Datasheet" "https://www.diodes.com/part/view/PI3EQX16904GL"
			(at 0 0 90)
			(layer "F.Fab")
			(hide yes)
			(effects
				(font
					(size 1.27 1.27)
					(thickness 0.15)
				)
			)
		)
		(property "Description" "16Gbps 4-Channel ReDriver with Linear Equalization"
			(at 0 0 90)
			(layer "F.Fab")
			(hide yes)
			(effects
				(font
					(size 1.27 1.27)
					(thickness 0.15)
				)
			)
		)
		(property "MPN" "PI3EQX16904GLZHEX"
			(at 0 0 -90)
			(unlocked yes)
			(layer "F.Fab")
			(hide yes)
			(effects
				(font
					(size 1 1)
					(thickness 0.15)
				)
			)
		)
		(property "Manufacturer" "Diodes Incorporated"
			(at 0 0 -90)
			(unlocked yes)
			(layer "F.Fab")
			(hide yes)
			(effects
				(font
					(size 1 1)
					(thickness 0.15)
				)
			)
		)
		(property "Author" "Antmicro"
			(at 0 0 -90)
			(unlocked yes)
			(layer "F.Fab")
			(hide yes)
			(effects
				(font
					(size 1 1)
					(thickness 0.15)
				)
			)
		)
		(property "License" "Apache-2.0"
			(at 0 0 -90)
			(unlocked yes)
			(layer "F.Fab")
			(hide yes)
			(effects
				(font
					(size 1 1)
					(thickness 0.15)
				)
			)
		)
		(sheetname "Root")
		(sheetfile "jetson-orin-baseboard-oculink-expansion.kicad_sch")
		(attr smd)
		(fp_line
			(start -1.861 4.61)
			(end -1.861 4.384)
			(stroke
				(width 0.15)
				(type solid)
			)
			(layer "F.SilkS")
		)
		(fp_line
			(start -1.135 4.61)
			(end -1.861 4.61)
			(stroke
				(width 0.15)
				(type solid)
			)
			(layer "F.SilkS")
		)
		(fp_line
			(start 1.134 4.61)
			(end 1.86 4.61)
			(stroke
				(width 0.15)
				(type solid)
			)
			(layer "F.SilkS")
		)
		(fp_line
			(start 1.86 4.61)
			(end 1.86 4.384)
			(stroke
				(width 0.15)
				(type solid)
			)
			(layer "F.SilkS")
		)
		(fp_line
			(start -1.135 -4.611)
			(end -1.861 -4.611)
			(stroke
				(width 0.15)
				(type solid)
			)
			(layer "F.SilkS")
		)
		(fp_line
			(start 1.134 -4.611)
			(end 1.86 -4.611)
			(stroke
				(width 0.15)
				(type solid)
			)
			(layer "F.SilkS")
		)
		(fp_line
			(start 1.86 -4.611)
			(end 1.86 -4.385)
			(stroke
				(width 0.15)
				(type solid)
			)
			(layer "F.SilkS")
		)
		(fp_circle
			(center -2.68 -4)
			(end -2.63 -4)
			(stroke
				(width 0.15)
				(type solid)
			)
			(fill solid)
			(layer "F.SilkS")
		)
		(fp_rect
			(start -2.25 -5)
			(end 2.249 4.998)
			(stroke
				(width 0.05)
				(type solid)
			)
			(fill none)
			(layer "F.CrtYd")
		)
		(fp_line
			(start -1.75 4.498)
			(end -1.75 -3.625)
			(stroke
				(width 0.15)
				(type solid)
			)
			(layer "F.Fab")
		)
		(fp_line
			(start 1.749 4.498)
			(end -1.75 4.498)
			(stroke
				(width 0.15)
				(type solid)
			)
			(layer "F.Fab")
		)
		(fp_line
			(start -1.75 -3.625)
			(end -0.875 -4.5)
			(stroke
				(width 0.15)
				(type solid)
			)
			(layer "F.Fab")
		)
		(fp_line
			(start -0.875 -4.5)
			(end 1.749 -4.5)
			(stroke
				(width 0.15)
				(type solid)
			)
			(layer "F.Fab")
		)
		(fp_line
			(start 1.749 -4.5)
			(end 1.749 4.498)
			(stroke
				(width 0.15)
				(type solid)
			)
			(layer "F.Fab")
		)
		(fp_text user "License: Apache-2.0"
			(at -2.73 9.02 90)
			(layer "F.Fab")
			(hide yes)
			(effects
				(font
					(size 0.7 0.7)
					(thickness 0.15)
				)
				(justify right top)
			)
		)
		(fp_text user "${REFERENCE}"
			(at -2.73 10.22 90)
			(layer "F.Fab")
			(hide yes)
			(effects
				(font
					(size 0.7 0.7)
					(thickness 0.15)
				)
				(justify right top)
			)
		)
		(fp_text user "Author: Antmicro"
			(at -2.73 7.82 90)
			(layer "F.Fab")
			(hide yes)
			(effects
				(font
					(size 0.7 0.7)
					(thickness 0.15)
				)
				(justify right top)
			)
		)
		(pad "" smd roundrect
			(at -0.51 -3.242 270)
			(size 0.83 0.87)
			(layers "F.Paste")
			(roundrect_rratio 0.25)
		)
		(pad "" smd roundrect
			(at -0.51 -2.161 270)
			(size 0.83 0.87)
			(layers "F.Paste")
			(roundrect_rratio 0.25)
		)
		(pad "" smd roundrect
			(at -0.51 -1.081 270)
			(size 0.83 0.87)
			(layers "F.Paste")
			(roundrect_rratio 0.25)
		)
		(pad "" smd roundrect
			(at -0.51 0 270)
			(size 0.83 0.87)
			(layers "F.Paste")
			(roundrect_rratio 0.25)
		)
		(pad "" smd roundrect
			(at -0.51 1.08 270)
			(size 0.83 0.87)
			(layers "F.Paste")
			(roundrect_rratio 0.25)
		)
		(pad "" smd roundrect
			(at -0.51 2.16 270)
			(size 0.83 0.87)
			(layers "F.Paste")
			(roundrect_rratio 0.25)
		)
		(pad "" smd roundrect
			(at -0.51 3.24 270)
			(size 0.83 0.87)
			(layers "F.Paste")
			(roundrect_rratio 0.25)
		)
		(pad "" smd roundrect
			(at 0.508 -3.242 270)
			(size 0.83 0.87)
			(layers "F.Paste")
			(roundrect_rratio 0.25)
		)
		(pad "" smd roundrect
			(at 0.508 -2.161 270)
			(size 0.83 0.87)
			(layers "F.Paste")
			(roundrect_rratio 0.25)
		)
		(pad "" smd roundrect
			(at 0.508 -1.081 270)
			(size 0.83 0.87)
			(layers "F.Paste")
			(roundrect_rratio 0.25)
		)
		(pad "" smd roundrect
			(at 0.508 0 270)
			(size 0.83 0.87)
			(layers "F.Paste")
			(roundrect_rratio 0.25)
		)
		(pad "" smd roundrect
			(at 0.508 1.08 270)
			(size 0.83 0.87)
			(layers "F.Paste")
			(roundrect_rratio 0.25)
		)
		(pad "" smd roundrect
			(at 0.508 2.16 270)
			(size 0.83 0.87)
			(layers "F.Paste")
			(roundrect_rratio 0.25)
		)
		(pad "" smd roundrect
			(at 0.508 3.24 270)
			(size 0.83 0.87)
			(layers "F.Paste")
			(roundrect_rratio 0.25)
		)
		(pad "1" smd roundrect
			(at -1.688 -4 270)
			(size 0.875 0.25)
			(layers "F.Cu" "F.Paste" "F.Mask")
			(roundrect_rratio 0.25)
			(net 99 "/TX_EQ2")
			(pinfunction "EQ2")
			(pintype "passive")
		)
		(pad "2" smd roundrect
			(at -1.688 -3.5 270)
			(size 0.875 0.25)
			(layers "F.Cu" "F.Paste" "F.Mask")
			(roundrect_rratio 0.25)
			(net 102 "/TX_SW")
			(pinfunction "SW1")
			(pintype "input")
		)
		(pad "3" smd roundrect
			(at -1.688 -3 270)
			(size 0.875 0.25)
			(layers "F.Cu" "F.Paste" "F.Mask")
			(roundrect_rratio 0.25)
			(net 23 "+3V3")
			(pinfunction "VCC")
			(pintype "passive")
		)
		(pad "4" smd roundrect
			(at -1.688 -2.5 270)
			(size 0.875 0.25)
			(layers "F.Cu" "F.Paste" "F.Mask")
			(roundrect_rratio 0.25)
			(net 87 "/PCIE_{I}_TX1-")
			(pinfunction "A0RX+")
			(pintype "input")
		)
		(pad "5" smd roundrect
			(at -1.688 -2 270)
			(size 0.875 0.25)
			(layers "F.Cu" "F.Paste" "F.Mask")
			(roundrect_rratio 0.25)
			(net 86 "/PCIE_{I}_TX1+")
			(pinfunction "A0RX-")
			(pintype "input")
		)
		(pad "6" smd roundrect
			(at -1.688 -1.5 270)
			(size 0.875 0.25)
			(layers "F.Cu" "F.Paste" "F.Mask")
			(roundrect_rratio 0.25)
			(net 23 "+3V3")
			(pinfunction "VCC")
			(pintype "passive")
		)
		(pad "7" smd roundrect
			(at -1.688 -1 270)
			(size 0.875 0.25)
			(layers "F.Cu" "F.Paste" "F.Mask")
			(roundrect_rratio 0.25)
			(net 85 "/PCIE_{I}_TX0-")
			(pinfunction "A1RX+")
			(pintype "input")
		)
		(pad "8" smd roundrect
			(at -1.688 -0.5 270)
			(size 0.875 0.25)
			(layers "F.Cu" "F.Paste" "F.Mask")
			(roundrect_rratio 0.25)
			(net 88 "/PCIE_{I}_TX0+")
			(pinfunction "A1RX-")
			(pintype "input")
		)
		(pad "9" smd roundrect
			(at -1.688 0 270)
			(size 0.875 0.25)
			(layers "F.Cu" "F.Paste" "F.Mask")
			(roundrect_rratio 0.25)
			(net 23 "+3V3")
			(pinfunction "VCC")
			(pintype "passive")
		)
		(pad "10" smd roundrect
			(at -1.688 0.5 270)
			(size 0.875 0.25)
			(layers "F.Cu" "F.Paste" "F.Mask")
			(roundrect_rratio 0.25)
			(net 122 "unconnected-(U3-A2RX+-Pad10)")
			(pinfunction "A2RX+")
			(pintype "input+no_connect")
		)
		(pad "11" smd roundrect
			(at -1.688 1 270)
			(size 0.875 0.25)
			(layers "F.Cu" "F.Paste" "F.Mask")
			(roundrect_rratio 0.25)
			(net 124 "unconnected-(U3-A2RX--Pad11)")
			(pinfunction "A2RX-")
			(pintype "input+no_connect")
		)
		(pad "12" smd roundrect
			(at -1.688 1.5 270)
			(size 0.875 0.25)
			(layers "F.Cu" "F.Paste" "F.Mask")
			(roundrect_rratio 0.25)
			(net 23 "+3V3")
			(pinfunction "VCC")
			(pintype "power_in")
		)
		(pad "13" smd roundrect
			(at -1.688 2 270)
			(size 0.875 0.25)
			(layers "F.Cu" "F.Paste" "F.Mask")
			(roundrect_rratio 0.25)
			(net 131 "unconnected-(U3-A3RX+-Pad13)")
			(pinfunction "A3RX+")
			(pintype "input+no_connect")
		)
		(pad "14" smd roundrect
			(at -1.688 2.5 270)
			(size 0.875 0.25)
			(layers "F.Cu" "F.Paste" "F.Mask")
			(roundrect_rratio 0.25)
			(net 123 "unconnected-(U3-A3RX--Pad14)")
			(pinfunction "A3RX-")
			(pintype "input+no_connect")
		)
		(pad "15" smd roundrect
			(at -1.688 3 270)
			(size 0.875 0.25)
			(layers "F.Cu" "F.Paste" "F.Mask")
			(roundrect_rratio 0.25)
			(net 23 "+3V3")
			(pinfunction "VCC")
			(pintype "passive")
		)
		(pad "16" smd roundrect
			(at -1.688 3.5 270)
			(size 0.875 0.25)
			(layers "F.Cu" "F.Paste" "F.Mask")
			(roundrect_rratio 0.25)
			(net 112 "Net-(U3-~{I2C_{RESET}})")
			(pinfunction "~{I2C_{RESET}}")
			(pintype "input")
		)
		(pad "17" smd roundrect
			(at -1.688 4 270)
			(size 0.875 0.25)
			(layers "F.Cu" "F.Paste" "F.Mask")
			(roundrect_rratio 0.25)
			(net 130 "unconnected-(U3-AD1-Pad17)")
			(pinfunction "AD1")
			(pintype "passive+no_connect")
		)
		(pad "18" smd roundrect
			(at -0.75 4.437 270)
			(size 0.25 0.875)
			(layers "F.Cu" "F.Paste" "F.Mask")
			(roundrect_rratio 0.25)
			(net 107 "Net-(U3-SDA)")
			(pinfunction "SDA")
			(pintype "open_collector")
		)
		(pad "19" smd roundrect
			(at -0.25 4.437 270)
			(size 0.25 0.875)
			(layers "F.Cu" "F.Paste" "F.Mask")
			(roundrect_rratio 0.25)
			(net 108 "Net-(U3-SCL)")
			(pinfunction "SCL")
			(pintype "open_collector")
		)
		(pad "20" smd roundrect
			(at 0.25 4.437 270)
			(size 0.25 0.875)
			(layers "F.Cu" "F.Paste" "F.Mask")
			(roundrect_rratio 0.25)
			(net 71 "/~{CPRSNT}")
			(pinfunction "~{PRSNT}")
			(pintype "input")
		)
		(pad "21" smd roundrect
			(at 0.75 4.437 270)
			(size 0.25 0.875)
			(layers "F.Cu" "F.Paste" "F.Mask")
			(roundrect_rratio 0.25)
			(net 105 "Net-(U3-EN_{I2C})")
			(pinfunction "EN_{I2C}")
			(pintype "input")
		)
		(pad "22" smd roundrect
			(at 1.687 4 270)
			(size 0.875 0.25)
			(layers "F.Cu" "F.Paste" "F.Mask")
			(roundrect_rratio 0.25)
			(net 111 "Net-(U3-I2C_{DONE})")
			(pinfunction "I2C_{DONE}")
			(pintype "input")
		)
		(pad "23" smd roundrect
			(at 1.687 3.5 270)
			(size 0.875 0.25)
			(layers "F.Cu" "F.Paste" "F.Mask")
			(roundrect_rratio 0.25)
			(net 104 "Net-(U3-RXDET)")
			(pinfunction "RXDET")
			(pintype "input")
		)
		(pad "24" smd roundrect
			(at 1.687 3 270)
			(size 0.875 0.25)
			(layers "F.Cu" "F.Paste" "F.Mask")
			(roundrect_rratio 0.25)
			(net 23 "+3V3")
			(pinfunction "VCC")
			(pintype "passive")
		)
		(pad "25" smd roundrect
			(at 1.687 2.5 270)
			(size 0.875 0.25)
			(layers "F.Cu" "F.Paste" "F.Mask")
			(roundrect_rratio 0.25)
			(net 121 "unconnected-(U3-A3TX--Pad25)")
			(pinfunction "A3TX-")
			(pintype "output+no_connect")
		)
		(pad "26" smd roundrect
			(at 1.687 2 270)
			(size 0.875 0.25)
			(layers "F.Cu" "F.Paste" "F.Mask")
			(roundrect_rratio 0.25)
			(net 129 "unconnected-(U3-A3TX+-Pad26)")
			(pinfunction "A3TX+")
			(pintype "input+no_connect")
		)
		(pad "27" smd roundrect
			(at 1.687 1.5 270)
			(size 0.875 0.25)
			(layers "F.Cu" "F.Paste" "F.Mask")
			(roundrect_rratio 0.25)
			(net 23 "+3V3")
			(pinfunction "VCC")
			(pintype "passive")
		)
		(pad "28" smd roundrect
			(at 1.687 1 270)
			(size 0.875 0.25)
			(layers "F.Cu" "F.Paste" "F.Mask")
			(roundrect_rratio 0.25)
			(net 119 "unconnected-(U3-A2TX--Pad28)")
			(pinfunction "A2TX-")
			(pintype "output+no_connect")
		)
		(pad "29" smd roundrect
			(at 1.687 0.5 270)
			(size 0.875 0.25)
			(layers "F.Cu" "F.Paste" "F.Mask")
			(roundrect_rratio 0.25)
			(net 120 "unconnected-(U3-A2TX+-Pad29)")
			(pinfunction "A2TX+")
			(pintype "input+no_connect")
		)
		(pad "30" smd roundrect
			(at 1.687 0 270)
			(size 0.875 0.25)
			(layers "F.Cu" "F.Paste" "F.Mask")
			(roundrect_rratio 0.25)
			(net 23 "+3V3")
			(pinfunction "VCC")
			(pintype "passive")
		)
		(pad "31" smd roundrect
			(at 1.687 -0.5 270)
			(size 0.875 0.25)
			(layers "F.Cu" "F.Paste" "F.Mask")
			(roundrect_rratio 0.25)
			(net 63 "/PCIE_{O}_C.TX0+")
			(pinfunction "A1TX-")
			(pintype "output")
		)
		(pad "32" smd roundrect
			(at 1.687 -1 270)
			(size 0.875 0.25)
			(layers "F.Cu" "F.Paste" "F.Mask")
			(roundrect_rratio 0.25)
			(net 31 "/PCIE_{O}_C.TX0-")
			(pinfunction "A1TX+")
			(pintype "input")
		)
		(pad "33" smd roundrect
			(at 1.687 -1.5 270)
			(size 0.875 0.25)
			(layers "F.Cu" "F.Paste" "F.Mask")
			(roundrect_rratio 0.25)
			(net 23 "+3V3")
			(pinfunction "VCC")
			(pintype "passive")
		)
		(pad "34" smd roundrect
			(at 1.687 -2 270)
			(size 0.875 0.25)
			(layers "F.Cu" "F.Paste" "F.Mask")
			(roundrect_rratio 0.25)
			(net 57 "/PCIE_{O}_C.TX1+")
			(pinfunction "A0TX-")
			(pintype "output")
		)
		(pad "35" smd roundrect
			(at 1.687 -2.5 270)
			(size 0.875 0.25)
			(layers "F.Cu" "F.Paste" "F.Mask")
			(roundrect_rratio 0.25)
			(net 60 "/PCIE_{O}_C.TX1-")
			(pinfunction "A0TX+")
			(pintype "input")
		)
		(pad "36" smd roundrect
			(at 1.687 -3 270)
			(size 0.875 0.25)
			(layers "F.Cu" "F.Paste" "F.Mask")
			(roundrect_rratio 0.25)
			(net 23 "+3V3")
			(pinfunction "VCC")
			(pintype "passive")
		)
		(pad "37" smd roundrect
			(at 1.687 -3.5 270)
			(size 0.875 0.25)
			(layers "F.Cu" "F.Paste" "F.Mask")
			(roundrect_rratio 0.25)
			(net 100 "/TX_FG0")
			(pinfunction "FG0")
			(pintype "passive")
		)
		(pad "38" smd roundrect
			(at 1.687 -4 270)
			(size 0.875 0.25)
			(layers "F.Cu" "F.Paste" "F.Mask")
			(roundrect_rratio 0.25)
			(net 101 "/TX_FG1")
			(pinfunction "FG1")
			(pintype "passive")
		)
		(pad "39" smd roundrect
			(at 0.75 -4.438 270)
			(size 0.25 0.875)
			(layers "F.Cu" "F.Paste" "F.Mask")
			(roundrect_rratio 0.25)
			(net 96 "/TX_EQ0")
			(pinfunction "EQ0")
			(pintype "passive")
		)
		(pad "40" smd roundrect
			(at 0.25 -4.438 270)
			(size 0.25 0.875)
			(layers "F.Cu" "F.Paste" "F.Mask")
			(roundrect_rratio 0.25)
			(net 98 "/TX_EQ1")
			(pinfunction "EQ1")
			(pintype "passive")
		)
		(pad "41" smd roundrect
			(at -0.25 -4.438 270)
			(size 0.25 0.875)
			(layers "F.Cu" "F.Paste" "F.Mask")
			(roundrect_rratio 0.25)
			(net 51 "GND")
			(pinfunction "AD2")
			(pintype "passive")
		)
		(pad "42" smd roundrect
			(at -0.75 -4.438 270)
			(size 0.25 0.875)
			(layers "F.Cu" "F.Paste" "F.Mask")
			(roundrect_rratio 0.25)
			(net 51 "GND")
			(pinfunction "AD3")
			(pintype "passive")
		)
		(pad "43" smd rect
			(at 0 0 270)
			(size 2.05 7.55)
			(layers "F.Cu" "F.Mask")
			(net 51 "GND")
			(pinfunction "GND")
			(pintype "power_in")
		)
	)
	(footprint "antmicro-footprints:C_0402_1005Metric"
		(layer "F.Cu")
		(at 118.59 137.64 -90)
		(descr "Capacitor SMD 0402")
		(tags "capacitor SMD 0402")
		(property "Reference" "C35"
			(at 0.86 0.34 90)
			(layer "F.SilkS")
			(effects
				(font
					(size 0.7 0.7)
					(thickness 0.15)
				)
				(justify right top)
			)
		)
		(property "Value" "C_220n_0402"
			(at -1.022927 2.155213 90)
			(layer "F.Fab")
			(effects
				(font
					(size 0.7 0.7)
					(thickness 0.15)
				)
				(justify right top)
			)
		)
		(property "Footprint" "antmicro-footprints:C_0402_1005Metric"
			(at 0 0 90)
			(layer "F.Fab")
			(hide yes)
			(effects
				(font
					(size 1.27 1.27)
					(thickness 0.15)
				)
			)
		)
		(property "Datasheet" "https://www.yageo.com/en/Chart/Download/pdf/CC0402KRX5R6BB224"
			(at 0 0 90)
			(layer "F.Fab")
			(hide yes)
			(effects
				(font
					(size 1.27 1.27)
					(thickness 0.15)
				)
			)
		)
		(property "Description" "SMD Multilayer Ceramic Capacitor, 0.22 µF, 10 V, 0402 [1005 Metric], ± 10%, X5R, CC Series"
			(at 0 0 90)
			(layer "F.Fab")
			(hide yes)
			(effects
				(font
					(size 1.27 1.27)
					(thickness 0.15)
				)
			)
		)
		(property "MPN" "CC0402KRX5R6BB224"
			(at 0 0 -90)
			(unlocked yes)
			(layer "F.Fab")
			(hide yes)
			(effects
				(font
					(size 1 1)
					(thickness 0.15)
				)
			)
		)
		(property "Manufacturer" "YAGEO"
			(at 0 0 -90)
			(unlocked yes)
			(layer "F.Fab")
			(hide yes)
			(effects
				(font
					(size 1 1)
					(thickness 0.15)
				)
			)
		)
		(property "License" "Apache-2.0"
			(at 0 0 -90)
			(unlocked yes)
			(layer "F.Fab")
			(hide yes)
			(effects
				(font
					(size 1 1)
					(thickness 0.15)
				)
			)
		)
		(property "Author" "Antmicro"
			(at 0 0 -90)
			(unlocked yes)
			(layer "F.Fab")
			(hide yes)
			(effects
				(font
					(size 1 1)
					(thickness 0.15)
				)
			)
		)
		(property "Val" "220n"
			(at 0 0 -90)
			(unlocked yes)
			(layer "F.Fab")
			(hide yes)
			(effects
				(font
					(size 1 1)
					(thickness 0.15)
				)
			)
		)
		(property "Voltage" ""
			(at 0 0 -90)
			(unlocked yes)
			(layer "F.Fab")
			(hide yes)
			(effects
				(font
					(size 1 1)
					(thickness 0.15)
				)
			)
		)
		(property "Dielectric" ""
			(at 0 0 -90)
			(unlocked yes)
			(layer "F.Fab")
			(hide yes)
			(effects
				(font
					(size 1 1)
					(thickness 0.15)
				)
			)
		)
		(property "Public" "False"
			(at 0 0 -90)
			(unlocked yes)
			(layer "F.Fab")
			(hide yes)
			(effects
				(font
					(size 1 1)
					(thickness 0.15)
				)
			)
		)
		(sheetname "Root")
		(sheetfile "jetson-orin-baseboard-oculink-expansion.kicad_sch")
		(attr smd)
		(fp_rect
			(start -0.925 -0.47)
			(end 0.925 0.47)
			(stroke
				(width 0.05)
				(type default)
			)
			(fill none)
			(layer "F.CrtYd")
		)
		(fp_line
			(start -0.494 0.248)
			(end -0.494 -0.25)
			(stroke
				(width 0.15)
				(type solid)
			)
			(layer "F.Fab")
		)
		(fp_line
			(start 0.504 0.248)
			(end -0.494 0.248)
			(stroke
				(width 0.15)
				(type solid)
			)
			(layer "F.Fab")
		)
		(fp_line
			(start -0.494 -0.25)
			(end 0.504 -0.25)
			(stroke
				(width 0.15)
				(type solid)
			)
			(layer "F.Fab")
		)
		(fp_line
			(start 0.504 -0.25)
			(end 0.504 0.248)
			(stroke
				(width 0.15)
				(type solid)
			)
			(layer "F.Fab")
		)
		(fp_text user "License: Apache-2.0"
			(at -0.939 5.799 90)
			(layer "F.Fab")
			(hide yes)
			(effects
				(font
					(size 0.7 0.7)
					(thickness 0.15)
				)
				(justify right top)
			)
		)
		(fp_text user "Author: Antmicro"
			(at -0.939 3.399 90)
			(layer "F.Fab")
			(hide yes)
			(effects
				(font
					(size 0.7 0.7)
					(thickness 0.15)
				)
				(justify right top)
			)
		)
		(fp_text user "${REFERENCE}"
			(at -0.939 4.599 90)
			(layer "F.Fab")
			(hide yes)
			(effects
				(font
					(size 0.7 0.7)
					(thickness 0.15)
				)
				(justify right top)
			)
		)
		(pad "1" smd roundrect
			(at -0.48 0 270)
			(size 0.59 0.64)
			(layers "F.Cu" "F.Paste" "F.Mask")
			(roundrect_rratio 0.25)
			(net 60 "/PCIE_{O}_C.TX1-")
			(pintype "passive")
		)
		(pad "2" smd roundrect
			(at 0.48 0 270)
			(size 0.59 0.64)
			(layers "F.Cu" "F.Paste" "F.Mask")
			(roundrect_rratio 0.25)
			(net 62 "/PCIE_{O}_TX1-")
			(pintype "passive")
		)
	)
	(footprint "antmicro-footprints:TP_SMD_0.75mm"
		(layer "F.Cu")
		(at 128.495 118.814751 180)
		(property "Reference" "TP12"
			(at -0.805 -0.485249 0)
			(layer "F.SilkS")
			(effects
				(font
					(size 0.7 0.7)
					(thickness 0.15)
				)
				(justify right top)
			)
		)
		(property "Value" "TP_0.75mm_SMD"
			(at 0 1.2 0)
			(layer "F.Fab")
			(effects
				(font
					(size 0.7 0.7)
					(thickness 0.15)
				)
				(justify right top)
			)
		)
		(property "Footprint" "antmicro-footprints:TP_SMD_0.75mm"
			(at 0 0 0)
			(layer "F.Fab")
			(hide yes)
			(effects
				(font
					(size 1.27 1.27)
					(thickness 0.15)
				)
			)
		)
		(property "Description" "SMT test point"
			(at 0 0 0)
			(layer "F.Fab")
			(hide yes)
			(effects
				(font
					(size 1.27 1.27)
					(thickness 0.15)
				)
			)
		)
		(property "MPN" ""
			(at 0 0 180)
			(unlocked yes)
			(layer "F.Fab")
			(hide yes)
			(effects
				(font
					(size 1 1)
					(thickness 0.15)
				)
			)
		)
		(property "Manufacturer" ""
			(at 0 0 180)
			(unlocked yes)
			(layer "F.Fab")
			(hide yes)
			(effects
				(font
					(size 1 1)
					(thickness 0.15)
				)
			)
		)
		(property "Author" "Antmicro"
			(at 0 0 180)
			(unlocked yes)
			(layer "F.Fab")
			(hide yes)
			(effects
				(font
					(size 1 1)
					(thickness 0.15)
				)
			)
		)
		(property "License" "Apache-2.0"
			(at 0 0 180)
			(unlocked yes)
			(layer "F.Fab")
			(hide yes)
			(effects
				(font
					(size 1 1)
					(thickness 0.15)
				)
			)
		)
		(property "Public" "False"
			(at 0 0 180)
			(unlocked yes)
			(layer "F.Fab")
			(hide yes)
			(effects
				(font
					(size 1 1)
					(thickness 0.15)
				)
			)
		)
		(sheetname "Root")
		(sheetfile "jetson-orin-baseboard-oculink-expansion.kicad_sch")
		(attr exclude_from_pos_files exclude_from_bom)
		(fp_circle
			(center 0 0)
			(end 0.475 0)
			(stroke
				(width 0.05)
				(type default)
			)
			(fill none)
			(layer "F.CrtYd")
		)
		(fp_text user "License: Apache-2.0"
			(at -0.4 5.101 0)
			(layer "F.Fab")
			(hide yes)
			(effects
				(font
					(size 0.7 0.7)
					(thickness 0.15)
				)
				(justify right top)
			)
		)
		(fp_text user "${REFERENCE}"
			(at -0.4 2.7 0)
			(layer "F.Fab")
			(hide yes)
			(effects
				(font
					(size 0.7 0.7)
					(thickness 0.15)
				)
				(justify right top)
			)
		)
		(fp_text user "Author: Antmicro"
			(at -0.4 3.901 0)
			(layer "F.Fab")
			(hide yes)
			(effects
				(font
					(size 0.7 0.7)
					(thickness 0.15)
				)
				(justify right top)
			)
		)
		(pad "1" smd circle
			(at 0 0 180)
			(size 0.75 0.75)
			(layers "F.Cu" "F.Mask")
			(net 110 "Net-(U2-~{I2C_{RESET}})")
			(pinfunction "1")
			(pintype "passive")
		)
	)
	(footprint "antmicro-footprints:C_0402_1005Metric"
		(layer "F.Cu")
		(at 111.1 146.306 90)
		(descr "Capacitor SMD 0402")
		(tags "capacitor SMD 0402")
		(property "Reference" "C3"
			(at 1.306 0.4 90)
			(layer "F.SilkS")
			(effects
				(font
					(size 0.7 0.7)
					(thickness 0.15)
				)
				(justify left bottom)
			)
		)
		(property "Value" "C_10u_0402"
			(at -1.022927 2.155213 90)
			(layer "F.Fab")
			(effects
				(font
					(size 0.7 0.7)
					(thickness 0.15)
				)
				(justify left bottom)
			)
		)
		(property "Footprint" "antmicro-footprints:C_0402_1005Metric"
			(at 0 0 90)
			(layer "F.Fab")
			(hide yes)
			(effects
				(font
					(size 1.27 1.27)
					(thickness 0.15)
				)
			)
		)
		(property "Datasheet" "https://www.yageo.com/en/Chart/Download/pdf/CC0402MRX5R5BB106"
			(at 0 0 90)
			(layer "F.Fab")
			(hide yes)
			(effects
				(font
					(size 1.27 1.27)
					(thickness 0.15)
				)
			)
		)
		(property "Description" "SMD Multilayer Ceramic Capacitor, 10 µF, 6.3 V, 0402 [1005 Metric], ± 20%, X5R, CC Series"
			(at 0 0 90)
			(layer "F.Fab")
			(hide yes)
			(effects
				(font
					(size 1.27 1.27)
					(thickness 0.15)
				)
			)
		)
		(property "MPN" "CC0402MRX5R5BB106"
			(at 0 0 90)
			(unlocked yes)
			(layer "F.Fab")
			(hide yes)
			(effects
				(font
					(size 1 1)
					(thickness 0.15)
				)
			)
		)
		(property "Manufacturer" "YAGEO"
			(at 0 0 90)
			(unlocked yes)
			(layer "F.Fab")
			(hide yes)
			(effects
				(font
					(size 1 1)
					(thickness 0.15)
				)
			)
		)
		(property "License" "Apache-2.0"
			(at 0 0 90)
			(unlocked yes)
			(layer "F.Fab")
			(hide yes)
			(effects
				(font
					(size 1 1)
					(thickness 0.15)
				)
			)
		)
		(property "Author" "Antmicro"
			(at 0 0 90)
			(unlocked yes)
			(layer "F.Fab")
			(hide yes)
			(effects
				(font
					(size 1 1)
					(thickness 0.15)
				)
			)
		)
		(property "Val" "10u"
			(at 0 0 90)
			(unlocked yes)
			(layer "F.Fab")
			(hide yes)
			(effects
				(font
					(size 1 1)
					(thickness 0.15)
				)
			)
		)
		(property "Voltage" ""
			(at 0 0 90)
			(unlocked yes)
			(layer "F.Fab")
			(hide yes)
			(effects
				(font
					(size 1 1)
					(thickness 0.15)
				)
			)
		)
		(property "Dielectric" ""
			(at 0 0 90)
			(unlocked yes)
			(layer "F.Fab")
			(hide yes)
			(effects
				(font
					(size 1 1)
					(thickness 0.15)
				)
			)
		)
		(sheetname "Root")
		(sheetfile "jetson-orin-baseboard-oculink-expansion.kicad_sch")
		(attr smd)
		(fp_rect
			(start -0.925 -0.47)
			(end 0.925 0.47)
			(stroke
				(width 0.05)
				(type default)
			)
			(fill none)
			(layer "F.CrtYd")
		)
		(fp_line
			(start 0.504 -0.25)
			(end 0.504 0.248)
			(stroke
				(width 0.15)
				(type solid)
			)
			(layer "F.Fab")
		)
		(fp_line
			(start -0.494 -0.25)
			(end 0.504 -0.25)
			(stroke
				(width 0.15)
				(type solid)
			)
			(layer "F.Fab")
		)
		(fp_line
			(start 0.504 0.248)
			(end -0.494 0.248)
			(stroke
				(width 0.15)
				(type solid)
			)
			(layer "F.Fab")
		)
		(fp_line
			(start -0.494 0.248)
			(end -0.494 -0.25)
			(stroke
				(width 0.15)
				(type solid)
			)
			(layer "F.Fab")
		)
		(fp_text user "${REFERENCE}"
			(at -0.939 4.599 90)
			(layer "F.Fab")
			(hide yes)
			(effects
				(font
					(size 0.7 0.7)
					(thickness 0.15)
				)
				(justify left bottom)
			)
		)
		(fp_text user "License: Apache-2.0"
			(at -0.939 5.799 90)
			(layer "F.Fab")
			(hide yes)
			(effects
				(font
					(size 0.7 0.7)
					(thickness 0.15)
				)
				(justify left bottom)
			)
		)
		(fp_text user "Author: Antmicro"
			(at -0.939 3.399 90)
			(layer "F.Fab")
			(hide yes)
			(effects
				(font
					(size 0.7 0.7)
					(thickness 0.15)
				)
				(justify left bottom)
			)
		)
		(pad "1" smd roundrect
			(at -0.48 0 90)
			(size 0.59 0.64)
			(layers "F.Cu" "F.Paste" "F.Mask")
			(roundrect_rratio 0.25)
			(net 51 "GND")
			(pintype "passive")
		)
		(pad "2" smd roundrect
			(at 0.48 0 90)
			(size 0.59 0.64)
			(layers "F.Cu" "F.Paste" "F.Mask")
			(roundrect_rratio 0.25)
			(net 132 "+3V3_OCU")
			(pintype "passive")
		)
	)
	(footprint "antmicro-footprints:R_0402_1005Metric"
		(layer "F.Cu")
		(at 131.46 117.17 180)
		(descr "Resistor SMD 0402")
		(tags "resistor SMD 0402")
		(property "Reference" "R36"
			(at -2.28 -0.55 180)
			(layer "F.SilkS")
			(effects
				(font
					(size 0.7 0.7)
					(thickness 0.15)
				)
				(justify right top)
			)
		)
		(property "Value" "R_0R_0402"
			(at -1.011843 1.772047 0)
			(layer "F.Fab")
			(effects
				(font
					(size 0.7 0.7)
					(thickness 0.15)
				)
				(justify right top)
			)
		)
		(property "Footprint" "antmicro-footprints:R_0402_1005Metric"
			(at 0 0 0)
			(layer "F.Fab")
			(hide yes)
			(effects
				(font
					(size 1.27 1.27)
					(thickness 0.15)
				)
			)
		)
		(property "Datasheet" "https://industrial.panasonic.com/cdbs/www-data/pdf/RDA0000/AOA0000C301.pdf"
			(at 0 0 0)
			(layer "F.Fab")
			(hide yes)
			(effects
				(font
					(size 1.27 1.27)
					(thickness 0.15)
				)
			)
		)
		(property "Description" "SMD Chip Resistor, Jumper, 0 ohm, 100 mW, 0402 [1005 Metric], Thick Film, General Purpose"
			(at 0 0 0)
			(layer "F.Fab")
			(hide yes)
			(effects
				(font
					(size 1.27 1.27)
					(thickness 0.15)
				)
			)
		)
		(property "MPN" "ERJ2GE0R00X"
			(at 0 0 180)
			(unlocked yes)
			(layer "F.Fab")
			(hide yes)
			(effects
				(font
					(size 1 1)
					(thickness 0.15)
				)
			)
		)
		(property "Manufacturer" "Panasonic"
			(at 0 0 180)
			(unlocked yes)
			(layer "F.Fab")
			(hide yes)
			(effects
				(font
					(size 1 1)
					(thickness 0.15)
				)
			)
		)
		(property "License" "Apache-2.0"
			(at 0 0 180)
			(unlocked yes)
			(layer "F.Fab")
			(hide yes)
			(effects
				(font
					(size 1 1)
					(thickness 0.15)
				)
			)
		)
		(property "Author" "Antmicro"
			(at 0 0 180)
			(unlocked yes)
			(layer "F.Fab")
			(hide yes)
			(effects
				(font
					(size 1 1)
					(thickness 0.15)
				)
			)
		)
		(property "Val" "0R"
			(at 0 0 180)
			(unlocked yes)
			(layer "F.Fab")
			(hide yes)
			(effects
				(font
					(size 1 1)
					(thickness 0.15)
				)
			)
		)
		(property "Tolerance" ""
			(at 0 0 180)
			(unlocked yes)
			(layer "F.Fab")
			(hide yes)
			(effects
				(font
					(size 1 1)
					(thickness 0.15)
				)
			)
		)
		(property "Current" "1A"
			(at 0 0 180)
			(unlocked yes)
			(layer "F.Fab")
			(hide yes)
			(effects
				(font
					(size 1 1)
					(thickness 0.15)
				)
			)
		)
		(property "Public" "False"
			(at 0 0 180)
			(unlocked yes)
			(layer "F.Fab")
			(hide yes)
			(effects
				(font
					(size 1 1)
					(thickness 0.15)
				)
			)
		)
		(sheetname "Root")
		(sheetfile "jetson-orin-baseboard-oculink-expansion.kicad_sch")
		(attr smd dnp)
		(fp_rect
			(start -0.925 -0.47)
			(end 0.925 0.47)
			(stroke
				(width 0.05)
				(type default)
			)
			(fill none)
			(layer "F.CrtYd")
		)
		(fp_rect
			(start -0.5 -0.25)
			(end 0.5 0.25)
			(stroke
				(width 0.15)
				(type solid)
			)
			(fill none)
			(layer "F.Fab")
		)
		(fp_text user "${REFERENCE}"
			(at -0.95 3.168 0)
			(layer "F.Fab")
			(hide yes)
			(effects
				(font
					(size 0.7 0.7)
					(thickness 0.15)
				)
				(justify right top)
			)
		)
		(fp_text user "License: Apache-2.0"
			(at -0.95 5.169 0)
			(layer "F.Fab")
			(hide yes)
			(effects
				(font
					(size 0.7 0.7)
					(thickness 0.15)
				)
				(justify right top)
			)
		)
		(fp_text user "Author: Antmicro"
			(at -0.95 4.169 0)
			(layer "F.Fab")
			(hide yes)
			(effects
				(font
					(size 0.7 0.7)
					(thickness 0.15)
				)
				(justify right top)
			)
		)
		(pad "1" smd roundrect
			(at -0.48 0 180)
			(size 0.59 0.64)
			(layers "F.Cu" "F.Paste" "F.Mask")
			(roundrect_rratio 0.25)
			(net 61 "/I2C_SDA")
			(pintype "passive")
		)
		(pad "2" smd roundrect
			(at 0.48 0 180)
			(size 0.59 0.64)
			(layers "F.Cu" "F.Paste" "F.Mask")
			(roundrect_rratio 0.25)
			(net 95 "Net-(U2-SDA)")
			(pintype "passive")
		)
	)
	(footprint "antmicro-footprints:R_0402_1005Metric"
		(layer "F.Cu")
		(at 141.1 140.5)
		(descr "Resistor SMD 0402")
		(tags "resistor SMD 0402")
		(property "Reference" "R3"
			(at -0.75 -0.35 0)
			(layer "F.SilkS")
			(effects
				(font
					(size 0.7 0.7)
					(thickness 0.15)
				)
				(justify left bottom)
			)
		)
		(property "Value" "R_10k_0402"
			(at -1.011843 1.772047 0)
			(layer "F.Fab")
			(effects
				(font
					(size 0.7 0.7)
					(thickness 0.15)
				)
				(justify left bottom)
			)
		)
		(property "Footprint" "antmicro-footprints:R_0402_1005Metric"
			(at 0 0 0)
			(layer "F.Fab")
			(hide yes)
			(effects
				(font
					(size 1.27 1.27)
					(thickness 0.15)
				)
			)
		)
		(property "Datasheet" "https://www.bourns.com/docs/product-datasheets/cr.pdf"
			(at 0 0 0)
			(layer "F.Fab")
			(hide yes)
			(effects
				(font
					(size 1.27 1.27)
					(thickness 0.15)
				)
			)
		)
		(property "Description" "SMD Chip Resistor, 10 kohm, ± 1%, 62.5 mW, 0402 [1005 Metric], Thick Film, General Purpose"
			(at 0 0 0)
			(layer "F.Fab")
			(hide yes)
			(effects
				(font
					(size 1.27 1.27)
					(thickness 0.15)
				)
			)
		)
		(property "MPN" "CR0402-FX-1002GLF"
			(at 0 0 0)
			(unlocked yes)
			(layer "F.Fab")
			(hide yes)
			(effects
				(font
					(size 1 1)
					(thickness 0.15)
				)
			)
		)
		(property "Manufacturer" "Bourns"
			(at 0 0 0)
			(unlocked yes)
			(layer "F.Fab")
			(hide yes)
			(effects
				(font
					(size 1 1)
					(thickness 0.15)
				)
			)
		)
		(property "License" "Apache-2.0"
			(at 0 0 0)
			(unlocked yes)
			(layer "F.Fab")
			(hide yes)
			(effects
				(font
					(size 1 1)
					(thickness 0.15)
				)
			)
		)
		(property "Author" "Antmicro"
			(at 0 0 0)
			(unlocked yes)
			(layer "F.Fab")
			(hide yes)
			(effects
				(font
					(size 1 1)
					(thickness 0.15)
				)
			)
		)
		(property "Val" "10k"
			(at 0 0 0)
			(unlocked yes)
			(layer "F.Fab")
			(hide yes)
			(effects
				(font
					(size 1 1)
					(thickness 0.15)
				)
			)
		)
		(property "Tolerance" "1%"
			(at 0 0 0)
			(unlocked yes)
			(layer "F.Fab")
			(hide yes)
			(effects
				(font
					(size 1 1)
					(thickness 0.15)
				)
			)
		)
		(sheetname "Root")
		(sheetfile "jetson-orin-baseboard-oculink-expansion.kicad_sch")
		(attr smd)
		(fp_rect
			(start -0.925 -0.47)
			(end 0.925 0.47)
			(stroke
				(width 0.05)
				(type default)
			)
			(fill none)
			(layer "F.CrtYd")
		)
		(fp_rect
			(start -0.5 -0.25)
			(end 0.5 0.25)
			(stroke
				(width 0.15)
				(type solid)
			)
			(fill none)
			(layer "F.Fab")
		)
		(fp_text user "License: Apache-2.0"
			(at -0.95 5.169 0)
			(layer "F.Fab")
			(hide yes)
			(effects
				(font
					(size 0.7 0.7)
					(thickness 0.15)
				)
				(justify left bottom)
			)
		)
		(fp_text user "Author: Antmicro"
			(at -0.95 4.169 0)
			(layer "F.Fab")
			(hide yes)
			(effects
				(font
					(size 0.7 0.7)
					(thickness 0.15)
				)
				(justify left bottom)
			)
		)
		(fp_text user "${REFERENCE}"
			(at -0.95 3.168 0)
			(layer "F.Fab")
			(hide yes)
			(effects
				(font
					(size 0.7 0.7)
					(thickness 0.15)
				)
				(justify left bottom)
			)
		)
		(pad "1" smd roundrect
			(at -0.48 0)
			(size 0.59 0.64)
			(layers "F.Cu" "F.Paste" "F.Mask")
			(roundrect_rratio 0.25)
			(net 51 "GND")
			(pintype "passive")
		)
		(pad "2" smd roundrect
			(at 0.48 0)
			(size 0.59 0.64)
			(layers "F.Cu" "F.Paste" "F.Mask")
			(roundrect_rratio 0.25)
			(net 70 "Net-(U1-~{THREE_STATE})")
			(pintype "passive")
		)
	)
	(footprint "antmicro-footprints:R_0402_1005Metric"
		(layer "F.Cu")
		(at 146.22 144.66)
		(descr "Resistor SMD 0402")
		(tags "resistor SMD 0402")
		(property "Reference" "R33"
			(at -1.09 1.49 0)
			(layer "F.SilkS")
			(effects
				(font
					(size 0.7 0.7)
					(thickness 0.15)
				)
				(justify left bottom)
			)
		)
		(property "Value" "R_1k_0402"
			(at -1.011843 1.772047 0)
			(layer "F.Fab")
			(effects
				(font
					(size 0.7 0.7)
					(thickness 0.15)
				)
				(justify left bottom)
			)
		)
		(property "Footprint" "antmicro-footprints:R_0402_1005Metric"
			(at 0 0 0)
			(layer "F.Fab")
			(hide yes)
			(effects
				(font
					(size 1.27 1.27)
					(thickness 0.15)
				)
			)
		)
		(property "Datasheet" "https://www.bourns.com/docs/product-datasheets/cr.pdf"
			(at 0 0 0)
			(layer "F.Fab")
			(hide yes)
			(effects
				(font
					(size 1.27 1.27)
					(thickness 0.15)
				)
			)
		)
		(property "Description" "SMD Chip Resistor, 1 kohm, ± 1%, 63 mW, 0402 [1005 Metric], Thick Film, General Purpose"
			(at 0 0 0)
			(layer "F.Fab")
			(hide yes)
			(effects
				(font
					(size 1.27 1.27)
					(thickness 0.15)
				)
			)
		)
		(property "MPN" "CR0402-FX-1001GLF"
			(at 0 0 0)
			(unlocked yes)
			(layer "F.Fab")
			(hide yes)
			(effects
				(font
					(size 1 1)
					(thickness 0.15)
				)
			)
		)
		(property "Manufacturer" "Bourns"
			(at 0 0 0)
			(unlocked yes)
			(layer "F.Fab")
			(hide yes)
			(effects
				(font
					(size 1 1)
					(thickness 0.15)
				)
			)
		)
		(property "License" "Apache-2.0"
			(at 0 0 0)
			(unlocked yes)
			(layer "F.Fab")
			(hide yes)
			(effects
				(font
					(size 1 1)
					(thickness 0.15)
				)
			)
		)
		(property "Author" "Antmicro"
			(at 0 0 0)
			(unlocked yes)
			(layer "F.Fab")
			(hide yes)
			(effects
				(font
					(size 1 1)
					(thickness 0.15)
				)
			)
		)
		(property "Val" "1k"
			(at 0 0 0)
			(unlocked yes)
			(layer "F.Fab")
			(hide yes)
			(effects
				(font
					(size 1 1)
					(thickness 0.15)
				)
			)
		)
		(property "Tolerance" "1%"
			(at 0 0 0)
			(unlocked yes)
			(layer "F.Fab")
			(hide yes)
			(effects
				(font
					(size 1 1)
					(thickness 0.15)
				)
			)
		)
		(property "Public" "False"
			(at 0 0 0)
			(unlocked yes)
			(layer "F.Fab")
			(hide yes)
			(effects
				(font
					(size 1 1)
					(thickness 0.15)
				)
			)
		)
		(sheetname "Root")
		(sheetfile "jetson-orin-baseboard-oculink-expansion.kicad_sch")
		(attr smd)
		(fp_rect
			(start -0.925 -0.47)
			(end 0.925 0.47)
			(stroke
				(width 0.05)
				(type default)
			)
			(fill none)
			(layer "F.CrtYd")
		)
		(fp_rect
			(start -0.5 -0.25)
			(end 0.5 0.25)
			(stroke
				(width 0.15)
				(type solid)
			)
			(fill none)
			(layer "F.Fab")
		)
		(fp_text user "License: Apache-2.0"
			(at -0.95 5.169 0)
			(layer "F.Fab")
			(hide yes)
			(effects
				(font
					(size 0.7 0.7)
					(thickness 0.15)
				)
				(justify left bottom)
			)
		)
		(fp_text user "Author: Antmicro"
			(at -0.95 4.169 0)
			(layer "F.Fab")
			(hide yes)
			(effects
				(font
					(size 0.7 0.7)
					(thickness 0.15)
				)
				(justify left bottom)
			)
		)
		(fp_text user "${REFERENCE}"
			(at -0.95 3.168 0)
			(layer "F.Fab")
			(hide yes)
			(effects
				(font
					(size 0.7 0.7)
					(thickness 0.15)
				)
				(justify left bottom)
			)
		)
		(pad "1" smd roundrect
			(at -0.48 0)
			(size 0.59 0.64)
			(layers "F.Cu" "F.Paste" "F.Mask")
			(roundrect_rratio 0.25)
			(net 71 "/~{CPRSNT}")
			(pintype "passive")
		)
		(pad "2" smd roundrect
			(at 0.48 0)
			(size 0.59 0.64)
			(layers "F.Cu" "F.Paste" "F.Mask")
			(roundrect_rratio 0.25)
			(net 51 "GND")
			(pintype "passive")
		)
	)
	(footprint "antmicro-footprints:TP_SMD_0.75mm"
		(layer "F.Cu")
		(at 130.005 112.903751 180)
		(property "Reference" "TP11"
			(at -2.385 1.303751 0)
			(layer "F.SilkS")
			(effects
				(font
					(size 0.7 0.7)
					(thickness 0.15)
				)
				(justify right top)
			)
		)
		(property "Value" "TP_0.75mm_SMD"
			(at 0 1.2 0)
			(layer "F.Fab")
			(effects
				(font
					(size 0.7 0.7)
					(thickness 0.15)
				)
				(justify right top)
			)
		)
		(property "Footprint" "antmicro-footprints:TP_SMD_0.75mm"
			(at 0 0 0)
			(layer "F.Fab")
			(hide yes)
			(effects
				(font
					(size 1.27 1.27)
					(thickness 0.15)
				)
			)
		)
		(property "Description" "SMT test point"
			(at 0 0 0)
			(layer "F.Fab")
			(hide yes)
			(effects
				(font
					(size 1.27 1.27)
					(thickness 0.15)
				)
			)
		)
		(property "MPN" ""
			(at 0 0 180)
			(unlocked yes)
			(layer "F.Fab")
			(hide yes)
			(effects
				(font
					(size 1 1)
					(thickness 0.15)
				)
			)
		)
		(property "Manufacturer" ""
			(at 0 0 180)
			(unlocked yes)
			(layer "F.Fab")
			(hide yes)
			(effects
				(font
					(size 1 1)
					(thickness 0.15)
				)
			)
		)
		(property "Author" "Antmicro"
			(at 0 0 180)
			(unlocked yes)
			(layer "F.Fab")
			(hide yes)
			(effects
				(font
					(size 1 1)
					(thickness 0.15)
				)
			)
		)
		(property "License" "Apache-2.0"
			(at 0 0 180)
			(unlocked yes)
			(layer "F.Fab")
			(hide yes)
			(effects
				(font
					(size 1 1)
					(thickness 0.15)
				)
			)
		)
		(property "Public" "False"
			(at 0 0 180)
			(unlocked yes)
			(layer "F.Fab")
			(hide yes)
			(effects
				(font
					(size 1 1)
					(thickness 0.15)
				)
			)
		)
		(sheetname "Root")
		(sheetfile "jetson-orin-baseboard-oculink-expansion.kicad_sch")
		(attr exclude_from_pos_files exclude_from_bom)
		(fp_circle
			(center 0 0)
			(end 0.475 0)
			(stroke
				(width 0.05)
				(type default)
			)
			(fill none)
			(layer "F.CrtYd")
		)
		(fp_text user "License: Apache-2.0"
			(at -0.4 5.101 0)
			(layer "F.Fab")
			(hide yes)
			(effects
				(font
					(size 0.7 0.7)
					(thickness 0.15)
				)
				(justify right top)
			)
		)
		(fp_text user "Author: Antmicro"
			(at -0.4 3.901 0)
			(layer "F.Fab")
			(hide yes)
			(effects
				(font
					(size 0.7 0.7)
					(thickness 0.15)
				)
				(justify right top)
			)
		)
		(fp_text user "${REFERENCE}"
			(at -0.4 2.7 0)
			(layer "F.Fab")
			(hide yes)
			(effects
				(font
					(size 0.7 0.7)
					(thickness 0.15)
				)
				(justify right top)
			)
		)
		(pad "1" smd circle
			(at 0 0 180)
			(size 0.75 0.75)
			(layers "F.Cu" "F.Mask")
			(net 109 "Net-(U2-I2C_{DONE})")
			(pinfunction "1")
			(pintype "passive")
		)
	)
	(footprint "antmicro-footprints:C_0402_1005Metric"
		(layer "F.Cu")
		(at 129.2 109.278 180)
		(descr "Capacitor SMD 0402")
		(tags "capacitor SMD 0402")
		(property "Reference" "C38"
			(at 0.9 0.37 0)
			(layer "F.SilkS")
			(effects
				(font
					(size 0.7 0.7)
					(thickness 0.15)
				)
				(justify right top)
			)
		)
		(property "Value" "C_220n_0402"
			(at -1.022927 2.155213 0)
			(layer "F.Fab")
			(effects
				(font
					(size 0.7 0.7)
					(thickness 0.15)
				)
				(justify right top)
			)
		)
		(property "Footprint" "antmicro-footprints:C_0402_1005Metric"
			(at 0 0 0)
			(layer "F.Fab")
			(hide yes)
			(effects
				(font
					(size 1.27 1.27)
					(thickness 0.15)
				)
			)
		)
		(property "Datasheet" "https://www.yageo.com/en/Chart/Download/pdf/CC0402KRX5R6BB224"
			(at 0 0 0)
			(layer "F.Fab")
			(hide yes)
			(effects
				(font
					(size 1.27 1.27)
					(thickness 0.15)
				)
			)
		)
		(property "Description" "SMD Multilayer Ceramic Capacitor, 0.22 µF, 10 V, 0402 [1005 Metric], ± 10%, X5R, CC Series"
			(at 0 0 0)
			(layer "F.Fab")
			(hide yes)
			(effects
				(font
					(size 1.27 1.27)
					(thickness 0.15)
				)
			)
		)
		(property "MPN" "CC0402KRX5R6BB224"
			(at 0 0 180)
			(unlocked yes)
			(layer "F.Fab")
			(hide yes)
			(effects
				(font
					(size 1 1)
					(thickness 0.15)
				)
			)
		)
		(property "Manufacturer" "YAGEO"
			(at 0 0 180)
			(unlocked yes)
			(layer "F.Fab")
			(hide yes)
			(effects
				(font
					(size 1 1)
					(thickness 0.15)
				)
			)
		)
		(property "License" "Apache-2.0"
			(at 0 0 180)
			(unlocked yes)
			(layer "F.Fab")
			(hide yes)
			(effects
				(font
					(size 1 1)
					(thickness 0.15)
				)
			)
		)
		(property "Author" "Antmicro"
			(at 0 0 180)
			(unlocked yes)
			(layer "F.Fab")
			(hide yes)
			(effects
				(font
					(size 1 1)
					(thickness 0.15)
				)
			)
		)
		(property "Val" "220n"
			(at 0 0 180)
			(unlocked yes)
			(layer "F.Fab")
			(hide yes)
			(effects
				(font
					(size 1 1)
					(thickness 0.15)
				)
			)
		)
		(property "Voltage" ""
			(at 0 0 180)
			(unlocked yes)
			(layer "F.Fab")
			(hide yes)
			(effects
				(font
					(size 1 1)
					(thickness 0.15)
				)
			)
		)
		(property "Dielectric" ""
			(at 0 0 180)
			(unlocked yes)
			(layer "F.Fab")
			(hide yes)
			(effects
				(font
					(size 1 1)
					(thickness 0.15)
				)
			)
		)
		(property "Public" "False"
			(at 0 0 180)
			(unlocked yes)
			(layer "F.Fab")
			(hide yes)
			(effects
				(font
					(size 1 1)
					(thickness 0.15)
				)
			)
		)
		(sheetname "Root")
		(sheetfile "jetson-orin-baseboard-oculink-expansion.kicad_sch")
		(attr smd)
		(fp_rect
			(start -0.925 -0.47)
			(end 0.925 0.47)
			(stroke
				(width 0.05)
				(type default)
			)
			(fill none)
			(layer "F.CrtYd")
		)
		(fp_line
			(start 0.504 0.248)
			(end -0.494 0.248)
			(stroke
				(width 0.15)
				(type solid)
			)
			(layer "F.Fab")
		)
		(fp_line
			(start 0.504 -0.25)
			(end 0.504 0.248)
			(stroke
				(width 0.15)
				(type solid)
			)
			(layer "F.Fab")
		)
		(fp_line
			(start -0.494 0.248)
			(end -0.494 -0.25)
			(stroke
				(width 0.15)
				(type solid)
			)
			(layer "F.Fab")
		)
		(fp_line
			(start -0.494 -0.25)
			(end 0.504 -0.25)
			(stroke
				(width 0.15)
				(type solid)
			)
			(layer "F.Fab")
		)
		(fp_text user "License: Apache-2.0"
			(at -0.939 5.799 0)
			(layer "F.Fab")
			(hide yes)
			(effects
				(font
					(size 0.7 0.7)
					(thickness 0.15)
				)
				(justify right top)
			)
		)
		(fp_text user "Author: Antmicro"
			(at -0.939 3.399 0)
			(layer "F.Fab")
			(hide yes)
			(effects
				(font
					(size 0.7 0.7)
					(thickness 0.15)
				)
				(justify right top)
			)
		)
		(fp_text user "${REFERENCE}"
			(at -0.939 4.599 0)
			(layer "F.Fab")
			(hide yes)
			(effects
				(font
					(size 0.7 0.7)
					(thickness 0.15)
				)
				(justify right top)
			)
		)
		(pad "1" smd roundrect
			(at -0.48 0 180)
			(size 0.59 0.64)
			(layers "F.Cu" "F.Paste" "F.Mask")
			(roundrect_rratio 0.25)
			(net 78 "/PCIE_{I}_RX0+")
			(pintype "passive")
		)
		(pad "2" smd roundrect
			(at 0.48 0 180)
			(size 0.59 0.64)
			(layers "F.Cu" "F.Paste" "F.Mask")
			(roundrect_rratio 0.25)
			(net 77 "/PCIE_{I}_C.RX0+")
			(pintype "passive")
		)
	)
	(footprint "antmicro-footprints:SOT-23-8"
		(layer "F.Cu")
		(at 144.099 142.299 180)
		(descr "http://www.ti.com/lit/ds/symlink/ina219.pdf")
		(property "Reference" "U1"
			(at -0.301 -1.901 90)
			(layer "F.SilkS")
			(effects
				(font
					(size 0.7 0.7)
					(thickness 0.15)
				)
				(justify right top)
			)
		)
		(property "Value" "MAX3373EEKA+"
			(at -4.101 -2.301 0)
			(layer "F.Fab")
			(effects
				(font
					(size 0.7 0.7)
					(thickness 0.15)
				)
				(justify right top)
			)
		)
		(property "Footprint" "antmicro-footprints:SOT-23-8"
			(at 0 0 0)
			(layer "F.Fab")
			(hide yes)
			(effects
				(font
					(size 1.27 1.27)
					(thickness 0.15)
				)
			)
		)
		(property "Datasheet" "https://www.analog.com/en/products/max3373e.html"
			(at 0 0 0)
			(layer "F.Fab")
			(hide yes)
			(effects
				(font
					(size 1.27 1.27)
					(thickness 0.15)
				)
			)
		)
		(property "Description" "±15kV ESD-Protected, 1µA, 16Mbps, Dual/Quad Low-Voltage Level Translators in UCSP"
			(at 0 0 0)
			(layer "F.Fab")
			(hide yes)
			(effects
				(font
					(size 1.27 1.27)
					(thickness 0.15)
				)
			)
		)
		(property "MPN" "MAX3373EEKA+"
			(at 0 0 180)
			(unlocked yes)
			(layer "F.Fab")
			(hide yes)
			(effects
				(font
					(size 1 1)
					(thickness 0.15)
				)
			)
		)
		(property "Manufacturer" "Analog Devices"
			(at 0 0 180)
			(unlocked yes)
			(layer "F.Fab")
			(hide yes)
			(effects
				(font
					(size 1 1)
					(thickness 0.15)
				)
			)
		)
		(property "Author" "Antmicro"
			(at 0 0 180)
			(unlocked yes)
			(layer "F.Fab")
			(hide yes)
			(effects
				(font
					(size 1 1)
					(thickness 0.15)
				)
			)
		)
		(property "License" "Apache-2.0"
			(at 0 0 180)
			(unlocked yes)
			(layer "F.Fab")
			(hide yes)
			(effects
				(font
					(size 1 1)
					(thickness 0.15)
				)
			)
		)
		(sheetname "Root")
		(sheetfile "jetson-orin-baseboard-oculink-expansion.kicad_sch")
		(attr smd)
		(fp_line
			(start 1 1.6)
			(end 0.6 1.6)
			(stroke
				(width 0.15)
				(type solid)
			)
			(layer "F.SilkS")
		)
		(fp_line
			(start 1 1.3)
			(end 1 1.6)
			(stroke
				(width 0.15)
				(type solid)
			)
			(layer "F.SilkS")
		)
		(fp_line
			(start 1 -1.3)
			(end 1 -1.6)
			(stroke
				(width 0.15)
				(type solid)
			)
			(layer "F.SilkS")
		)
		(fp_line
			(start 1 -1.6)
			(end 0.625 -1.6)
			(stroke
				(width 0.15)
				(type solid)
			)
			(layer "F.SilkS")
		)
		(fp_line
			(start -0.613 1.6)
			(end -0.987 1.6)
			(stroke
				(width 0.15)
				(type solid)
			)
			(layer "F.SilkS")
		)
		(fp_line
			(start -0.987 1.6)
			(end -0.987 1.324)
			(stroke
				(width 0.15)
				(type solid)
			)
			(layer "F.SilkS")
		)
		(fp_line
			(start -1 -1.3)
			(end -1 -1.6)
			(stroke
				(width 0.15)
				(type solid)
			)
			(layer "F.SilkS")
		)
		(fp_line
			(start -1 -1.6)
			(end -0.6 -1.6)
			(stroke
				(width 0.15)
				(type solid)
			)
			(layer "F.SilkS")
		)
		(fp_circle
			(center -1.3 -1.4)
			(end -1.25 -1.4)
			(stroke
				(width 0.15)
				(type solid)
			)
			(fill solid)
			(layer "F.SilkS")
		)
		(fp_rect
			(start -1.9 -1.75)
			(end 1.898 1.75)
			(stroke
				(width 0.05)
				(type solid)
			)
			(fill none)
			(layer "F.CrtYd")
		)
		(fp_line
			(start -1.4 -1.25)
			(end -1.2 -1.45)
			(stroke
				(width 0.15)
				(type solid)
			)
			(layer "F.Fab")
		)
		(fp_rect
			(start -1.401 -1.45)
			(end 1.398 1.449)
			(stroke
				(width 0.15)
				(type solid)
			)
			(fill none)
			(layer "F.Fab")
		)
		(fp_text user "Author: Antmicro"
			(at -2.925 7.2 0)
			(layer "F.Fab")
			(hide yes)
			(effects
				(font
					(size 0.7 0.7)
					(thickness 0.15)
				)
				(justify right top)
			)
		)
		(fp_text user "${REFERENCE}"
			(at -2.925 4.8 0)
			(layer "F.Fab")
			(hide yes)
			(effects
				(font
					(size 0.7 0.7)
					(thickness 0.15)
				)
				(justify right top)
			)
		)
		(fp_text user "License: Apache-2.0"
			(at -2.925 6 0)
			(layer "F.Fab")
			(hide yes)
			(effects
				(font
					(size 0.7 0.7)
					(thickness 0.15)
				)
				(justify right top)
			)
		)
		(pad "1" smd roundrect
			(at -1.3 -0.975 90)
			(size 0.45 1.1)
			(layers "F.Cu" "F.Paste" "F.Mask")
			(roundrect_rratio 0.25)
			(net 71 "/~{CPRSNT}")
			(pinfunction "IO_V_{CC}2")
			(pintype "bidirectional")
		)
		(pad "2" smd roundrect
			(at -1.3 -0.325 90)
			(size 0.45 1.1)
			(layers "F.Cu" "F.Paste" "F.Mask")
			(roundrect_rratio 0.25)
			(net 51 "GND")
			(pinfunction "GND")
			(pintype "power_in")
		)
		(pad "3" smd roundrect
			(at -1.3 0.325 90)
			(size 0.45 1.1)
			(layers "F.Cu" "F.Paste" "F.Mask")
			(roundrect_rratio 0.25)
			(net 20 "+1V8")
			(pinfunction "V_{L}")
			(pintype "power_in")
		)
		(pad "4" smd roundrect
			(at -1.3 0.975 90)
			(size 0.45 1.1)
			(layers "F.Cu" "F.Paste" "F.Mask")
			(roundrect_rratio 0.25)
			(net 67 "/JOB_GPIO07")
			(pinfunction "IO_V_{L}2")
			(pintype "bidirectional")
		)
		(pad "5" smd roundrect
			(at 1.3 0.975 90)
			(size 0.45 1.1)
			(layers "F.Cu" "F.Paste" "F.Mask")
			(roundrect_rratio 0.25)
			(net 65 "/JOB_GPIO09")
			(pinfunction "IO_V_{L}1")
			(pintype "bidirectional")
		)
		(pad "6" smd roundrect
			(at 1.3 0.325 90)
			(size 0.45 1.1)
			(layers "F.Cu" "F.Paste" "F.Mask")
			(roundrect_rratio 0.25)
			(net 70 "Net-(U1-~{THREE_STATE})")
			(pinfunction "~{THREE_STATE}")
			(pintype "input")
		)
		(pad "7" smd roundrect
			(at 1.3 -0.325 90)
			(size 0.45 1.1)
			(layers "F.Cu" "F.Paste" "F.Mask")
			(roundrect_rratio 0.25)
			(net 23 "+3V3")
			(pinfunction "V_{CC}")
			(pintype "power_in")
		)
		(pad "8" smd roundrect
			(at 1.3 -0.975 90)
			(size 0.45 1.1)
			(layers "F.Cu" "F.Paste" "F.Mask")
			(roundrect_rratio 0.25)
			(net 69 "/~{PCIE_CWAKE}")
			(pinfunction "IO_V_{CC}1")
			(pintype "bidirectional")
		)
	)
	(footprint "antmicro-footprints:C_0402_1005Metric"
		(layer "F.Cu")
		(at 115.43875 137.65 -90)
		(descr "Capacitor SMD 0402")
		(tags "capacitor SMD 0402")
		(property "Reference" "C15"
			(at 0.85 0.30875 90)
			(layer "F.SilkS")
			(effects
				(font
					(size 0.7 0.7)
					(thickness 0.15)
				)
				(justify right top)
			)
		)
		(property "Value" "C_220n_0402"
			(at -1.022927 2.155213 90)
			(layer "F.Fab")
			(effects
				(font
					(size 0.7 0.7)
					(thickness 0.15)
				)
				(justify right top)
			)
		)
		(property "Footprint" "antmicro-footprints:C_0402_1005Metric"
			(at 0 0 90)
			(layer "F.Fab")
			(hide yes)
			(effects
				(font
					(size 1.27 1.27)
					(thickness 0.15)
				)
			)
		)
		(property "Datasheet" "https://www.yageo.com/en/Chart/Download/pdf/CC0402KRX5R6BB224"
			(at 0 0 90)
			(layer "F.Fab")
			(hide yes)
			(effects
				(font
					(size 1.27 1.27)
					(thickness 0.15)
				)
			)
		)
		(property "Description" "SMD Multilayer Ceramic Capacitor, 0.22 µF, 10 V, 0402 [1005 Metric], ± 10%, X5R, CC Series"
			(at 0 0 90)
			(layer "F.Fab")
			(hide yes)
			(effects
				(font
					(size 1.27 1.27)
					(thickness 0.15)
				)
			)
		)
		(property "MPN" "CC0402KRX5R6BB224"
			(at 0 0 -90)
			(unlocked yes)
			(layer "F.Fab")
			(hide yes)
			(effects
				(font
					(size 1 1)
					(thickness 0.15)
				)
			)
		)
		(property "Manufacturer" "YAGEO"
			(at 0 0 -90)
			(unlocked yes)
			(layer "F.Fab")
			(hide yes)
			(effects
				(font
					(size 1 1)
					(thickness 0.15)
				)
			)
		)
		(property "License" "Apache-2.0"
			(at 0 0 -90)
			(unlocked yes)
			(layer "F.Fab")
			(hide yes)
			(effects
				(font
					(size 1 1)
					(thickness 0.15)
				)
			)
		)
		(property "Author" "Antmicro"
			(at 0 0 -90)
			(unlocked yes)
			(layer "F.Fab")
			(hide yes)
			(effects
				(font
					(size 1 1)
					(thickness 0.15)
				)
			)
		)
		(property "Val" "220n"
			(at 0 0 -90)
			(unlocked yes)
			(layer "F.Fab")
			(hide yes)
			(effects
				(font
					(size 1 1)
					(thickness 0.15)
				)
			)
		)
		(property "Voltage" ""
			(at 0 0 -90)
			(unlocked yes)
			(layer "F.Fab")
			(hide yes)
			(effects
				(font
					(size 1 1)
					(thickness 0.15)
				)
			)
		)
		(property "Dielectric" ""
			(at 0 0 -90)
			(unlocked yes)
			(layer "F.Fab")
			(hide yes)
			(effects
				(font
					(size 1 1)
					(thickness 0.15)
				)
			)
		)
		(property "Public" "False"
			(at 0 0 -90)
			(unlocked yes)
			(layer "F.Fab")
			(hide yes)
			(effects
				(font
					(size 1 1)
					(thickness 0.15)
				)
			)
		)
		(sheetname "Root")
		(sheetfile "jetson-orin-baseboard-oculink-expansion.kicad_sch")
		(attr smd)
		(fp_rect
			(start -0.925 -0.47)
			(end 0.925 0.47)
			(stroke
				(width 0.05)
				(type default)
			)
			(fill none)
			(layer "F.CrtYd")
		)
		(fp_line
			(start -0.494 0.248)
			(end -0.494 -0.25)
			(stroke
				(width 0.15)
				(type solid)
			)
			(layer "F.Fab")
		)
		(fp_line
			(start 0.504 0.248)
			(end -0.494 0.248)
			(stroke
				(width 0.15)
				(type solid)
			)
			(layer "F.Fab")
		)
		(fp_line
			(start -0.494 -0.25)
			(end 0.504 -0.25)
			(stroke
				(width 0.15)
				(type solid)
			)
			(layer "F.Fab")
		)
		(fp_line
			(start 0.504 -0.25)
			(end 0.504 0.248)
			(stroke
				(width 0.15)
				(type solid)
			)
			(layer "F.Fab")
		)
		(fp_text user "Author: Antmicro"
			(at -0.939 3.399 90)
			(layer "F.Fab")
			(hide yes)
			(effects
				(font
					(size 0.7 0.7)
					(thickness 0.15)
				)
				(justify right top)
			)
		)
		(fp_text user "License: Apache-2.0"
			(at -0.939 5.799 90)
			(layer "F.Fab")
			(hide yes)
			(effects
				(font
					(size 0.7 0.7)
					(thickness 0.15)
				)
				(justify right top)
			)
		)
		(fp_text user "${REFERENCE}"
			(at -0.939 4.599 90)
			(layer "F.Fab")
			(hide yes)
			(effects
				(font
					(size 0.7 0.7)
					(thickness 0.15)
				)
				(justify right top)
			)
		)
		(pad "1" smd roundrect
			(at -0.48 0 270)
			(size 0.59 0.64)
			(layers "F.Cu" "F.Paste" "F.Mask")
			(roundrect_rratio 0.25)
			(net 63 "/PCIE_{O}_C.TX0+")
			(pintype "passive")
		)
		(pad "2" smd roundrect
			(at 0.48 0 270)
			(size 0.59 0.64)
			(layers "F.Cu" "F.Paste" "F.Mask")
			(roundrect_rratio 0.25)
			(net 72 "/PCIE_{O}_TX0+")
			(pintype "passive")
		)
	)
	(footprint "antmicro-footprints:TSOT23-6"
		(layer "F.Cu")
		(at 144.6 111.55 90)
		(property "Reference" "U4"
			(at 0 -1.9 90)
			(layer "F.SilkS")
			(effects
				(font
					(size 0.7 0.7)
					(thickness 0.15)
				)
				(justify left bottom)
			)
		)
		(property "Value" "~"
			(at 0 2.6 90)
			(layer "F.Fab")
			(effects
				(font
					(size 0.7 0.7)
					(thickness 0.15)
				)
				(justify left bottom)
			)
		)
		(property "Footprint" "antmicro-footprints:TSOT23-6"
			(at 0 0 90)
			(layer "F.Fab")
			(hide yes)
			(effects
				(font
					(size 1.27 1.27)
					(thickness 0.15)
				)
			)
		)
		(property "Datasheet" "https://www.mouser.com/datasheet/2/115/DIOD_S_A0008958405_1-2543193.pdf"
			(at 0 0 90)
			(layer "F.Fab")
			(hide yes)
			(effects
				(font
					(size 1.27 1.27)
					(thickness 0.15)
				)
			)
		)
		(property "Description" "Power Load Distribution Switch, High Side, Active High, 1 Output, 5.5 V, 3.6 A, 0.04 ohm, TSOT-26-6"
			(at 0 0 90)
			(layer "F.Fab")
			(hide yes)
			(effects
				(font
					(size 1.27 1.27)
					(thickness 0.15)
				)
			)
		)
		(property "MPN" "AP22615AWU-7"
			(at 0 0 90)
			(unlocked yes)
			(layer "F.Fab")
			(hide yes)
			(effects
				(font
					(size 1 1)
					(thickness 0.15)
				)
			)
		)
		(property "Manufacturer" "Diodes Incorporated"
			(at 0 0 90)
			(unlocked yes)
			(layer "F.Fab")
			(hide yes)
			(effects
				(font
					(size 1 1)
					(thickness 0.15)
				)
			)
		)
		(property "Author" "Antmicro"
			(at 0 0 90)
			(unlocked yes)
			(layer "F.Fab")
			(hide yes)
			(effects
				(font
					(size 1 1)
					(thickness 0.15)
				)
			)
		)
		(property "License" "Apache-2.0"
			(at 0 0 90)
			(unlocked yes)
			(layer "F.Fab")
			(hide yes)
			(effects
				(font
					(size 1 1)
					(thickness 0.15)
				)
			)
		)
		(sheetname "Root")
		(sheetfile "jetson-orin-baseboard-oculink-expansion.kicad_sch")
		(attr smd)
		(fp_line
			(start -1 -1.5)
			(end -1 -1.375)
			(stroke
				(width 0.15)
				(type solid)
			)
			(layer "F.SilkS")
		)
		(fp_line
			(start 1 -1.497)
			(end -1 -1.5)
			(stroke
				(width 0.15)
				(type solid)
			)
			(layer "F.SilkS")
		)
		(fp_line
			(start 1 -1.497)
			(end 1 -1.375)
			(stroke
				(width 0.15)
				(type solid)
			)
			(layer "F.SilkS")
		)
		(fp_line
			(start 1 1.55)
			(end 1 1.4)
			(stroke
				(width 0.15)
				(type solid)
			)
			(layer "F.SilkS")
		)
		(fp_line
			(start 1 1.55)
			(end -1 1.55)
			(stroke
				(width 0.15)
				(type solid)
			)
			(layer "F.SilkS")
		)
		(fp_line
			(start -1 1.55)
			(end -1 1.4)
			(stroke
				(width 0.15)
				(type solid)
			)
			(layer "F.SilkS")
		)
		(fp_circle
			(center -1.44 -1.5)
			(end -1.39 -1.5)
			(stroke
				(width 0.15)
				(type solid)
			)
			(fill solid)
			(layer "F.SilkS")
		)
		(fp_rect
			(start 1.93 -1.7)
			(end -1.93 1.7)
			(stroke
				(width 0.05)
				(type solid)
			)
			(fill none)
			(layer "F.CrtYd")
		)
		(fp_line
			(start -0.45 -1.521)
			(end -0.876 -1.096)
			(stroke
				(width 0.15)
				(type solid)
			)
			(layer "F.Fab")
		)
		(fp_rect
			(start 0.875 1.528)
			(end -0.875 -1.525)
			(stroke
				(width 0.15)
				(type solid)
			)
			(fill none)
			(layer "F.Fab")
		)
		(fp_text user "${REFERENCE}"
			(at -1.93 3.8 90)
			(layer "F.Fab")
			(hide yes)
			(effects
				(font
					(size 0.7 0.7)
					(thickness 0.15)
				)
				(justify left bottom)
			)
		)
		(fp_text user "Author: Antmicro"
			(at -1.93 5 90)
			(layer "F.Fab")
			(hide yes)
			(effects
				(font
					(size 0.7 0.7)
					(thickness 0.15)
				)
				(justify left bottom)
			)
		)
		(fp_text user "License: Apache-2.0"
			(at -1.93 6.199 90)
			(layer "F.Fab")
			(hide yes)
			(effects
				(font
					(size 0.7 0.7)
					(thickness 0.15)
				)
				(justify left bottom)
			)
		)
		(pad "1" smd rect
			(at -1.301 -0.947)
			(size 0.7 1.2)
			(layers "F.Cu" "F.Paste" "F.Mask")
			(net 134 "Net-(U4-OUT)")
			(pinfunction "OUT")
			(pintype "power_out")
		)
		(pad "2" smd rect
			(at -1.301 0.004)
			(size 0.7 1.2)
			(layers "F.Cu" "F.Paste" "F.Mask")
			(net 51 "GND")
			(pinfunction "GND")
			(pintype "power_in")
		)
		(pad "3" smd rect
			(at -1.301 0.954)
			(size 0.7 1.2)
			(layers "F.Cu" "F.Paste" "F.Mask")
			(net 136 "Net-(U4-FLG)")
			(pinfunction "FLG")
			(pintype "output")
		)
		(pad "4" smd rect
			(at 1.299 0.954)
			(size 0.7 1.2)
			(layers "F.Cu" "F.Paste" "F.Mask")
			(net 23 "+3V3")
			(pinfunction "EN")
			(pintype "input")
		)
		(pad "5" smd rect
			(at 1.299 0.004)
			(size 0.7 1.2)
			(layers "F.Cu" "F.Paste" "F.Mask")
			(net 137 "Net-(U4-ISET)")
			(pinfunction "ISET")
			(pintype "passive")
		)
		(pad "6" smd rect
			(at 1.299 -0.947)
			(size 0.7 1.2)
			(layers "F.Cu" "F.Paste" "F.Mask")
			(net 23 "+3V3")
			(pinfunction "IN")
			(pintype "power_in")
		)
	)
	(footprint "antmicro-footprints:Amphenol_G14A421211112HR"
		(layer "F.Cu")
		(at 119.92875 146.930466)
		(property "Reference" "J1"
			(at -9.52875 -4.330466 0)
			(unlocked yes)
			(layer "F.SilkS")
			(effects
				(font
					(size 0.7 0.7)
					(thickness 0.15)
				)
				(justify left bottom)
			)
		)
		(property "Value" "OCuLink_x4_Amphenol_G14A421211112HR"
			(at 0 6.385 0)
			(unlocked yes)
			(layer "F.Fab")
			(effects
				(font
					(size 0.7 0.7)
					(thickness 0.15)
				)
				(justify left bottom)
			)
		)
		(property "Footprint" "antmicro-footprints:Amphenol_G14A421211112HR"
			(at 0 0 0)
			(layer "F.Fab")
			(hide yes)
			(effects
				(font
					(size 1.27 1.27)
					(thickness 0.15)
				)
			)
		)
		(property "Datasheet" "https://cdn.amphenol-cs.com/media/wysiwyg/files/drawing/g14a421x1bxxxhr.pdf"
			(at 0 0 0)
			(layer "F.Fab")
			(hide yes)
			(effects
				(font
					(size 1.27 1.27)
					(thickness 0.15)
				)
			)
		)
		(property "Description" "I/O Connectors OCulink, Receptacle, 0.5mm pitch, 4X, R/A SMT with shell leg SMT type, 30U\" gold plating, LCP, black, T&R packing"
			(at 0 0 0)
			(layer "F.Fab")
			(hide yes)
			(effects
				(font
					(size 1.27 1.27)
					(thickness 0.15)
				)
			)
		)
		(property "Manufacturer" "Amphenol"
			(at 0 0 0)
			(unlocked yes)
			(layer "F.Fab")
			(hide yes)
			(effects
				(font
					(size 1 1)
					(thickness 0.15)
				)
			)
		)
		(property "MPN" "G14A421211112HR"
			(at 0 0 0)
			(unlocked yes)
			(layer "F.Fab")
			(hide yes)
			(effects
				(font
					(size 1 1)
					(thickness 0.15)
				)
			)
		)
		(property "Author" "Antmicro"
			(at 0 0 0)
			(unlocked yes)
			(layer "F.Fab")
			(hide yes)
			(effects
				(font
					(size 1 1)
					(thickness 0.15)
				)
			)
		)
		(property "License" "Apache-2.0"
			(at 0 0 0)
			(unlocked yes)
			(layer "F.Fab")
			(hide yes)
			(effects
				(font
					(size 1 1)
					(thickness 0.15)
				)
			)
		)
		(sheetname "Root")
		(sheetfile "jetson-orin-baseboard-oculink-expansion.kicad_sch")
		(solder_paste_margin -0.06)
		(attr smd)
		(fp_line
			(start -6.8 -0.4)
			(end -6.8 -3)
			(stroke
				(width 0.1)
				(type default)
			)
			(layer "F.SilkS")
		)
		(fp_line
			(start 6.8 -3)
			(end 6.8 -0.4)
			(stroke
				(width 0.1)
				(type default)
			)
			(layer "F.SilkS")
		)
		(fp_circle
			(center -5.3 -5.52)
			(end -5.25 -5.52)
			(stroke
				(width 0.15)
				(type solid)
			)
			(fill solid)
			(layer "F.SilkS")
		)
		(fp_rect
			(start -8.22 -5.22)
			(end 8.22 4.94)
			(stroke
				(width 0.05)
				(type solid)
			)
			(fill none)
			(layer "F.CrtYd")
		)
		(fp_line
			(start 7 3.065)
			(end -7 3.065)
			(stroke
				(width 0.1)
				(type default)
			)
			(layer "F.Fab")
		)
		(fp_text user "Author: Antmicro"
			(at -8.22 11.085 0)
			(layer "F.Fab")
			(hide yes)
			(effects
				(font
					(size 0.7 0.7)
					(thickness 0.15)
				)
				(justify left bottom)
			)
		)
		(fp_text user "License: Apache-2.0"
			(at -8.22 12.285 0)
			(layer "F.Fab")
			(hide yes)
			(effects
				(font
					(size 0.7 0.7)
					(thickness 0.15)
				)
				(justify left bottom)
			)
		)
		(fp_text user "PCB EDGE"
			(at 2.8 2.95 0)
			(unlocked yes)
			(layer "F.Fab")
			(effects
				(font
					(size 0.5 0.5)
					(thickness 0.125)
				)
				(justify left bottom)
			)
		)
		(fp_text user "${REFERENCE}"
			(at -8.22 9.885 0)
			(unlocked yes)
			(layer "F.Fab")
			(hide yes)
			(effects
				(font
					(size 0.7 0.7)
					(thickness 0.15)
				)
				(justify left bottom)
			)
		)
		(pad "" np_thru_hole circle
			(at -5.42 -1.395 90)
			(size 1 1)
			(drill 1)
			(layers "F&B.Cu" "*.Mask")
		)
		(pad "" np_thru_hole circle
			(at 5.95 -1.395 90)
			(size 1 1)
			(drill 1)
			(layers "F&B.Cu" "*.Mask")
		)
		(pad "A1" smd roundrect
			(at -4.75 -2.115 90)
			(size 0.91 0.31)
			(layers "F.Cu" "F.Paste" "F.Mask")
			(roundrect_rratio 0.5)
			(net 132 "+3V3_OCU")
			(pinfunction "V_{ACT}_RX_3V3")
			(pintype "power_in")
		)
		(pad "A2" smd roundrect
			(at -4.25 -2.115 90)
			(size 0.91 0.31)
			(layers "F.Cu" "F.Paste" "F.Mask")
			(roundrect_rratio 0.5)
			(net 51 "GND")
			(pinfunction "GND")
			(pintype "passive")
		)
		(pad "A3" smd roundrect
			(at -3.75 -2.115 90)
			(size 0.91 0.31)
			(layers "F.Cu" "F.Paste" "F.Mask")
			(roundrect_rratio 0.5)
			(net 81 "/PCIE_{O}_RX0+")
			(pinfunction "PER0+")
			(pintype "output")
		)
		(pad "A4" smd roundrect
			(at -3.25 -2.115 90)
			(size 0.91 0.31)
			(layers "F.Cu" "F.Paste" "F.Mask")
			(roundrect_rratio 0.5)
			(net 83 "/PCIE_{O}_RX0-")
			(pinfunction "PER0-")
			(pintype "output")
		)
		(pad "A5" smd roundrect
			(at -2.75 -2.115 90)
			(size 0.91 0.31)
			(layers "F.Cu" "F.Paste" "F.Mask")
			(roundrect_rratio 0.5)
			(net 51 "GND")
			(pinfunction "GND")
			(pintype "passive")
		)
		(pad "A6" smd roundrect
			(at -2.25 -2.115 90)
			(size 0.91 0.31)
			(layers "F.Cu" "F.Paste" "F.Mask")
			(roundrect_rratio 0.5)
			(net 82 "/PCIE_{O}_RX1+")
			(pinfunction "PER1+")
			(pintype "output")
		)
		(pad "A7" smd roundrect
			(at -1.75 -2.115 90)
			(size 0.91 0.31)
			(layers "F.Cu" "F.Paste" "F.Mask")
			(roundrect_rratio 0.5)
			(net 84 "/PCIE_{O}_RX1-")
			(pinfunction "PER1-")
			(pintype "output")
		)
		(pad "A8" smd roundrect
			(at -1.25 -2.115 90)
			(size 0.91 0.31)
			(layers "F.Cu" "F.Paste" "F.Mask")
			(roundrect_rratio 0.5)
			(net 51 "GND")
			(pinfunction "GND")
			(pintype "passive")
		)
		(pad "A9" smd roundrect
			(at -0.75 -2.115 90)
			(size 0.91 0.31)
			(layers "F.Cu" "F.Paste" "F.Mask")
			(roundrect_rratio 0.5)
			(net 6 "unconnected-(J1-NC-PadA9)")
			(pinfunction "NC")
			(pintype "no_connect")
		)
		(pad "A10" smd roundrect
			(at -0.25 -2.115 90)
			(size 0.91 0.31)
			(layers "F.Cu" "F.Paste" "F.Mask")
			(roundrect_rratio 0.5)
			(net 54 "Net-(J1-~{CWAKE})")
			(pinfunction "~{CWAKE}")
			(pintype "bidirectional")
		)
		(pad "A11" smd roundrect
			(at 0.25 -2.115 90)
			(size 0.91 0.31)
			(layers "F.Cu" "F.Paste" "F.Mask")
			(roundrect_rratio 0.5)
			(net 51 "GND")
			(pinfunction "GND")
			(pintype "passive")
		)
		(pad "A12" smd roundrect
			(at 0.75 -2.115 90)
			(size 0.91 0.31)
			(layers "F.Cu" "F.Paste" "F.Mask")
			(roundrect_rratio 0.5)
			(net 53 "/PCIE_CLK+")
			(pinfunction "VSP1")
			(pintype "bidirectional")
		)
		(pad "A13" smd roundrect
			(at 1.25 -2.115 90)
			(size 0.91 0.31)
			(layers "F.Cu" "F.Paste" "F.Mask")
			(roundrect_rratio 0.5)
			(net 55 "/PCIE_CLK-")
			(pinfunction "VSP2")
			(pintype "bidirectional")
		)
		(pad "A14" smd roundrect
			(at 1.75 -2.115 90)
			(size 0.91 0.31)
			(layers "F.Cu" "F.Paste" "F.Mask")
			(roundrect_rratio 0.5)
			(net 51 "GND")
			(pinfunction "GND")
			(pintype "passive")
		)
		(pad "A15" smd roundrect
			(at 2.25 -2.115 90)
			(size 0.91 0.31)
			(layers "F.Cu" "F.Paste" "F.Mask")
			(roundrect_rratio 0.5)
			(net 5 "unconnected-(J1-PER2+-PadA15)")
			(pinfunction "PER2+")
			(pintype "output+no_connect")
		)
		(pad "A16" smd roundrect
			(at 2.75 -2.115 90)
			(size 0.91 0.31)
			(layers "F.Cu" "F.Paste" "F.Mask")
			(roundrect_rratio 0.5)
			(net 7 "unconnected-(J1-PER2--PadA16)")
			(pinfunction "PER2-")
			(pintype "output+no_connect")
		)
		(pad "A17" smd roundrect
			(at 3.25 -2.115 90)
			(size 0.91 0.31)
			(layers "F.Cu" "F.Paste" "F.Mask")
			(roundrect_rratio 0.5)
			(net 51 "GND")
			(pinfunction "GND")
			(pintype "passive")
		)
		(pad "A18" smd roundrect
			(at 3.75 -2.115 90)
			(size 0.91 0.31)
			(layers "F.Cu" "F.Paste" "F.Mask")
			(roundrect_rratio 0.5)
			(net 2 "unconnected-(J1-PER3+-PadA18)")
			(pinfunction "PER3+")
			(pintype "output+no_connect")
		)
		(pad "A19" smd roundrect
			(at 4.25 -2.115 90)
			(size 0.91 0.31)
			(layers "F.Cu" "F.Paste" "F.Mask")
			(roundrect_rratio 0.5)
			(net 3 "unconnected-(J1-PER3--PadA19)")
			(pinfunction "PER3-")
			(pintype "output+no_connect")
		)
		(pad "A20" smd roundrect
			(at 4.75 -2.115 90)
			(size 0.91 0.31)
			(layers "F.Cu" "F.Paste" "F.Mask")
			(roundrect_rratio 0.5)
			(net 51 "GND")
			(pinfunction "GND")
			(pintype "passive")
		)
		(pad "A21" smd roundrect
			(at 5.25 -2.115 90)
			(size 0.91 0.31)
			(layers "F.Cu" "F.Paste" "F.Mask")
			(roundrect_rratio 0.5)
			(net 133 "+5V_OCU")
			(pinfunction "5V")
			(pintype "passive")
		)
		(pad "B1" smd roundrect
			(at -5.25 -4.305 90)
			(size 0.91 0.31)
			(layers "F.Cu" "F.Paste" "F.Mask")
			(roundrect_rratio 0.5)
			(net 133 "+5V_OCU")
			(pinfunction "5V")
			(pintype "passive")
			(teardrops
				(best_length_ratio 0.5)
				(max_length 1)
				(best_width_ratio 1)
				(max_width 2)
				(curve_points 5)
				(filter_ratio 0.9)
				(enabled no)
				(allow_two_segments yes)
				(prefer_zone_connections yes)
			)
		)
		(pad "B2" smd roundrect
			(at -4.75 -4.305 90)
			(size 0.91 0.31)
			(layers "F.Cu" "F.Paste" "F.Mask")
			(roundrect_rratio 0.5)
			(net 51 "GND")
			(pinfunction "GND")
			(pintype "passive")
		)
		(pad "B3" smd roundrect
			(at -4.25 -4.305 90)
			(size 0.91 0.31)
			(layers "F.Cu" "F.Paste" "F.Mask")
			(roundrect_rratio 0.5)
			(net 72 "/PCIE_{O}_TX0+")
			(pinfunction "PET0+")
			(pintype "input")
		)
		(pad "B4" smd roundrect
			(at -3.75 -4.305 90)
			(size 0.91 0.31)
			(layers "F.Cu" "F.Paste" "F.Mask")
			(roundrect_rratio 0.5)
			(net 56 "/PCIE_{O}_TX0-")
			(pinfunction "PET0-")
			(pintype "input")
		)
		(pad "B5" smd roundrect
			(at -3.25 -4.305 90)
			(size 0.91 0.31)
			(layers "F.Cu" "F.Paste" "F.Mask")
			(roundrect_rratio 0.5)
			(net 51 "GND")
			(pinfunction "GND")
			(pintype "passive")
		)
		(pad "B6" smd roundrect
			(at -2.75 -4.305 90)
			(size 0.91 0.31)
			(layers "F.Cu" "F.Paste" "F.Mask")
			(roundrect_rratio 0.5)
			(net 58 "/PCIE_{O}_TX1+")
			(pinfunction "PET1+")
			(pintype "input")
		)
		(pad "B7" smd roundrect
			(at -2.25 -4.305 90)
			(size 0.91 0.31)
			(layers "F.Cu" "F.Paste" "F.Mask")
			(roundrect_rratio 0.5)
			(net 62 "/PCIE_{O}_TX1-")
			(pinfunction "PET1-")
			(pintype "input")
		)
		(pad "B8" smd roundrect
			(at -1.75 -4.305 90)
			(size 0.91 0.31)
			(layers "F.Cu" "F.Paste" "F.Mask")
			(roundrect_rratio 0.5)
			(net 51 "GND")
			(pinfunction "GND")
			(pintype "passive")
		)
		(pad "B9" smd roundrect
			(at -1.25 -4.305 90)
			(size 0.91 0.31)
			(layers "F.Cu" "F.Paste" "F.Mask")
			(roundrect_rratio 0.5)
			(net 126 "Net-(J1-SCL)")
			(pinfunction "SCL")
			(pintype "bidirectional")
		)
		(pad "B10" smd roundrect
			(at -0.75 -4.305 90)
			(size 0.91 0.31)
			(layers "F.Cu" "F.Paste" "F.Mask")
			(roundrect_rratio 0.5)
			(net 125 "Net-(J1-SDA)")
			(pinfunction "SDA")
			(pintype "bidirectional")
		)
		(pad "B11" smd roundrect
			(at -0.25 -4.305 90)
			(size 0.91 0.31)
			(layers "F.Cu" "F.Paste" "F.Mask")
			(roundrect_rratio 0.5)
			(net 51 "GND")
			(pinfunction "GND")
			(pintype "passive")
		)
		(pad "B12" smd roundrect
			(at 0.25 -4.305 90)
			(size 0.91 0.31)
			(layers "F.Cu" "F.Paste" "F.Mask")
			(roundrect_rratio 0.5)
			(net 59 "/~{PCIE_RST}")
			(pinfunction "~{PERST}")
			(pintype "bidirectional")
		)
		(pad "B13" smd roundrect
			(at 0.75 -4.305 90)
			(size 0.91 0.31)
			(layers "F.Cu" "F.Paste" "F.Mask")
			(roundrect_rratio 0.5)
			(net 66 "Net-(J1-~{CPRSNT})")
			(pinfunction "~{CPRSNT}")
			(pintype "bidirectional")
		)
		(pad "B14" smd roundrect
			(at 1.25 -4.305 90)
			(size 0.91 0.31)
			(layers "F.Cu" "F.Paste" "F.Mask")
			(roundrect_rratio 0.5)
			(net 51 "GND")
			(pinfunction "GND")
			(pintype "passive")
		)
		(pad "B15" smd roundrect
			(at 1.75 -4.305 90)
			(size 0.91 0.31)
			(layers "F.Cu" "F.Paste" "F.Mask")
			(roundrect_rratio 0.5)
			(net 4 "unconnected-(J1-PET2+-PadB15)")
			(pinfunction "PET2+")
			(pintype "input+no_connect")
		)
		(pad "B16" smd roundrect
			(at 2.25 -4.305 90)
			(size 0.91 0.31)
			(layers "F.Cu" "F.Paste" "F.Mask")
			(roundrect_rratio 0.5)
			(net 9 "unconnected-(J1-PET2--PadB16)")
			(pinfunction "PET2-")
			(pintype "input+no_connect")
		)
		(pad "B17" smd roundrect
			(at 2.75 -4.305 90)
			(size 0.91 0.31)
			(layers "F.Cu" "F.Paste" "F.Mask")
			(roundrect_rratio 0.5)
			(net 51 "GND")
			(pinfunction "GND")
			(pintype "passive")
		)
		(pad "B18" smd roundrect
			(at 3.25 -4.305 90)
			(size 0.91 0.31)
			(layers "F.Cu" "F.Paste" "F.Mask")
			(roundrect_rratio 0.5)
			(net 8 "unconnected-(J1-PET3+-PadB18)")
			(pinfunction "PET3+")
			(pintype "input+no_connect")
		)
		(pad "B19" smd roundrect
			(at 3.75 -4.305 90)
			(size 0.91 0.31)
			(layers "F.Cu" "F.Paste" "F.Mask")
			(roundrect_rratio 0.5)
			(net 1 "unconnected-(J1-PET3--PadB19)")
			(pinfunction "PET3-")
			(pintype "input+no_connect")
		)
		(pad "B20" smd roundrect
			(at 4.25 -4.305 90)
			(size 0.91 0.31)
			(layers "F.Cu" "F.Paste" "F.Mask")
			(roundrect_rratio 0.5)
			(net 51 "GND")
			(pinfunction "GND")
			(pintype "passive")
		)
		(pad "B21" smd roundrect
			(at 4.75 -4.305 90)
			(size 0.91 0.31)
			(layers "F.Cu" "F.Paste" "F.Mask")
			(roundrect_rratio 0.5)
			(net 132 "+3V3_OCU")
			(pinfunction "V_{ACT}_TX_3V3")
			(pintype "power_in")
		)
		(pad "SH" smd roundrect
			(at -6.91 -3.915 90)
			(size 1.38 1.81)
			(layers "F.Cu" "F.Paste" "F.Mask")
			(roundrect_rratio 0.1)
			(net 51 "GND")
			(pinfunction "SH")
			(pintype "passive")
		)
		(pad "SH" smd roundrect
			(at -6.91 0.805 90)
			(size 1.81 1.8)
			(layers "F.Cu" "F.Paste" "F.Mask")
			(roundrect_rratio 0.1)
			(net 51 "GND")
			(pinfunction "SH")
			(pintype "passive")
		)
		(pad "SH" smd roundrect
			(at 6.91 -3.915 90)
			(size 1.38 1.81)
			(layers "F.Cu" "F.Paste" "F.Mask")
			(roundrect_rratio 0.1)
			(net 51 "GND")
			(pinfunction "SH")
			(pintype "passive")
		)
		(pad "SH" smd roundrect
			(at 6.91 0.805 90)
			(size 1.81 1.8)
			(layers "F.Cu" "F.Paste" "F.Mask")
			(roundrect_rratio 0.1)
			(net 51 "GND")
			(pinfunction "SH")
			(pintype "passive")
		)
	)
	(footprint "antmicro-footprints:C_0402_1005Metric"
		(layer "F.Cu")
		(at 141.247 142.516 -90)
		(descr "Capacitor SMD 0402")
		(tags "capacitor SMD 0402")
		(property "Reference" "C6"
			(at -1.397 1.747 90)
			(layer "F.SilkS")
			(effects
				(font
					(size 0.7 0.7)
					(thickness 0.15)
				)
				(justify right top)
			)
		)
		(property "Value" "C_100n_0402"
			(at -1.022927 2.155213 90)
			(layer "F.Fab")
			(effects
				(font
					(size 0.7 0.7)
					(thickness 0.15)
				)
				(justify right top)
			)
		)
		(property "Footprint" "antmicro-footprints:C_0402_1005Metric"
			(at 0 0 90)
			(layer "F.Fab")
			(hide yes)
			(effects
				(font
					(size 1.27 1.27)
					(thickness 0.15)
				)
			)
		)
		(property "Datasheet" "https://www.murata.com/products/productdetail?partno=GRM155R61H104KE14%23"
			(at 0 0 90)
			(layer "F.Fab")
			(hide yes)
			(effects
				(font
					(size 1.27 1.27)
					(thickness 0.15)
				)
			)
		)
		(property "Description" "SMD Multilayer Ceramic Capacitor, 0.1 µF, 50 V, 0402 [1005 Metric], ± 10%, X5R, GRM Series"
			(at 0 0 90)
			(layer "F.Fab")
			(hide yes)
			(effects
				(font
					(size 1.27 1.27)
					(thickness 0.15)
				)
			)
		)
		(property "MPN" "GRM155R61H104KE14D"
			(at 0 0 -90)
			(unlocked yes)
			(layer "F.Fab")
			(hide yes)
			(effects
				(font
					(size 1 1)
					(thickness 0.15)
				)
			)
		)
		(property "Manufacturer" "Murata"
			(at 0 0 -90)
			(unlocked yes)
			(layer "F.Fab")
			(hide yes)
			(effects
				(font
					(size 1 1)
					(thickness 0.15)
				)
			)
		)
		(property "License" "Apache-2.0"
			(at 0 0 -90)
			(unlocked yes)
			(layer "F.Fab")
			(hide yes)
			(effects
				(font
					(size 1 1)
					(thickness 0.15)
				)
			)
		)
		(property "Author" "Antmicro"
			(at 0 0 -90)
			(unlocked yes)
			(layer "F.Fab")
			(hide yes)
			(effects
				(font
					(size 1 1)
					(thickness 0.15)
				)
			)
		)
		(property "Val" "100n"
			(at 0 0 -90)
			(unlocked yes)
			(layer "F.Fab")
			(hide yes)
			(effects
				(font
					(size 1 1)
					(thickness 0.15)
				)
			)
		)
		(property "Voltage" "50V"
			(at 0 0 -90)
			(unlocked yes)
			(layer "F.Fab")
			(hide yes)
			(effects
				(font
					(size 1 1)
					(thickness 0.15)
				)
			)
		)
		(property "Dielectric" "X5R"
			(at 0 0 -90)
			(unlocked yes)
			(layer "F.Fab")
			(hide yes)
			(effects
				(font
					(size 1 1)
					(thickness 0.15)
				)
			)
		)
		(sheetname "Root")
		(sheetfile "jetson-orin-baseboard-oculink-expansion.kicad_sch")
		(attr smd)
		(fp_rect
			(start -0.925 -0.47)
			(end 0.925 0.47)
			(stroke
				(width 0.05)
				(type default)
			)
			(fill none)
			(layer "F.CrtYd")
		)
		(fp_line
			(start -0.494 0.248)
			(end -0.494 -0.25)
			(stroke
				(width 0.15)
				(type solid)
			)
			(layer "F.Fab")
		)
		(fp_line
			(start 0.504 0.248)
			(end -0.494 0.248)
			(stroke
				(width 0.15)
				(type solid)
			)
			(layer "F.Fab")
		)
		(fp_line
			(start -0.494 -0.25)
			(end 0.504 -0.25)
			(stroke
				(width 0.15)
				(type solid)
			)
			(layer "F.Fab")
		)
		(fp_line
			(start 0.504 -0.25)
			(end 0.504 0.248)
			(stroke
				(width 0.15)
				(type solid)
			)
			(layer "F.Fab")
		)
		(fp_text user "${REFERENCE}"
			(at -0.939 4.599 90)
			(layer "F.Fab")
			(hide yes)
			(effects
				(font
					(size 0.7 0.7)
					(thickness 0.15)
				)
				(justify right top)
			)
		)
		(fp_text user "License: Apache-2.0"
			(at -0.939 5.799 90)
			(layer "F.Fab")
			(hide yes)
			(effects
				(font
					(size 0.7 0.7)
					(thickness 0.15)
				)
				(justify right top)
			)
		)
		(fp_text user "Author: Antmicro"
			(at -0.939 3.399 90)
			(layer "F.Fab")
			(hide yes)
			(effects
				(font
					(size 0.7 0.7)
					(thickness 0.15)
				)
				(justify right top)
			)
		)
		(pad "1" smd roundrect
			(at -0.48 0 270)
			(size 0.59 0.64)
			(layers "F.Cu" "F.Paste" "F.Mask")
			(roundrect_rratio 0.25)
			(net 51 "GND")
			(pintype "passive")
		)
		(pad "2" smd roundrect
			(at 0.48 0 270)
			(size 0.59 0.64)
			(layers "F.Cu" "F.Paste" "F.Mask")
			(roundrect_rratio 0.25)
			(net 23 "+3V3")
			(pintype "passive")
		)
	)
	(footprint "antmicro-footprints:C_0402_1005Metric"
		(layer "F.Cu")
		(at 129.2 108.32 180)
		(descr "Capacitor SMD 0402")
		(tags "capacitor SMD 0402")
		(property "Reference" "C42"
			(at 0.9 0.37 0)
			(layer "F.SilkS")
			(effects
				(font
					(size 0.7 0.7)
					(thickness 0.15)
				)
				(justify right top)
			)
		)
		(property "Value" "C_220n_0402"
			(at -1.022927 2.155213 0)
			(layer "F.Fab")
			(effects
				(font
					(size 0.7 0.7)
					(thickness 0.15)
				)
				(justify right top)
			)
		)
		(property "Footprint" "antmicro-footprints:C_0402_1005Metric"
			(at 0 0 0)
			(layer "F.Fab")
			(hide yes)
			(effects
				(font
					(size 1.27 1.27)
					(thickness 0.15)
				)
			)
		)
		(property "Datasheet" "https://www.yageo.com/en/Chart/Download/pdf/CC0402KRX5R6BB224"
			(at 0 0 0)
			(layer "F.Fab")
			(hide yes)
			(effects
				(font
					(size 1.27 1.27)
					(thickness 0.15)
				)
			)
		)
		(property "Description" "SMD Multilayer Ceramic Capacitor, 0.22 µF, 10 V, 0402 [1005 Metric], ± 10%, X5R, CC Series"
			(at 0 0 0)
			(layer "F.Fab")
			(hide yes)
			(effects
				(font
					(size 1.27 1.27)
					(thickness 0.15)
				)
			)
		)
		(property "MPN" "CC0402KRX5R6BB224"
			(at 0 0 180)
			(unlocked yes)
			(layer "F.Fab")
			(hide yes)
			(effects
				(font
					(size 1 1)
					(thickness 0.15)
				)
			)
		)
		(property "Manufacturer" "YAGEO"
			(at 0 0 180)
			(unlocked yes)
			(layer "F.Fab")
			(hide yes)
			(effects
				(font
					(size 1 1)
					(thickness 0.15)
				)
			)
		)
		(property "License" "Apache-2.0"
			(at 0 0 180)
			(unlocked yes)
			(layer "F.Fab")
			(hide yes)
			(effects
				(font
					(size 1 1)
					(thickness 0.15)
				)
			)
		)
		(property "Author" "Antmicro"
			(at 0 0 180)
			(unlocked yes)
			(layer "F.Fab")
			(hide yes)
			(effects
				(font
					(size 1 1)
					(thickness 0.15)
				)
			)
		)
		(property "Val" "220n"
			(at 0 0 180)
			(unlocked yes)
			(layer "F.Fab")
			(hide yes)
			(effects
				(font
					(size 1 1)
					(thickness 0.15)
				)
			)
		)
		(property "Voltage" ""
			(at 0 0 180)
			(unlocked yes)
			(layer "F.Fab")
			(hide yes)
			(effects
				(font
					(size 1 1)
					(thickness 0.15)
				)
			)
		)
		(property "Dielectric" ""
			(at 0 0 180)
			(unlocked yes)
			(layer "F.Fab")
			(hide yes)
			(effects
				(font
					(size 1 1)
					(thickness 0.15)
				)
			)
		)
		(property "Public" "False"
			(at 0 0 180)
			(unlocked yes)
			(layer "F.Fab")
			(hide yes)
			(effects
				(font
					(size 1 1)
					(thickness 0.15)
				)
			)
		)
		(sheetname "Root")
		(sheetfile "jetson-orin-baseboard-oculink-expansion.kicad_sch")
		(attr smd)
		(fp_rect
			(start -0.925 -0.47)
			(end 0.925 0.47)
			(stroke
				(width 0.05)
				(type default)
			)
			(fill none)
			(layer "F.CrtYd")
		)
		(fp_line
			(start 0.504 0.248)
			(end -0.494 0.248)
			(stroke
				(width 0.15)
				(type solid)
			)
			(layer "F.Fab")
		)
		(fp_line
			(start 0.504 -0.25)
			(end 0.504 0.248)
			(stroke
				(width 0.15)
				(type solid)
			)
			(layer "F.Fab")
		)
		(fp_line
			(start -0.494 0.248)
			(end -0.494 -0.25)
			(stroke
				(width 0.15)
				(type solid)
			)
			(layer "F.Fab")
		)
		(fp_line
			(start -0.494 -0.25)
			(end 0.504 -0.25)
			(stroke
				(width 0.15)
				(type solid)
			)
			(layer "F.Fab")
		)
		(fp_text user "${REFERENCE}"
			(at -0.939 4.599 0)
			(layer "F.Fab")
			(hide yes)
			(effects
				(font
					(size 0.7 0.7)
					(thickness 0.15)
				)
				(justify right top)
			)
		)
		(fp_text user "Author: Antmicro"
			(at -0.939 3.399 0)
			(layer "F.Fab")
			(hide yes)
			(effects
				(font
					(size 0.7 0.7)
					(thickness 0.15)
				)
				(justify right top)
			)
		)
		(fp_text user "License: Apache-2.0"
			(at -0.939 5.799 0)
			(layer "F.Fab")
			(hide yes)
			(effects
				(font
					(size 0.7 0.7)
					(thickness 0.15)
				)
				(justify right top)
			)
		)
		(pad "1" smd roundrect
			(at -0.48 0 180)
			(size 0.59 0.64)
			(layers "F.Cu" "F.Paste" "F.Mask")
			(roundrect_rratio 0.25)
			(net 74 "/PCIE_{I}_RX0-")
			(pintype "passive")
		)
		(pad "2" smd roundrect
			(at 0.48 0 180)
			(size 0.59 0.64)
			(layers "F.Cu" "F.Paste" "F.Mask")
			(roundrect_rratio 0.25)
			(net 73 "/PCIE_{I}_C.RX0-")
			(pintype "passive")
		)
	)
	(footprint "antmicro-footprints:antmicro-logo_scaled_15mm"
		(layer "F.Cu")
		(at 114.2 98.8 90)
		(property "Reference" "N4"
			(at 0.1 -3 90)
			(layer "F.SilkS")
			(hide yes)
			(effects
				(font
					(size 0.7 0.7)
					(thickness 0.15)
				)
				(justify left bottom)
			)
		)
		(property "Value" "antmicro_logo"
			(at 0 3.1 90)
			(layer "F.Fab")
			(hide yes)
			(effects
				(font
					(size 0.7 0.7)
					(thickness 0.15)
				)
				(justify left bottom)
			)
		)
		(property "Footprint" "antmicro-footprints:antmicro-logo_scaled_15mm"
			(at 0 0 90)
			(layer "F.Fab")
			(hide yes)
			(effects
				(font
					(size 1.27 1.27)
					(thickness 0.15)
				)
			)
		)
		(property "Description" "Mechanical part"
			(at 0 0 90)
			(layer "F.Fab")
			(hide yes)
			(effects
				(font
					(size 1.27 1.27)
					(thickness 0.15)
				)
			)
		)
		(property "MPN" ""
			(at 0 0 90)
			(unlocked yes)
			(layer "F.Fab")
			(hide yes)
			(effects
				(font
					(size 1 1)
					(thickness 0.15)
				)
			)
		)
		(property "Manufacturer" ""
			(at 0 0 90)
			(unlocked yes)
			(layer "F.Fab")
			(hide yes)
			(effects
				(font
					(size 1 1)
					(thickness 0.15)
				)
			)
		)
		(property "Author" "Antmicro"
			(at 0 0 90)
			(unlocked yes)
			(layer "F.Fab")
			(hide yes)
			(effects
				(font
					(size 1 1)
					(thickness 0.15)
				)
			)
		)
		(property "License" "Apache-2.0"
			(at 0 0 90)
			(unlocked yes)
			(layer "F.Fab")
			(hide yes)
			(effects
				(font
					(size 1 1)
					(thickness 0.15)
				)
			)
		)
		(sheetname "Root")
		(sheetfile "jetson-orin-baseboard-oculink-expansion.kicad_sch")
		(attr exclude_from_pos_files exclude_from_bom allow_soldermask_bridges)
		(fp_poly
			(pts
				(xy 3.455 0.778) (xy 3.172 0.778) (xy 3.172 -0.9) (xy 3.455 -0.9) (xy 3.455 0.778)
			)
			(stroke
				(width 0.001395)
				(type solid)
			)
			(fill solid)
			(layer "F.Cu")
		)
		(fp_poly
			(pts
				(xy 5.669 -0.922) (xy 5.69 -0.919) (xy 5.698 -0.914) (xy 5.7 -0.912) (xy 5.695 -0.894) (xy 5.687 -0.86)
				(xy 5.674 -0.816) (xy 5.668 -0.798) (xy 5.652 -0.749) (xy 5.64 -0.72) (xy 5.629 -0.706) (xy 5.618 -0.704)
				(xy 5.616 -0.704) (xy 5.543 -0.72) (xy 5.461 -0.725) (xy 5.379 -0.72) (xy 5.309 -0.705) (xy 5.294 -0.7)
				(xy 5.262 -0.688) (xy 5.262 0.778) (xy 4.978 0.778) (xy 4.978 -0.814) (xy 5.065 -0.845) (xy 5.139 -0.87)
				(xy 5.206 -0.888) (xy 5.275 -0.903) (xy 5.349 -0.912) (xy 5.437 -0.918) (xy 5.501 -0.92) (xy 5.578 -0.923)
				(xy 5.632 -0.923) (xy 5.669 -0.922)
			)
			(stroke
				(width 0.001395)
				(type solid)
			)
			(fill solid)
			(layer "F.Cu")
		)
		(fp_poly
			(pts
				(xy 0.142 -1.349) (xy 0.144 -1.317) (xy 0.146 -1.27) (xy 0.147 -1.21) (xy 0.147 -1.139) (xy 0.147 -1.13)
				(xy 0.147 -0.9) (xy 0.431 -0.9) (xy 0.431 -0.71) (xy 0.147 -0.71) (xy 0.147 0.442) (xy 0.174 0.493)
				(xy 0.209 0.543) (xy 0.253 0.572) (xy 0.311 0.585) (xy 0.357 0.586) (xy 0.431 0.582) (xy 0.431 0.674)
				(xy 0.429 0.729) (xy 0.423 0.763) (xy 0.416 0.774) (xy 0.4 0.778) (xy 0.363 0.782) (xy 0.316 0.785)
				(xy 0.283 0.787) (xy 0.219 0.787) (xy 0.171 0.784) (xy 0.13 0.776) (xy 0.103 0.768) (xy 0.032 0.733)
				(xy -0.026 0.687) (xy -0.073 0.621) (xy -0.088 0.594) (xy -0.13 0.515) (xy -0.133 -0.099) (xy -0.137 -0.71)
				(xy -0.325 -0.71) (xy -0.325 -0.9) (xy -0.136 -0.9) (xy -0.136 -1.276) (xy -0.001 -1.319) (xy 0.051 -1.335)
				(xy 0.096 -1.349) (xy 0.126 -1.357) (xy 0.14 -1.361) (xy 0.142 -1.349)
			)
			(stroke
				(width 0.001395)
				(type solid)
			)
			(fill solid)
			(layer "F.Cu")
		)
		(fp_poly
			(pts
				(xy -1.069 -0.917) (xy -1.006 -0.916) (xy -0.958 -0.913) (xy -0.92 -0.907) (xy -0.886 -0.9) (xy -0.874 -0.895)
				(xy -0.767 -0.854) (xy -0.681 -0.804) (xy -0.613 -0.742) (xy -0.569 -0.679) (xy -0.556 -0.652) (xy -0.544 -0.626)
				(xy -0.534 -0.6) (xy -0.525 -0.572) (xy -0.519 -0.54) (xy -0.512 -0.499) (xy -0.508 -0.451) (xy -0.505 -0.391)
				(xy -0.503 -0.316) (xy -0.502 -0.229) (xy -0.501 -0.122) (xy -0.501 0.003) (xy -0.501 0.148) (xy -0.501 0.778)
				(xy -0.786 0.778) (xy -0.786 0.153) (xy -0.786 0.007) (xy -0.786 -0.118) (xy -0.787 -0.224) (xy -0.788 -0.311)
				(xy -0.79 -0.384) (xy -0.793 -0.442) (xy -0.798 -0.489) (xy -0.803 -0.527) (xy -0.81 -0.556) (xy -0.818 -0.578)
				(xy -0.829 -0.598) (xy -0.842 -0.615) (xy -0.857 -0.633) (xy -0.858 -0.634) (xy -0.908 -0.679) (xy -0.966 -0.709)
				(xy -1.043 -0.73) (xy -1.071 -0.734) (xy -1.149 -0.739) (xy -1.238 -0.735) (xy -1.323 -0.722) (xy -1.384 -0.706)
				(xy -1.428 -0.69) (xy -1.432 0.043) (xy -1.434 0.778) (xy -1.718 0.778) (xy -1.718 -0.814) (xy -1.609 -0.849)
				(xy -1.533 -0.873) (xy -1.47 -0.891) (xy -1.41 -0.904) (xy -1.351 -0.912) (xy -1.283 -0.916) (xy -1.2 -0.918)
				(xy -1.151 -0.918) (xy -1.069 -0.917)
			)
			(stroke
				(width 0.001395)
				(type solid)
			)
			(fill solid)
			(layer "F.Cu")
		)
		(fp_poly
			(pts
				(xy 2.363 -0.915) (xy 2.479 -0.889) (xy 2.577 -0.847) (xy 2.66 -0.791) (xy 2.726 -0.716) (xy 2.757 -0.664)
				(xy 2.77 -0.638) (xy 2.781 -0.613) (xy 2.789 -0.587) (xy 2.797 -0.559) (xy 2.802 -0.524) (xy 2.807 -0.481)
				(xy 2.811 -0.429) (xy 2.813 -0.366) (xy 2.815 -0.289) (xy 2.817 -0.197) (xy 2.818 -0.086) (xy 2.818 0.046)
				(xy 2.818 0.152) (xy 2.818 0.778) (xy 2.535 0.778) (xy 2.531 0.124) (xy 2.527 -0.528) (xy 2.494 -0.589)
				(xy 2.447 -0.652) (xy 2.386 -0.697) (xy 2.314 -0.727) (xy 2.236 -0.739) (xy 2.152 -0.735) (xy 2.071 -0.714)
				(xy 1.991 -0.677) (xy 1.935 -0.634) (xy 1.884 -0.59) (xy 1.884 0.778) (xy 1.6 0.778) (xy 1.6 0.139)
				(xy 1.6 -0.022) (xy 1.6 -0.159) (xy 1.598 -0.276) (xy 1.598 -0.369) (xy 1.596 -0.443) (xy 1.592 -0.497)
				(xy 1.59 -0.533) (xy 1.588 -0.547) (xy 1.556 -0.613) (xy 1.505 -0.667) (xy 1.439 -0.706) (xy 1.356 -0.73)
				(xy 1.259 -0.74) (xy 1.161 -0.735) (xy 1.108 -0.728) (xy 1.07 -0.722) (xy 1.038 -0.715) (xy 1.004 -0.704)
				(xy 0.983 -0.696) (xy 0.951 -0.685) (xy 0.951 0.778) (xy 0.68 0.778) (xy 0.68 -0.815) (xy 0.792 -0.852)
				(xy 0.919 -0.887) (xy 1.038 -0.911) (xy 1.157 -0.921) (xy 1.282 -0.921) (xy 1.381 -0.915) (xy 1.463 -0.904)
				(xy 1.533 -0.885) (xy 1.594 -0.858) (xy 1.653 -0.822) (xy 1.679 -0.805) (xy 1.755 -0.745) (xy 1.806 -0.787)
				(xy 1.9 -0.849) (xy 2.008 -0.892) (xy 2.128 -0.918) (xy 2.233 -0.923) (xy 2.363 -0.915)
			)
			(stroke
				(width 0.001395)
				(type solid)
			)
			(fill solid)
			(layer "F.Cu")
		)
		(fp_poly
			(pts
				(xy 6.504 -0.916) (xy 6.61 -0.891) (xy 6.703 -0.849) (xy 6.788 -0.791) (xy 6.828 -0.753) (xy 6.901 -0.663)
				(xy 6.961 -0.555) (xy 7.006 -0.43) (xy 7.034 -0.288) (xy 7.044 -0.197) (xy 7.049 -0.031) (xy 7.041 0.123)
				(xy 7.015 0.266) (xy 6.977 0.395) (xy 6.924 0.507) (xy 6.857 0.604) (xy 6.778 0.684) (xy 6.73 0.719)
				(xy 6.652 0.757) (xy 6.559 0.787) (xy 6.461 0.804) (xy 6.36 0.809) (xy 6.27 0.801) (xy 6.153 0.769)
				(xy 6.051 0.717) (xy 5.961 0.648) (xy 5.885 0.559) (xy 5.825 0.453) (xy 5.778 0.329) (xy 5.753 0.22)
				(xy 5.732 0.06) (xy 5.728 -0.068) (xy 6.01 -0.068) (xy 6.015 0.065) (xy 6.031 0.192) (xy 6.057 0.307)
				(xy 6.094 0.406) (xy 6.139 0.483) (xy 6.198 0.545) (xy 6.267 0.586) (xy 6.341 0.609) (xy 6.418 0.612)
				(xy 6.498 0.593) (xy 6.523 0.581) (xy 6.589 0.539) (xy 6.644 0.478) (xy 6.688 0.402) (xy 6.722 0.305)
				(xy 6.748 0.19) (xy 6.761 0.069) (xy 6.767 -0.079) (xy 6.761 -0.217) (xy 6.743 -0.344) (xy 6.714 -0.455)
				(xy 6.674 -0.55) (xy 6.624 -0.626) (xy 6.594 -0.66) (xy 6.526 -0.707) (xy 6.453 -0.733) (xy 6.377 -0.74)
				(xy 6.302 -0.727) (xy 6.232 -0.695) (xy 6.169 -0.646) (xy 6.116 -0.578) (xy 6.095 -0.541) (xy 6.059 -0.441)
				(xy 6.031 -0.326) (xy 6.015 -0.2) (xy 6.01 -0.068) (xy 5.728 -0.068) (xy 5.727 -0.094) (xy 5.738 -0.243)
				(xy 5.761 -0.382) (xy 5.801 -0.509) (xy 5.853 -0.622) (xy 5.919 -0.719) (xy 5.938 -0.741) (xy 6.023 -0.817)
				(xy 6.119 -0.872) (xy 6.227 -0.908) (xy 6.347 -0.923) (xy 6.384 -0.924) (xy 6.504 -0.916)
			)
			(stroke
				(width 0.001395)
				(type solid)
			)
			(fill solid)
			(layer "F.Cu")
		)
		(fp_poly
			(pts
				(xy 4.406 -0.922) (xy 4.483 -0.914) (xy 4.527 -0.906) (xy 4.571 -0.892) (xy 4.62 -0.875) (xy 4.664 -0.855)
				(xy 4.7 -0.837) (xy 4.722 -0.822) (xy 4.722 -0.82) (xy 4.722 -0.806) (xy 4.712 -0.777) (xy 4.7 -0.74)
				(xy 4.684 -0.703) (xy 4.671 -0.673) (xy 4.66 -0.656) (xy 4.658 -0.654) (xy 4.642 -0.658) (xy 4.613 -0.67)
				(xy 4.584 -0.683) (xy 4.493 -0.713) (xy 4.405 -0.725) (xy 4.32 -0.718) (xy 4.246 -0.692) (xy 4.184 -0.649)
				(xy 4.128 -0.583) (xy 4.078 -0.5) (xy 4.036 -0.403) (xy 4.019 -0.346) (xy 4.006 -0.277) (xy 3.996 -0.19)
				(xy 3.992 -0.096) (xy 3.994 0.001) (xy 3.999 0.092) (xy 4.011 0.172) (xy 4.019 0.212) (xy 4.059 0.33)
				(xy 4.11 0.425) (xy 4.171 0.501) (xy 4.243 0.557) (xy 4.248 0.56) (xy 4.285 0.577) (xy 4.315 0.588)
				(xy 4.352 0.592) (xy 4.403 0.593) (xy 4.405 0.593) (xy 4.459 0.591) (xy 4.506 0.583) (xy 4.554 0.567)
				(xy 4.608 0.543) (xy 4.65 0.521) (xy 4.655 0.524) (xy 4.663 0.54) (xy 4.677 0.569) (xy 4.698 0.616)
				(xy 4.724 0.684) (xy 4.727 0.689) (xy 4.719 0.702) (xy 4.695 0.72) (xy 4.66 0.74) (xy 4.615 0.76)
				(xy 4.568 0.778) (xy 4.557 0.782) (xy 4.493 0.796) (xy 4.416 0.804) (xy 4.336 0.808) (xy 4.264 0.805)
				(xy 4.235 0.801) (xy 4.19 0.79) (xy 4.137 0.771) (xy 4.086 0.748) (xy 3.988 0.687) (xy 3.904 0.607)
				(xy 3.833 0.508) (xy 3.777 0.393) (xy 3.734 0.258) (xy 3.721 0.193) (xy 3.71 0.116) (xy 3.704 0.024)
				(xy 3.704 -0.075) (xy 3.708 -0.176) (xy 3.716 -0.271) (xy 3.728 -0.353) (xy 3.737 -0.398) (xy 3.783 -0.529)
				(xy 3.845 -0.643) (xy 3.918 -0.738) (xy 4.006 -0.816) (xy 4.107 -0.874) (xy 4.187 -0.905) (xy 4.248 -0.917)
				(xy 4.325 -0.923) (xy 4.406 -0.922)
			)
			(stroke
				(width 0.001395)
				(type solid)
			)
			(fill solid)
			(layer "F.Cu")
		)
		(fp_poly
			(pts
				(xy -2.526 -0.916) (xy -2.452 -0.902) (xy -2.367 -0.875) (xy -2.298 -0.843) (xy -2.238 -0.801) (xy -2.21 -0.774)
				(xy -2.166 -0.72) (xy -2.129 -0.652) (xy -2.098 -0.576) (xy -2.085 -0.524) (xy -2.081 -0.496) (xy -2.08 -0.448)
				(xy -2.077 -0.38) (xy -2.076 -0.294) (xy -2.074 -0.194) (xy -2.073 -0.078) (xy -2.073 0.049) (xy -2.073 0.117)
				(xy -2.073 0.693) (xy -2.127 0.718) (xy -2.226 0.753) (xy -2.342 0.782) (xy -2.465 0.8) (xy -2.592 0.809)
				(xy -2.713 0.807) (xy -2.776 0.801) (xy -2.901 0.776) (xy -3.008 0.735) (xy -3.097 0.682) (xy -3.167 0.613)
				(xy -3.218 0.531) (xy -3.25 0.434) (xy -3.263 0.325) (xy -3.263 0.27) (xy -3.262 0.26) (xy -2.992 0.26)
				(xy -2.988 0.357) (xy -2.968 0.441) (xy -2.927 0.513) (xy -2.87 0.567) (xy -2.794 0.608) (xy -2.758 0.62)
				(xy -2.711 0.628) (xy -2.649 0.631) (xy -2.58 0.631) (xy -2.509 0.627) (xy -2.445 0.619) (xy -2.395 0.608)
				(xy -2.388 0.606) (xy -2.332 0.586) (xy -2.332 -0.157) (xy -2.4 -0.149) (xy -2.444 -0.142) (xy -2.5 -0.132)
				(xy -2.558 -0.118) (xy -2.577 -0.114) (xy -2.698 -0.076) (xy -2.798 -0.03) (xy -2.875 0.025) (xy -2.933 0.088)
				(xy -2.972 0.163) (xy -2.991 0.247) (xy -2.992 0.26) (xy -3.262 0.26) (xy -3.247 0.164) (xy -3.213 0.069)
				(xy -3.155 -0.015) (xy -3.124 -0.05) (xy -3.052 -0.105) (xy -2.961 -0.157) (xy -2.852 -0.204) (xy -2.73 -0.243)
				(xy -2.596 -0.276) (xy -2.453 -0.298) (xy -2.452 -0.298) (xy -2.33 -0.313) (xy -2.336 -0.413) (xy -2.35 -0.508)
				(xy -2.377 -0.584) (xy -2.419 -0.643) (xy -2.476 -0.686) (xy -2.552 -0.714) (xy -2.588 -0.722) (xy -2.685 -0.731)
				(xy -2.794 -0.723) (xy -2.908 -0.699) (xy -3.024 -0.661) (xy -3.033 -0.656) (xy -3.069 -0.642) (xy -3.097 -0.632)
				(xy -3.106 -0.631) (xy -3.113 -0.644) (xy -3.125 -0.672) (xy -3.138 -0.707) (xy -3.153 -0.745) (xy -3.163 -0.778)
				(xy -3.17 -0.798) (xy -3.17 -0.801) (xy -3.161 -0.808) (xy -3.135 -0.821) (xy -3.106 -0.835) (xy -3 -0.873)
				(xy -2.883 -0.902) (xy -2.76 -0.918) (xy -2.639 -0.923) (xy -2.526 -0.916)
			)
			(stroke
				(width 0.001395)
				(type solid)
			)
			(fill solid)
			(layer "F.Cu")
		)
		(fp_poly
			(pts
				(xy -5.818 -2.456) (xy -5.77 -2.444) (xy -5.768 -2.444) (xy -5.753 -2.436) (xy -5.72 -2.417) (xy -5.669 -2.388)
				(xy -5.603 -2.351) (xy -5.523 -2.307) (xy -5.433 -2.254) (xy -5.332 -2.198) (xy -5.225 -2.135) (xy -5.111 -2.07)
				(xy -4.992 -2.002) (xy -4.872 -1.934) (xy -4.75 -1.863) (xy -4.63 -1.795) (xy -4.515 -1.728) (xy -4.401 -1.662)
				(xy -4.297 -1.601) (xy -4.199 -1.545) (xy -4.113 -1.494) (xy -4.037 -1.45) (xy -3.976 -1.416) (xy -3.931 -1.388)
				(xy -3.903 -1.371) (xy -3.899 -1.369) (xy -3.85 -1.329) (xy -3.811 -1.279) (xy -3.779 -1.224) (xy -3.775 -0.099)
				(xy -3.775 0.117) (xy -3.775 0.311) (xy -3.775 0.484) (xy -3.775 0.635) (xy -3.776 0.764) (xy -3.778 0.872)
				(xy -3.779 0.956) (xy -3.782 1.018) (xy -3.783 1.058) (xy -3.784 1.072) (xy -3.79 1.09) (xy -3.794 1.106)
				(xy -3.802 1.122) (xy -3.81 1.136) (xy -3.824 1.153) (xy -3.843 1.171) (xy -3.868 1.191) (xy -3.9 1.215)
				(xy -3.943 1.245) (xy -3.995 1.277) (xy -4.058 1.316) (xy -4.133 1.362) (xy -4.223 1.415) (xy -4.327 1.475)
				(xy -4.449 1.546) (xy -4.587 1.625) (xy -4.744 1.717) (xy -4.813 1.757) (xy -5.763 2.306) (xy -5.853 2.31)
				(xy -5.941 2.314) (xy -6.289 2.115) (xy -6.502 1.991) (xy -6.696 1.88) (xy -6.872 1.779) (xy -7.029 1.689)
				(xy -7.17 1.608) (xy -7.295 1.534) (xy -7.406 1.471) (xy -7.502 1.413) (xy -7.587 1.364) (xy -7.659 1.32)
				(xy -7.72 1.284) (xy -7.77 1.25) (xy -7.813 1.223) (xy -7.846 1.199) (xy -7.874 1.179) (xy -7.893 1.163)
				(xy -7.909 1.147) (xy -7.92 1.133) (xy -7.927 1.122) (xy -7.933 1.11) (xy -7.936 1.098) (xy -7.939 1.084)
				(xy -7.943 1.072) (xy -7.946 1.05) (xy -7.947 1.006) (xy -7.949 0.939) (xy -7.951 0.849) (xy -7.951 0.737)
				(xy -7.951 0.603) (xy -7.952 0.446) (xy -7.952 0.269) (xy -7.952 0.07) (xy -7.951 -0.072) (xy -7.223 -0.072)
				(xy -7.223 0.081) (xy -7.221 0.212) (xy -7.221 0.324) (xy -7.22 0.417) (xy -7.22 0.494) (xy -7.217 0.557)
				(xy -7.215 0.606) (xy -7.212 0.646) (xy -7.207 0.675) (xy -7.201 0.697) (xy -7.193 0.713) (xy -7.185 0.726)
				(xy -7.175 0.737) (xy -7.162 0.747) (xy -7.161 0.748) (xy -7.145 0.759) (xy -7.111 0.781) (xy -7.061 0.811)
				(xy -6.997 0.848) (xy -6.922 0.892) (xy -6.837 0.942) (xy -6.745 0.995) (xy -6.649 1.052) (xy -6.55 1.108)
				(xy -6.451 1.167) (xy -6.353 1.223) (xy -6.258 1.276) (xy -6.17 1.326) (xy -6.092 1.37) (xy -6.023 1.409)
				(xy -5.967 1.439) (xy -5.927 1.461) (xy -5.903 1.473) (xy -5.901 1.475) (xy -5.87 1.483) (xy -5.85 1.483)
				(xy -5.826 1.475) (xy -5.811 1.469) (xy -5.792 1.459) (xy -5.754 1.439) (xy -5.701 1.409) (xy -5.635 1.372)
				(xy -5.558 1.328) (xy -5.473 1.28) (xy -5.379 1.227) (xy -5.282 1.171) (xy -5.183 1.114) (xy -5.084 1.056)
				(xy -4.987 0.999) (xy -4.895 0.946) (xy -4.81 0.897) (xy -4.734 0.851) (xy -4.67 0.813) (xy -4.619 0.783)
				(xy -4.584 0.761) (xy -4.566 0.749) (xy -4.553 0.738) (xy -4.544 0.727) (xy -4.534 0.714) (xy -4.528 0.698)
				(xy -4.521 0.677) (xy -4.516 0.648) (xy -4.513 0.609) (xy -4.51 0.562) (xy -4.508 0.499) (xy -4.507 0.423)
				(xy -4.507 0.332) (xy -4.505 0.221) (xy -4.505 0.091) (xy -4.505 -0.059) (xy -4.505 -0.072) (xy -4.505 -0.228)
				(xy -4.505 -0.359) (xy -4.507 -0.471) (xy -4.507 -0.565) (xy -4.508 -0.644) (xy -4.51 -0.706) (xy -4.513 -0.756)
				(xy -4.518 -0.796) (xy -4.523 -0.825) (xy -4.529 -0.847) (xy -4.537 -0.864) (xy -4.547 -0.877) (xy -4.558 -0.887)
				(xy -4.572 -0.899) (xy -4.579 -0.903) (xy -4.595 -0.914) (xy -4.632 -0.936) (xy -4.683 -0.966) (xy -4.75 -1.005)
				(xy -4.83 -1.053) (xy -4.92 -1.105) (xy -5.02 -1.162) (xy -5.127 -1.224) (xy -5.215 -1.275) (xy -5.342 -1.349)
				(xy -5.451 -1.412) (xy -5.544 -1.464) (xy -5.619 -1.506) (xy -5.683 -1.541) (xy -5.733 -1.569) (xy -5.773 -1.589)
				(xy -5.802 -1.603) (xy -5.826 -1.613) (xy -5.843 -1.617) (xy -5.858 -1.621) (xy -5.862 -1.621) (xy -5.874 -1.619)
				(xy -5.89 -1.615) (xy -5.911 -1.607) (xy -5.938 -1.595) (xy -5.973 -1.579) (xy -6.018 -1.555) (xy -6.074 -1.523)
				(xy -6.144 -1.484) (xy -6.228 -1.438) (xy -6.329 -1.379) (xy -6.446 -1.313) (xy -6.528 -1.264) (xy -6.64 -1.2)
				(xy -6.745 -1.139) (xy -6.842 -1.083) (xy -6.931 -1.031) (xy -7.008 -0.985) (xy -7.072 -0.947) (xy -7.122 -0.919)
				(xy -7.154 -0.899) (xy -7.167 -0.889) (xy -7.178 -0.879) (xy -7.188 -0.869) (xy -7.196 -0.856) (xy -7.202 -0.839)
				(xy -7.207 -0.817) (xy -7.212 -0.787) (xy -7.215 -0.746) (xy -7.217 -0.694) (xy -7.22 -0.63) (xy -7.22 -0.552)
				(xy -7.221 -0.455) (xy -7.221 -0.341) (xy -7.223 -0.205) (xy -7.223 -0.072) (xy -7.951 -0.072) (xy -7.951 -0.099)
				(xy -7.951 -0.29) (xy -7.951 -0.46) (xy -7.951 -0.607) (xy -7.949 -0.736) (xy -7.949 -0.848) (xy -7.947 -0.943)
				(xy -7.946 -1.023) (xy -7.944 -1.089) (xy -7.941 -1.143) (xy -7.938 -1.188) (xy -7.934 -1.222) (xy -7.93 -1.248)
				(xy -7.925 -1.268) (xy -7.917 -1.285) (xy -7.909 -1.297) (xy -7.901 -1.307) (xy -7.89 -1.315) (xy -7.878 -1.327)
				(xy -7.874 -1.331) (xy -7.858 -1.341) (xy -7.824 -1.363) (xy -7.773 -1.393) (xy -7.705 -1.434) (xy -7.624 -1.484)
				(xy -7.528 -1.539) (xy -7.422 -1.601) (xy -7.305 -1.67) (xy -7.18 -1.742) (xy -7.048 -1.819) (xy -6.911 -1.898)
				(xy -6.896 -1.907) (xy -6.736 -2) (xy -6.595 -2.081) (xy -6.473 -2.153) (xy -6.366 -2.214) (xy -6.273 -2.266)
				(xy -6.196 -2.311) (xy -6.13 -2.347) (xy -6.076 -2.376) (xy -6.031 -2.4) (xy -5.995 -2.419) (xy -5.967 -2.432)
				(xy -5.944 -2.443) (xy -5.927 -2.448) (xy -5.911 -2.452) (xy -5.898 -2.456) (xy -5.885 -2.456) (xy -5.882 -2.456)
				(xy -5.818 -2.456)
			)
			(stroke
				(width 0.001395)
				(type solid)
			)
			(fill solid)
			(layer "F.Cu")
		)
		(fp_poly
			(pts
				(xy -5.8 -1.041) (xy -5.789 -1.037) (xy -5.736 -1.001) (xy -5.696 -0.951) (xy -5.673 -0.891) (xy -5.672 -0.827)
				(xy -5.675 -0.813) (xy -5.697 -0.751) (xy -5.739 -0.706) (xy -5.779 -0.682) (xy -5.829 -0.658) (xy -5.829 -0.38)
				(xy -5.622 -0.38) (xy -5.537 -0.465) (xy -5.452 -0.549) (xy -5.459 -0.609) (xy -5.459 -0.61) (xy -5.379 -0.61)
				(xy -5.366 -0.583) (xy -5.337 -0.57) (xy -5.305 -0.573) (xy -5.281 -0.587) (xy -5.263 -0.615) (xy -5.27 -0.644)
				(xy -5.286 -0.664) (xy -5.308 -0.683) (xy -5.326 -0.685) (xy -5.351 -0.671) (xy -5.353 -0.669) (xy -5.374 -0.643)
				(xy -5.379 -0.61) (xy -5.459 -0.61) (xy -5.46 -0.649) (xy -5.455 -0.675) (xy -5.441 -0.699) (xy -5.433 -0.707)
				(xy -5.39 -0.744) (xy -5.343 -0.76) (xy -5.295 -0.759) (xy -5.252 -0.743) (xy -5.215 -0.714) (xy -5.191 -0.674)
				(xy -5.183 -0.624) (xy -5.191 -0.575) (xy -5.217 -0.529) (xy -5.26 -0.498) (xy -5.316 -0.486) (xy -5.326 -0.486)
				(xy -5.351 -0.485) (xy -5.372 -0.481) (xy -5.393 -0.47) (xy -5.419 -0.451) (xy -5.454 -0.418) (xy -5.483 -0.392)
				(xy -5.584 -0.297) (xy -5.829 -0.297) (xy -5.829 -0.108) (xy -5.38 -0.108) (xy -5.362 -0.142) (xy -5.33 -0.18)
				(xy -5.286 -0.204) (xy -5.236 -0.21) (xy -5.188 -0.201) (xy -5.145 -0.172) (xy -5.141 -0.169) (xy -5.111 -0.12)
				(xy -5.1 -0.071) (xy -5.108 -0.026) (xy -5.129 0.016) (xy -5.164 0.046) (xy -5.207 0.065) (xy -5.255 0.068)
				(xy -5.308 0.05) (xy -5.318 0.044) (xy -5.346 0.024) (xy -5.364 0.002) (xy -5.364 -0.002) (xy -5.367 -0.01)
				(xy -5.374 -0.016) (xy -5.39 -0.02) (xy -5.414 -0.023) (xy -5.451 -0.024) (xy -5.507 -0.026) (xy -5.58 -0.026)
				(xy -5.6 -0.026) (xy -5.829 -0.026) (xy -5.829 0.151) (xy -5.585 0.151) (xy -5.39 0.348) (xy -5.334 0.343)
				(xy -5.276 0.347) (xy -5.229 0.37) (xy -5.197 0.411) (xy -5.189 0.433) (xy -5.181 0.489) (xy -5.196 0.539)
				(xy -5.225 0.577) (xy -5.27 0.609) (xy -5.319 0.62) (xy -5.366 0.614) (xy -5.409 0.591) (xy -5.439 0.555)
				(xy -5.457 0.506) (xy -5.459 0.47) (xy -5.377 0.47) (xy -5.374 0.5) (xy -5.362 0.518) (xy -5.335 0.538)
				(xy -5.31 0.537) (xy -5.286 0.518) (xy -5.265 0.488) (xy -5.266 0.463) (xy -5.284 0.441) (xy -5.313 0.426)
				(xy -5.342 0.429) (xy -5.366 0.445) (xy -5.377 0.47) (xy -5.459 0.47) (xy -5.459 0.46) (xy -5.451 0.404)
				(xy -5.622 0.234) (xy -5.829 0.234) (xy -5.829 0.514) (xy -5.779 0.536) (xy -5.728 0.57) (xy -5.693 0.617)
				(xy -5.675 0.674) (xy -5.67 0.731) (xy -5.685 0.789) (xy -5.713 0.838) (xy -5.76 0.878) (xy -5.77 0.884)
				(xy -5.832 0.904) (xy -5.898 0.904) (xy -5.959 0.884) (xy -5.96 0.883) (xy -6.008 0.845) (xy -6.04 0.797)
				(xy -6.055 0.74) (xy -6.055 0.712) (xy -5.975 0.712) (xy -5.97 0.747) (xy -5.952 0.776) (xy -5.936 0.791)
				(xy -5.893 0.818) (xy -5.85 0.822) (xy -5.806 0.804) (xy -5.79 0.791) (xy -5.765 0.761) (xy -5.753 0.731)
				(xy -5.752 0.712) (xy -5.763 0.67) (xy -5.792 0.632) (xy -5.829 0.607) (xy -5.864 0.6) (xy -5.906 0.61)
				(xy -5.943 0.638) (xy -5.967 0.678) (xy -5.975 0.712) (xy -6.055 0.712) (xy -6.055 0.682) (xy -6.037 0.625)
				(xy -6.004 0.576) (xy -5.957 0.54) (xy -5.947 0.536) (xy -5.899 0.514) (xy -5.899 0.234) (xy -6.106 0.234)
				(xy -6.276 0.404) (xy -6.269 0.46) (xy -6.271 0.516) (xy -6.292 0.562) (xy -6.326 0.596) (xy -6.369 0.616)
				(xy -6.417 0.62) (xy -6.465 0.605) (xy -6.502 0.577) (xy -6.536 0.533) (xy -6.547 0.482) (xy -6.544 0.468)
				(xy -6.463 0.468) (xy -6.46 0.493) (xy -6.443 0.518) (xy -6.414 0.539) (xy -6.388 0.537) (xy -6.366 0.519)
				(xy -6.351 0.487) (xy -6.356 0.457) (xy -6.375 0.433) (xy -6.39 0.427) (xy -6.425 0.429) (xy -6.443 0.441)
				(xy -6.463 0.468) (xy -6.544 0.468) (xy -6.537 0.433) (xy -6.512 0.386) (xy -6.473 0.355) (xy -6.419 0.343)
				(xy -6.393 0.343) (xy -6.338 0.348) (xy -6.141 0.151) (xy -5.899 0.151) (xy -5.899 -0.026) (xy -6.128 -0.026)
				(xy -6.207 -0.026) (xy -6.266 -0.026) (xy -6.308 -0.023) (xy -6.335 -0.022) (xy -6.351 -0.018) (xy -6.361 -0.012)
				(xy -6.364 -0.004) (xy -6.366 -0.001) (xy -6.385 0.025) (xy -6.419 0.05) (xy -6.46 0.066) (xy -6.487 0.069)
				(xy -6.542 0.058) (xy -6.584 0.033) (xy -6.614 -0.007) (xy -6.627 -0.054) (xy -6.625 -0.071) (xy -6.547 -0.071)
				(xy -6.544 -0.053) (xy -6.531 -0.038) (xy -6.5 -0.018) (xy -6.47 -0.018) (xy -6.449 -0.032) (xy -6.433 -0.062)
				(xy -6.435 -0.083) (xy -5.295 -0.083) (xy -5.29 -0.05) (xy -5.278 -0.032) (xy -5.249 -0.015) (xy -5.217 -0.022)
				(xy -5.196 -0.038) (xy -5.181 -0.058) (xy -5.183 -0.075) (xy -5.191 -0.094) (xy -5.217 -0.121) (xy -5.247 -0.13)
				(xy -5.276 -0.117) (xy -5.278 -0.115) (xy -5.295 -0.083) (xy -6.435 -0.083) (xy -6.438 -0.094) (xy -6.454 -0.114)
				(xy -6.483 -0.13) (xy -6.512 -0.122) (xy -6.536 -0.094) (xy -6.547 -0.071) (xy -6.625 -0.071) (xy -6.622 -0.104)
				(xy -6.598 -0.153) (xy -6.587 -0.169) (xy -6.544 -0.2) (xy -6.495 -0.211) (xy -6.444 -0.204) (xy -6.399 -0.18)
				(xy -6.367 -0.143) (xy -6.346 -0.108) (xy -5.899 -0.108) (xy -5.899 -0.297) (xy -6.143 -0.297) (xy -6.244 -0.392)
				(xy -6.289 -0.432) (xy -6.319 -0.46) (xy -6.342 -0.475) (xy -6.364 -0.483) (xy -6.385 -0.486) (xy -6.404 -0.486)
				(xy -6.462 -0.494) (xy -6.504 -0.521) (xy -6.532 -0.565) (xy -6.539 -0.58) (xy -6.544 -0.623) (xy -6.467 -0.623)
				(xy -6.457 -0.596) (xy -6.431 -0.577) (xy -6.399 -0.569) (xy -6.37 -0.576) (xy -6.362 -0.583) (xy -6.348 -0.611)
				(xy -6.353 -0.643) (xy -6.374 -0.669) (xy -6.396 -0.683) (xy -6.409 -0.688) (xy -6.427 -0.679) (xy -6.447 -0.658)
				(xy -6.462 -0.634) (xy -6.467 -0.623) (xy -6.544 -0.623) (xy -6.544 -0.635) (xy -6.532 -0.684) (xy -6.505 -0.722)
				(xy -6.467 -0.748) (xy -6.422 -0.761) (xy -6.374 -0.759) (xy -6.327 -0.738) (xy -6.294 -0.707) (xy -6.276 -0.682)
				(xy -6.268 -0.658) (xy -6.268 -0.623) (xy -6.268 -0.609) (xy -6.276 -0.549) (xy -6.191 -0.465) (xy -6.106 -0.38)
				(xy -5.899 -0.38) (xy -5.899 -0.659) (xy -5.946 -0.68) (xy -6.002 -0.715) (xy -6.039 -0.766) (xy -6.052 -0.806)
				(xy -6.058 -0.86) (xy -5.978 -0.86) (xy -5.973 -0.833) (xy -5.965 -0.813) (xy -5.935 -0.773) (xy -5.895 -0.75)
				(xy -5.85 -0.748) (xy -5.805 -0.767) (xy -5.8 -0.772) (xy -5.765 -0.809) (xy -5.752 -0.849) (xy -5.762 -0.892)
				(xy -5.79 -0.938) (xy -5.829 -0.962) (xy -5.87 -0.968) (xy -5.912 -0.956) (xy -5.949 -0.926) (xy -5.97 -0.889)
				(xy -5.978 -0.86) (xy -6.058 -0.86) (xy -6.06 -0.868) (xy -6.045 -0.928) (xy -6.015 -0.977) (xy -5.973 -1.017)
				(xy -5.92 -1.043) (xy -5.861 -1.053) (xy -5.8 -1.041)
			)
			(stroke
				(width 0.001395)
				(type solid)
			)
			(fill solid)
			(layer "F.Cu")
		)
		(fp_poly
			(pts
				(xy 3.455 0.778) (xy 3.172 0.778) (xy 3.172 -0.9) (xy 3.455 -0.9) (xy 3.455 0.778)
			)
			(stroke
				(width 0.001395)
				(type solid)
			)
			(fill solid)
			(layer "F.Mask")
		)
		(fp_poly
			(pts
				(xy 5.669 -0.922) (xy 5.69 -0.919) (xy 5.698 -0.914) (xy 5.7 -0.912) (xy 5.695 -0.894) (xy 5.687 -0.86)
				(xy 5.674 -0.816) (xy 5.668 -0.798) (xy 5.652 -0.749) (xy 5.64 -0.72) (xy 5.629 -0.706) (xy 5.618 -0.704)
				(xy 5.616 -0.704) (xy 5.543 -0.72) (xy 5.461 -0.725) (xy 5.379 -0.72) (xy 5.309 -0.705) (xy 5.294 -0.7)
				(xy 5.262 -0.688) (xy 5.262 0.778) (xy 4.978 0.778) (xy 4.978 -0.814) (xy 5.065 -0.845) (xy 5.139 -0.87)
				(xy 5.206 -0.888) (xy 5.275 -0.903) (xy 5.349 -0.912) (xy 5.437 -0.918) (xy 5.501 -0.92) (xy 5.578 -0.923)
				(xy 5.632 -0.923) (xy 5.669 -0.922)
			)
			(stroke
				(width 0.001395)
				(type solid)
			)
			(fill solid)
			(layer "F.Mask")
		)
		(fp_poly
			(pts
				(xy 0.142 -1.349) (xy 0.144 -1.317) (xy 0.146 -1.27) (xy 0.147 -1.21) (xy 0.147 -1.139) (xy 0.147 -1.13)
				(xy 0.147 -0.9) (xy 0.431 -0.9) (xy 0.431 -0.71) (xy 0.147 -0.71) (xy 0.147 0.442) (xy 0.174 0.493)
				(xy 0.209 0.543) (xy 0.253 0.572) (xy 0.311 0.585) (xy 0.357 0.586) (xy 0.431 0.582) (xy 0.431 0.674)
				(xy 0.429 0.729) (xy 0.423 0.763) (xy 0.416 0.774) (xy 0.4 0.778) (xy 0.363 0.782) (xy 0.316 0.785)
				(xy 0.283 0.787) (xy 0.219 0.787) (xy 0.171 0.784) (xy 0.13 0.776) (xy 0.103 0.768) (xy 0.032 0.733)
				(xy -0.026 0.687) (xy -0.073 0.621) (xy -0.088 0.594) (xy -0.13 0.515) (xy -0.133 -0.099) (xy -0.137 -0.71)
				(xy -0.325 -0.71) (xy -0.325 -0.9) (xy -0.136 -0.9) (xy -0.136 -1.276) (xy -0.001 -1.319) (xy 0.051 -1.335)
				(xy 0.096 -1.349) (xy 0.126 -1.357) (xy 0.14 -1.361) (xy 0.142 -1.349)
			)
			(stroke
				(width 0.001395)
				(type solid)
			)
			(fill solid)
			(layer "F.Mask")
		)
		(fp_poly
			(pts
				(xy -1.069 -0.917) (xy -1.006 -0.916) (xy -0.958 -0.913) (xy -0.92 -0.907) (xy -0.886 -0.9) (xy -0.874 -0.895)
				(xy -0.767 -0.854) (xy -0.681 -0.804) (xy -0.613 -0.742) (xy -0.569 -0.679) (xy -0.556 -0.652) (xy -0.544 -0.626)
				(xy -0.534 -0.6) (xy -0.525 -0.572) (xy -0.519 -0.54) (xy -0.512 -0.499) (xy -0.508 -0.451) (xy -0.505 -0.391)
				(xy -0.503 -0.316) (xy -0.502 -0.229) (xy -0.501 -0.122) (xy -0.501 0.003) (xy -0.501 0.148) (xy -0.501 0.778)
				(xy -0.786 0.778) (xy -0.786 0.153) (xy -0.786 0.007) (xy -0.786 -0.118) (xy -0.787 -0.224) (xy -0.788 -0.311)
				(xy -0.79 -0.384) (xy -0.793 -0.442) (xy -0.798 -0.489) (xy -0.803 -0.527) (xy -0.81 -0.556) (xy -0.818 -0.578)
				(xy -0.829 -0.598) (xy -0.842 -0.615) (xy -0.857 -0.633) (xy -0.858 -0.634) (xy -0.908 -0.679) (xy -0.966 -0.709)
				(xy -1.043 -0.73) (xy -1.071 -0.734) (xy -1.149 -0.739) (xy -1.238 -0.735) (xy -1.323 -0.722) (xy -1.384 -0.706)
				(xy -1.428 -0.69) (xy -1.432 0.043) (xy -1.434 0.778) (xy -1.718 0.778) (xy -1.718 -0.814) (xy -1.609 -0.849)
				(xy -1.533 -0.873) (xy -1.47 -0.891) (xy -1.41 -0.904) (xy -1.351 -0.912) (xy -1.283 -0.916) (xy -1.2 -0.918)
				(xy -1.151 -0.918) (xy -1.069 -0.917)
			)
			(stroke
				(width 0.001395)
				(type solid)
			)
			(fill solid)
			(layer "F.Mask")
		)
		(fp_poly
			(pts
				(xy 2.363 -0.915) (xy 2.479 -0.889) (xy 2.577 -0.847) (xy 2.66 -0.791) (xy 2.726 -0.716) (xy 2.757 -0.664)
				(xy 2.77 -0.638) (xy 2.781 -0.613) (xy 2.789 -0.587) (xy 2.797 -0.559) (xy 2.802 -0.524) (xy 2.807 -0.481)
				(xy 2.811 -0.429) (xy 2.813 -0.366) (xy 2.815 -0.289) (xy 2.817 -0.197) (xy 2.818 -0.086) (xy 2.818 0.046)
				(xy 2.818 0.152) (xy 2.818 0.778) (xy 2.535 0.778) (xy 2.531 0.124) (xy 2.527 -0.528) (xy 2.494 -0.589)
				(xy 2.447 -0.652) (xy 2.386 -0.697) (xy 2.314 -0.727) (xy 2.236 -0.739) (xy 2.152 -0.735) (xy 2.071 -0.714)
				(xy 1.991 -0.677) (xy 1.935 -0.634) (xy 1.884 -0.59) (xy 1.884 0.778) (xy 1.6 0.778) (xy 1.6 0.139)
				(xy 1.6 -0.022) (xy 1.6 -0.159) (xy 1.598 -0.276) (xy 1.598 -0.369) (xy 1.596 -0.443) (xy 1.592 -0.497)
				(xy 1.59 -0.533) (xy 1.588 -0.547) (xy 1.556 -0.613) (xy 1.505 -0.667) (xy 1.439 -0.706) (xy 1.356 -0.73)
				(xy 1.259 -0.74) (xy 1.161 -0.735) (xy 1.108 -0.728) (xy 1.07 -0.722) (xy 1.038 -0.715) (xy 1.004 -0.704)
				(xy 0.983 -0.696) (xy 0.951 -0.685) (xy 0.951 0.778) (xy 0.68 0.778) (xy 0.68 -0.815) (xy 0.792 -0.852)
				(xy 0.919 -0.887) (xy 1.038 -0.911) (xy 1.157 -0.921) (xy 1.282 -0.921) (xy 1.381 -0.915) (xy 1.463 -0.904)
				(xy 1.533 -0.885) (xy 1.594 -0.858) (xy 1.653 -0.822) (xy 1.679 -0.805) (xy 1.755 -0.745) (xy 1.806 -0.787)
				(xy 1.9 -0.849) (xy 2.008 -0.892) (xy 2.128 -0.918) (xy 2.233 -0.923) (xy 2.363 -0.915)
			)
			(stroke
				(width 0.001395)
				(type solid)
			)
			(fill solid)
			(layer "F.Mask")
		)
		(fp_poly
			(pts
				(xy 6.504 -0.916) (xy 6.61 -0.891) (xy 6.703 -0.849) (xy 6.788 -0.791) (xy 6.828 -0.753) (xy 6.901 -0.663)
				(xy 6.961 -0.555) (xy 7.006 -0.43) (xy 7.034 -0.288) (xy 7.044 -0.197) (xy 7.049 -0.031) (xy 7.041 0.123)
				(xy 7.015 0.266) (xy 6.977 0.395) (xy 6.924 0.507) (xy 6.857 0.604) (xy 6.778 0.684) (xy 6.73 0.719)
				(xy 6.652 0.757) (xy 6.559 0.787) (xy 6.461 0.804) (xy 6.36 0.809) (xy 6.27 0.801) (xy 6.153 0.769)
				(xy 6.051 0.717) (xy 5.961 0.648) (xy 5.885 0.559) (xy 5.825 0.453) (xy 5.778 0.329) (xy 5.753 0.22)
				(xy 5.732 0.06) (xy 5.728 -0.068) (xy 6.01 -0.068) (xy 6.015 0.065) (xy 6.031 0.192) (xy 6.057 0.307)
				(xy 6.094 0.406) (xy 6.139 0.483) (xy 6.198 0.545) (xy 6.267 0.586) (xy 6.341 0.609) (xy 6.418 0.612)
				(xy 6.498 0.593) (xy 6.523 0.581) (xy 6.589 0.539) (xy 6.644 0.478) (xy 6.688 0.402) (xy 6.722 0.305)
				(xy 6.748 0.19) (xy 6.761 0.069) (xy 6.767 -0.079) (xy 6.761 -0.217) (xy 6.743 -0.344) (xy 6.714 -0.455)
				(xy 6.674 -0.55) (xy 6.624 -0.626) (xy 6.594 -0.66) (xy 6.526 -0.707) (xy 6.453 -0.733) (xy 6.377 -0.74)
				(xy 6.302 -0.727) (xy 6.232 -0.695) (xy 6.169 -0.646) (xy 6.116 -0.578) (xy 6.095 -0.541) (xy 6.059 -0.441)
				(xy 6.031 -0.326) (xy 6.015 -0.2) (xy 6.01 -0.068) (xy 5.728 -0.068) (xy 5.727 -0.094) (xy 5.738 -0.243)
				(xy 5.761 -0.382) (xy 5.801 -0.509) (xy 5.853 -0.622) (xy 5.919 -0.719) (xy 5.938 -0.741) (xy 6.023 -0.817)
				(xy 6.119 -0.872) (xy 6.227 -0.908) (xy 6.347 -0.923) (xy 6.384 -0.924) (xy 6.504 -0.916)
			)
			(stroke
				(width 0.001395)
				(type solid)
			)
			(fill solid)
			(layer "F.Mask")
		)
		(fp_poly
			(pts
				(xy 4.406 -0.922) (xy 4.483 -0.914) (xy 4.527 -0.906) (xy 4.571 -0.892) (xy 4.62 -0.875) (xy 4.664 -0.855)
				(xy 4.7 -0.837) (xy 4.722 -0.822) (xy 4.722 -0.82) (xy 4.722 -0.806) (xy 4.712 -0.777) (xy 4.7 -0.74)
				(xy 4.684 -0.703) (xy 4.671 -0.673) (xy 4.66 -0.656) (xy 4.658 -0.654) (xy 4.642 -0.658) (xy 4.613 -0.67)
				(xy 4.584 -0.683) (xy 4.493 -0.713) (xy 4.405 -0.725) (xy 4.32 -0.718) (xy 4.246 -0.692) (xy 4.184 -0.649)
				(xy 4.128 -0.583) (xy 4.078 -0.5) (xy 4.036 -0.403) (xy 4.019 -0.346) (xy 4.006 -0.277) (xy 3.996 -0.19)
				(xy 3.992 -0.096) (xy 3.994 0.001) (xy 3.999 0.092) (xy 4.011 0.172) (xy 4.019 0.212) (xy 4.059 0.33)
				(xy 4.11 0.425) (xy 4.171 0.501) (xy 4.243 0.557) (xy 4.248 0.56) (xy 4.285 0.577) (xy 4.315 0.588)
				(xy 4.352 0.592) (xy 4.403 0.593) (xy 4.405 0.593) (xy 4.459 0.591) (xy 4.506 0.583) (xy 4.554 0.567)
				(xy 4.608 0.543) (xy 4.65 0.521) (xy 4.655 0.524) (xy 4.663 0.54) (xy 4.677 0.569) (xy 4.698 0.616)
				(xy 4.724 0.684) (xy 4.727 0.689) (xy 4.719 0.702) (xy 4.695 0.72) (xy 4.66 0.74) (xy 4.615 0.76)
				(xy 4.568 0.778) (xy 4.557 0.782) (xy 4.493 0.796) (xy 4.416 0.804) (xy 4.336 0.808) (xy 4.264 0.805)
				(xy 4.235 0.801) (xy 4.19 0.79) (xy 4.137 0.771) (xy 4.086 0.748) (xy 3.988 0.687) (xy 3.904 0.607)
				(xy 3.833 0.508) (xy 3.777 0.393) (xy 3.734 0.258) (xy 3.721 0.193) (xy 3.71 0.116) (xy 3.704 0.024)
				(xy 3.704 -0.075) (xy 3.708 -0.176) (xy 3.716 -0.271) (xy 3.728 -0.353) (xy 3.737 -0.398) (xy 3.783 -0.529)
				(xy 3.845 -0.643) (xy 3.918 -0.738) (xy 4.006 -0.816) (xy 4.107 -0.874) (xy 4.187 -0.905) (xy 4.248 -0.917)
				(xy 4.325 -0.923) (xy 4.406 -0.922)
			)
			(stroke
				(width 0.001395)
				(type solid)
			)
			(fill solid)
			(layer "F.Mask")
		)
		(fp_poly
			(pts
				(xy -2.526 -0.916) (xy -2.452 -0.902) (xy -2.367 -0.875) (xy -2.298 -0.843) (xy -2.238 -0.801) (xy -2.21 -0.774)
				(xy -2.166 -0.72) (xy -2.129 -0.652) (xy -2.098 -0.576) (xy -2.085 -0.524) (xy -2.081 -0.496) (xy -2.08 -0.448)
				(xy -2.077 -0.38) (xy -2.076 -0.294) (xy -2.074 -0.194) (xy -2.073 -0.078) (xy -2.073 0.049) (xy -2.073 0.117)
				(xy -2.073 0.693) (xy -2.127 0.718) (xy -2.226 0.753) (xy -2.342 0.782) (xy -2.465 0.8) (xy -2.592 0.809)
				(xy -2.713 0.807) (xy -2.776 0.801) (xy -2.901 0.776) (xy -3.008 0.735) (xy -3.097 0.682) (xy -3.167 0.613)
				(xy -3.218 0.531) (xy -3.25 0.434) (xy -3.263 0.325) (xy -3.263 0.27) (xy -3.262 0.26) (xy -2.992 0.26)
				(xy -2.988 0.357) (xy -2.968 0.441) (xy -2.927 0.513) (xy -2.87 0.567) (xy -2.794 0.608) (xy -2.758 0.62)
				(xy -2.711 0.628) (xy -2.649 0.631) (xy -2.58 0.631) (xy -2.509 0.627) (xy -2.445 0.619) (xy -2.395 0.608)
				(xy -2.388 0.606) (xy -2.332 0.586) (xy -2.332 -0.157) (xy -2.4 -0.149) (xy -2.444 -0.142) (xy -2.5 -0.132)
				(xy -2.558 -0.118) (xy -2.577 -0.114) (xy -2.698 -0.076) (xy -2.798 -0.03) (xy -2.875 0.025) (xy -2.933 0.088)
				(xy -2.972 0.163) (xy -2.991 0.247) (xy -2.992 0.26) (xy -3.262 0.26) (xy -3.247 0.164) (xy -3.213 0.069)
				(xy -3.155 -0.015) (xy -3.124 -0.05) (xy -3.052 -0.105) (xy -2.961 -0.157) (xy -2.852 -0.204) (xy -2.73 -0.243)
				(xy -2.596 -0.276) (xy -2.453 -0.298) (xy -2.452 -0.298) (xy -2.33 -0.313) (xy -2.336 -0.413) (xy -2.35 -0.508)
				(xy -2.377 -0.584) (xy -2.419 -0.643) (xy -2.476 -0.686) (xy -2.552 -0.714) (xy -2.588 -0.722) (xy -2.685 -0.731)
				(xy -2.794 -0.723) (xy -2.908 -0.699) (xy -3.024 -0.661) (xy -3.033 -0.656) (xy -3.069 -0.642) (xy -3.097 -0.632)
				(xy -3.106 -0.631) (xy -3.113 -0.644) (xy -3.125 -0.672) (xy -3.138 -0.707) (xy -3.153 -0.745) (xy -3.163 -0.778)
				(xy -3.17 -0.798) (xy -3.17 -0.801) (xy -3.161 -0.808) (xy -3.135 -0.821) (xy -3.106 -0.835) (xy -3 -0.873)
				(xy -2.883 -0.902) (xy -2.76 -0.918) (xy -2.639 -0.923) (xy -2.526 -0.916)
			)
			(stroke
				(width 0.001395)
				(type solid)
			)
			(fill solid)
			(layer "F.Mask")
		)
		(fp_poly
			(pts
				(xy -5.818 -2.456) (xy -5.77 -2.444) (xy -5.768 -2.444) (xy -5.753 -2.436) (xy -5.72 -2.417) (xy -5.669 -2.388)
				(xy -5.603 -2.351) (xy -5.523 -2.307) (xy -5.433 -2.254) (xy -5.332 -2.198) (xy -5.225 -2.135) (xy -5.111 -2.07)
				(xy -4.992 -2.002) (xy -4.872 -1.934) (xy -4.75 -1.863) (xy -4.63 -1.795) (xy -4.515 -1.728) (xy -4.401 -1.662)
				(xy -4.297 -1.601) (xy -4.199 -1.545) (xy -4.113 -1.494) (xy -4.037 -1.45) (xy -3.976 -1.416) (xy -3.931 -1.388)
				(xy -3.903 -1.371) (xy -3.899 -1.369) (xy -3.85 -1.329) (xy -3.811 -1.279) (xy -3.779 -1.224) (xy -3.775 -0.099)
				(xy -3.775 0.117) (xy -3.775 0.311) (xy -3.775 0.484) (xy -3.775 0.635) (xy -3.776 0.764) (xy -3.778 0.872)
				(xy -3.779 0.956) (xy -3.782 1.018) (xy -3.783 1.058) (xy -3.784 1.072) (xy -3.79 1.09) (xy -3.794 1.106)
				(xy -3.802 1.122) (xy -3.81 1.136) (xy -3.824 1.153) (xy -3.843 1.171) (xy -3.868 1.191) (xy -3.9 1.215)
				(xy -3.943 1.245) (xy -3.995 1.277) (xy -4.058 1.316) (xy -4.133 1.362) (xy -4.223 1.415) (xy -4.327 1.475)
				(xy -4.449 1.546) (xy -4.587 1.625) (xy -4.744 1.717) (xy -4.813 1.757) (xy -5.763 2.306) (xy -5.853 2.31)
				(xy -5.941 2.314) (xy -6.289 2.115) (xy -6.502 1.991) (xy -6.696 1.88) (xy -6.872 1.779) (xy -7.029 1.689)
				(xy -7.17 1.608) (xy -7.295 1.534) (xy -7.406 1.471) (xy -7.502 1.413) (xy -7.587 1.364) (xy -7.659 1.32)
				(xy -7.72 1.284) (xy -7.77 1.25) (xy -7.813 1.223) (xy -7.846 1.199) (xy -7.874 1.179) (xy -7.893 1.163)
				(xy -7.909 1.147) (xy -7.92 1.133) (xy -7.927 1.122) (xy -7.933 1.11) (xy -7.936 1.098) (xy -7.939 1.084)
				(xy -7.943 1.072) (xy -7.946 1.05) (xy -7.947 1.006) (xy -7.949 0.939) (xy -7.951 0.849) (xy -7.951 0.737)
				(xy -7.951 0.603) (xy -7.952 0.446) (xy -7.952 0.269) (xy -7.952 0.07) (xy -7.951 -0.072) (xy -7.223 -0.072)
				(xy -7.223 0.081) (xy -7.221 0.212) (xy -7.221 0.324) (xy -7.22 0.417) (xy -7.22 0.494) (xy -7.217 0.557)
				(xy -7.215 0.606) (xy -7.212 0.646) (xy -7.207 0.675) (xy -7.201 0.697) (xy -7.193 0.713) (xy -7.185 0.726)
				(xy -7.175 0.737) (xy -7.162 0.747) (xy -7.161 0.748) (xy -7.145 0.759) (xy -7.111 0.781) (xy -7.061 0.811)
				(xy -6.997 0.848) (xy -6.922 0.892) (xy -6.837 0.942) (xy -6.745 0.995) (xy -6.649 1.052) (xy -6.55 1.108)
				(xy -6.451 1.167) (xy -6.353 1.223) (xy -6.258 1.276) (xy -6.17 1.326) (xy -6.092 1.37) (xy -6.023 1.409)
				(xy -5.967 1.439) (xy -5.927 1.461) (xy -5.903 1.473) (xy -5.901 1.475) (xy -5.87 1.483) (xy -5.85 1.483)
				(xy -5.826 1.475) (xy -5.811 1.469) (xy -5.792 1.459) (xy -5.754 1.439) (xy -5.701 1.409) (xy -5.635 1.372)
				(xy -5.558 1.328) (xy -5.473 1.28) (xy -5.379 1.227) (xy -5.282 1.171) (xy -5.183 1.114) (xy -5.084 1.056)
				(xy -4.987 0.999) (xy -4.895 0.946) (xy -4.81 0.897) (xy -4.734 0.851) (xy -4.67 0.813) (xy -4.619 0.783)
				(xy -4.584 0.761) (xy -4.566 0.749) (xy -4.553 0.738) (xy -4.544 0.727) (xy -4.534 0.714) (xy -4.528 0.698)
				(xy -4.521 0.677) (xy -4.516 0.648) (xy -4.513 0.609) (xy -4.51 0.562) (xy -4.508 0.499) (xy -4.507 0.423)
				(xy -4.507 0.332) (xy -4.505 0.221) (xy -4.505 0.091) (xy -4.505 -0.059) (xy -4.505 -0.072) (xy -4.505 -0.228)
				(xy -4.505 -0.359) (xy -4.507 -0.471) (xy -4.507 -0.565) (xy -4.508 -0.644) (xy -4.51 -0.706) (xy -4.513 -0.756)
				(xy -4.518 -0.796) (xy -4.523 -0.825) (xy -4.529 -0.847) (xy -4.537 -0.864) (xy -4.547 -0.877) (xy -4.558 -0.887)
				(xy -4.572 -0.899) (xy -4.579 -0.903) (xy -4.595 -0.914) (xy -4.632 -0.936) (xy -4.683 -0.966) (xy -4.75 -1.005)
				(xy -4.83 -1.053) (xy -4.92 -1.105) (xy -5.02 -1.162) (xy -5.127 -1.224) (xy -5.215 -1.275) (xy -5.342 -1.349)
				(xy -5.451 -1.412) (xy -5.544 -1.464) (xy -5.619 -1.506) (xy -5.683 -1.541) (xy -5.733 -1.569) (xy -5.773 -1.589)
				(xy -5.802 -1.603) (xy -5.826 -1.613) (xy -5.843 -1.617) (xy -5.858 -1.621) (xy -5.862 -1.621) (xy -5.874 -1.619)
				(xy -5.89 -1.615) (xy -5.911 -1.607) (xy -5.938 -1.595) (xy -5.973 -1.579) (xy -6.018 -1.555) (xy -6.074 -1.523)
				(xy -6.144 -1.484) (xy -6.228 -1.438) (xy -6.329 -1.379) (xy -6.446 -1.313) (xy -6.528 -1.264) (xy -6.64 -1.2)
				(xy -6.745 -1.139) (xy -6.842 -1.083) (xy -6.931 -1.031) (xy -7.008 -0.985) (xy -7.072 -0.947) (xy -7.122 -0.919)
				(xy -7.154 -0.899) (xy -7.167 -0.889) (xy -7.178 -0.879) (xy -7.188 -0.869) (xy -7.196 -0.856) (xy -7.202 -0.839)
				(xy -7.207 -0.817) (xy -7.212 -0.787) (xy -7.215 -0.746) (xy -7.217 -0.694) (xy -7.22 -0.63) (xy -7.22 -0.552)
				(xy -7.221 -0.455) (xy -7.221 -0.341) (xy -7.223 -0.205) (xy -7.223 -0.072) (xy -7.951 -0.072) (xy -7.951 -0.099)
				(xy -7.951 -0.29) (xy -7.951 -0.46) (xy -7.951 -0.607) (xy -7.949 -0.736) (xy -7.949 -0.848) (xy -7.947 -0.943)
				(xy -7.946 -1.023) (xy -7.944 -1.089) (xy -7.941 -1.143) (xy -7.938 -1.188) (xy -7.934 -1.222) (xy -7.93 -1.248)
				(xy -7.925 -1.268) (xy -7.917 -1.285) (xy -7.909 -1.297) (xy -7.901 -1.307) (xy -7.89 -1.315) (xy -7.878 -1.327)
				(xy -7.874 -1.331) (xy -7.858 -1.341) (xy -7.824 -1.363) (xy -7.773 -1.393) (xy -7.705 -1.434) (xy -7.624 -1.484)
				(xy -7.528 -1.539) (xy -7.422 -1.601) (xy -7.305 -1.67) (xy -7.18 -1.742) (xy -7.048 -1.819) (xy -6.911 -1.898)
				(xy -6.896 -1.907) (xy -6.736 -2) (xy -6.595 -2.081) (xy -6.473 -2.153) (xy -6.366 -2.214) (xy -6.273 -2.266)
				(xy -6.196 -2.311) (xy -6.13 -2.347) (xy -6.076 -2.376) (xy -6.031 -2.4) (xy -5.995 -2.419) (xy -5.967 -2.432)
				(xy -5.944 -2.443) (xy -5.927 -2.448) (xy -5.911 -2.452) (xy -5.898 -2.456) (xy -5.885 -2.456) (xy -5.882 -2.456)
				(xy -5.818 -2.456)
			)
			(stroke
				(width 0.001395)
				(type solid)
			)
			(fill solid)
			(layer "F.Mask")
		)
		(fp_poly
			(pts
				(xy -5.8 -1.041) (xy -5.789 -1.037) (xy -5.736 -1.001) (xy -5.696 -0.951) (xy -5.673 -0.891) (xy -5.672 -0.827)
				(xy -5.675 -0.813) (xy -5.697 -0.751) (xy -5.739 -0.706) (xy -5.779 -0.682) (xy -5.829 -0.658) (xy -5.829 -0.38)
				(xy -5.622 -0.38) (xy -5.537 -0.465) (xy -5.452 -0.549) (xy -5.459 -0.609) (xy -5.459 -0.61) (xy -5.379 -0.61)
				(xy -5.366 -0.583) (xy -5.337 -0.57) (xy -5.305 -0.573) (xy -5.281 -0.587) (xy -5.263 -0.615) (xy -5.27 -0.644)
				(xy -5.286 -0.664) (xy -5.308 -0.683) (xy -5.326 -0.685) (xy -5.351 -0.671) (xy -5.353 -0.669) (xy -5.374 -0.643)
				(xy -5.379 -0.61) (xy -5.459 -0.61) (xy -5.46 -0.649) (xy -5.455 -0.675) (xy -5.441 -0.699) (xy -5.433 -0.707)
				(xy -5.39 -0.744) (xy -5.343 -0.76) (xy -5.295 -0.759) (xy -5.252 -0.743) (xy -5.215 -0.714) (xy -5.191 -0.674)
				(xy -5.183 -0.624) (xy -5.191 -0.575) (xy -5.217 -0.529) (xy -5.26 -0.498) (xy -5.316 -0.486) (xy -5.326 -0.486)
				(xy -5.351 -0.485) (xy -5.372 -0.481) (xy -5.393 -0.47) (xy -5.419 -0.451) (xy -5.454 -0.418) (xy -5.483 -0.392)
				(xy -5.584 -0.297) (xy -5.829 -0.297) (xy -5.829 -0.108) (xy -5.38 -0.108) (xy -5.362 -0.142) (xy -5.33 -0.18)
				(xy -5.286 -0.204) (xy -5.236 -0.21) (xy -5.188 -0.201) (xy -5.145 -0.172) (xy -5.141 -0.169) (xy -5.111 -0.12)
				(xy -5.1 -0.071) (xy -5.108 -0.026) (xy -5.129 0.016) (xy -5.164 0.046) (xy -5.207 0.065) (xy -5.255 0.068)
				(xy -5.308 0.05) (xy -5.318 0.044) (xy -5.346 0.024) (xy -5.364 0.002) (xy -5.364 -0.002) (xy -5.367 -0.01)
				(xy -5.374 -0.016) (xy -5.39 -0.02) (xy -5.414 -0.023) (xy -5.451 -0.024) (xy -5.507 -0.026) (xy -5.58 -0.026)
				(xy -5.6 -0.026) (xy -5.829 -0.026) (xy -5.829 0.151) (xy -5.585 0.151) (xy -5.39 0.348) (xy -5.334 0.343)
				(xy -5.276 0.347) (xy -5.229 0.37) (xy -5.197 0.411) (xy -5.189 0.433) (xy -5.181 0.489) (xy -5.196 0.539)
				(xy -5.225 0.577) (xy -5.27 0.609) (xy -5.319 0.62) (xy -5.366 0.614) (xy -5.409 0.591) (xy -5.439 0.555)
				(xy -5.457 0.506) (xy -5.459 0.47) (xy -5.377 0.47) (xy -5.374 0.5) (xy -5.362 0.518) (xy -5.335 0.538)
				(xy -5.31 0.537) (xy -5.286 0.518) (xy -5.265 0.488) (xy -5.266 0.463) (xy -5.284 0.441) (xy -5.313 0.426)
				(xy -5.342 0.429) (xy -5.366 0.445) (xy -5.377 0.47) (xy -5.459 0.47) (xy -5.459 0.46) (xy -5.451 0.404)
				(xy -5.622 0.234) (xy -5.829 0.234) (xy -5.829 0.514) (xy -5.779 0.536) (xy -5.728 0.57) (xy -5.693 0.617)
				(xy -5.675 0.674) (xy -5.67 0.731) (xy -5.685 0.789) (xy -5.713 0.838) (xy -5.76 0.878) (xy -5.77 0.884)
				(xy -5.832 0.904) (xy -5.898 0.904) (xy -5.959 0.884) (xy -5.96 0.883) (xy -6.008 0.845) (xy -6.04 0.797)
				(xy -6.055 0.74) (xy -6.055 0.712) (xy -5.975 0.712) (xy -5.97 0.747) (xy -5.952 0.776) (xy -5.936 0.791)
				(xy -5.893 0.818) (xy -5.85 0.822) (xy -5.806 0.804) (xy -5.79 0.791) (xy -5.765 0.761) (xy -5.753 0.731)
				(xy -5.752 0.712) (xy -5.763 0.67) (xy -5.792 0.632) (xy -5.829 0.607) (xy -5.864 0.6) (xy -5.906 0.61)
				(xy -5.943 0.638) (xy -5.967 0.678) (xy -5.975 0.712) (xy -6.055 0.712) (xy -6.055 0.682) (xy -6.037 0.625)
				(xy -6.004 0.576) (xy -5.957 0.54) (xy -5.947 0.536) (xy -5.899 0.514) (xy -5.899 0.234) (xy -6.106 0.234)
				(xy -6.276 0.404) (xy -6.269 0.46) (xy -6.271 0.516) (xy -6.292 0.562) (xy -6.326 0.596) (xy -6.369 0.616)
				(xy -6.417 0.62) (xy -6.465 0.605) (xy -6.502 0.577) (xy -6.536 0.533) (xy -6.547 0.482) (xy -6.544 0.468)
				(xy -6.463 0.468) (xy -6.46 0.493) (xy -6.443 0.518) (xy -6.414 0.539) (xy -6.388 0.537) (xy -6.366 0.519)
				(xy -6.351 0.487) (xy -6.356 0.457) (xy -6.375 0.433) (xy -6.39 0.427) (xy -6.425 0.429) (xy -6.443 0.441)
				(xy -6.463 0.468) (xy -6.544 0.468) (xy -6.537 0.433) (xy -6.512 0.386) (xy -6.473 0.355) (xy -6.419 0.343)
				(xy -6.393 0.343) (xy -6.338 0.348) (xy -6.141 0.151) (xy -5.899 0.151) (xy -5.899 -0.026) (xy -6.128 -0.026)
				(xy -6.207 -0.026) (xy -6.266 -0.026) (xy -6.308 -0.023) (xy -6.335 -0.022) (xy -6.351 -0.018) (xy -6.361 -0.012)
				(xy -6.364 -0.004) (xy -6.366 -0.001) (xy -6.385 0.025) (xy -6.419 0.05) (xy -6.46 0.066) (xy -6.487 0.069)
				(xy -6.542 0.058) (xy -6.584 0.033) (xy -6.614 -0.007) (xy -6.627 -0.054) (xy -6.625 -0.071) (xy -6.547 -0.071)
				(xy -6.544 -0.053) (xy -6.531 -0.038) (xy -6.5 -0.018) (xy -6.47 -0.018) (xy -6.449 -0.032) (xy -6.433 -0.062)
				(xy -6.435 -0.083) (xy -5.295 -0.083) (xy -5.29 -0.05) (xy -5.278 -0.032) (xy -5.249 -0.015) (xy -5.217 -0.022)
				(xy -5.196 -0.038) (xy -5.181 -0.058) (xy -5.183 -0.075) (xy -5.191 -0.094) (xy -5.217 -0.121) (xy -5.247 -0.13)
				(xy -5.276 -0.117) (xy -5.278 -0.115) (xy -5.295 -0.083) (xy -6.435 -0.083) (xy -6.438 -0.094) (xy -6.454 -0.114)
				(xy -6.483 -0.13) (xy -6.512 -0.122) (xy -6.536 -0.094) (xy -6.547 -0.071) (xy -6.625 -0.071) (xy -6.622 -0.104)
				(xy -6.598 -0.153) (xy -6.587 -0.169) (xy -6.544 -0.2) (xy -6.495 -0.211) (xy -6.444 -0.204) (xy -6.399 -0.18)
				(xy -6.367 -0.143) (xy -6.346 -0.108) (xy -5.899 -0.108) (xy -5.899 -0.297) (xy -6.143 -0.297) (xy -6.244 -0.392)
				(xy -6.289 -0.432) (xy -6.319 -0.46) (xy -6.342 -0.475) (xy -6.364 -0.483) (xy -6.385 -0.486) (xy -6.404 -0.486)
				(xy -6.462 -0.494) (xy -6.504 -0.521) (xy -6.532 -0.565) (xy -6.539 -0.58) (xy -6.544 -0.623) (xy -6.467 -0.623)
				(xy -6.457 -0.596) (xy -6.431 -0.577) (xy -6.399 -0.569) (xy -6.37 -0.576) (xy -6.362 -0.583) (xy -6.348 -0.611)
				(xy -6.353 -0.643) (xy -6.374 -0.669) (xy -6.396 -0.683) (xy -6.409 -0.688) (xy -6.427 -0.679) (xy -6.447 -0.658)
				(xy -6.462 -0.634) (xy -6.467 -0.623) (xy -6.544 -0.623) (xy -6.544 -0.635) (xy -6.532 -0.684) (xy -6.505 -0.722)
				(xy -6.467 -0.748) (xy -6.422 -0.761) (xy -6.374 -0.759) (xy -6.327 -0.738) (xy -6.294 -0.707) (xy -6.276 -0.682)
				(xy -6.268 -0.658) (xy -6.268 -0.623) (xy -6.268 -0.609) (xy -6.276 -0.549) (xy -6.191 -0.465) (xy -6.106 -0.38)
				(xy -5.899 -0.38) (xy -5.899 -0.659) (xy -5.946 -0.68) (xy -6.002 -0.715) (xy -6.039 -0.766) (xy -6.052 -0.806)
				(xy -6.058 -0.86) (xy -5.978 -0.86) (xy -5.973 -0.833) (xy -5.965 -0.813) (xy -5.935 -0.773) (xy -5.895 -0.75)
				(xy -5.85 -0.748) (xy -5.805 -0.767) (xy -5.8 -0.772) (xy -5.765 -0.809) (xy -5.752 -0.849) (xy -5.762 -0.892)
				(xy -5.79 -0.938) (xy -5.829 -0.962) (xy -5.87 -0.968) (xy -5.912 -0.956) (xy -5.949 -0.926) (xy -5.97 -0.889)
				(xy -5.978 -0.86) (xy -6.058 -0.86) (xy -6.06 -0.868) (xy -6.045 -0.928) (xy -6.015 -0.977) (xy -5.973 -1.017)
				(xy -5.92 -1.043) (xy -5.861 -1.053) (xy -5.8 -1.041)
			)
			(stroke
				(width 0.001395)
				(type solid)
			)
			(fill solid)
			(layer "F.Mask")
		)
		(fp_rect
			(start -9.683 -4.203)
			(end 8.773 4.063)
			(stroke
				(width 0.05)
				(type default)
			)
			(fill none)
			(layer "F.CrtYd")
		)
		(fp_text user "${REFERENCE}"
			(at -7.952 14.498 90)
			(layer "F.Fab")
			(hide yes)
			(effects
				(font
					(size 0.7 0.7)
					(thickness 0.15)
				)
				(justify left bottom)
			)
		)
		(fp_text user "Author: Antmicro"
			(at -7.952 12.098 90)
			(layer "F.Fab")
			(hide yes)
			(effects
				(font
					(size 0.7 0.7)
					(thickness 0.15)
				)
				(justify left bottom)
			)
		)
		(fp_text user "License: Apache-2.0"
			(at -7.952 13.298 90)
			(layer "F.Fab")
			(hide yes)
			(effects
				(font
					(size 0.7 0.7)
					(thickness 0.15)
				)
				(justify left bottom)
			)
		)
	)
	(footprint "antmicro-footprints:C_0402_1005Metric"
		(layer "F.Cu")
		(at 144.133 114.08 180)
		(descr "Capacitor SMD 0402")
		(tags "capacitor SMD 0402")
		(property "Reference" "C31"
			(at 0.933 0.38 0)
			(layer "F.SilkS")
			(effects
				(font
					(size 0.7 0.7)
					(thickness 0.15)
				)
				(justify right top)
			)
		)
		(property "Value" "C_100n_0402"
			(at -1.022927 2.155213 0)
			(layer "F.Fab")
			(effects
				(font
					(size 0.7 0.7)
					(thickness 0.15)
				)
				(justify right top)
			)
		)
		(property "Footprint" "antmicro-footprints:C_0402_1005Metric"
			(at 0 0 0)
			(layer "F.Fab")
			(hide yes)
			(effects
				(font
					(size 1.27 1.27)
					(thickness 0.15)
				)
			)
		)
		(property "Datasheet" "https://www.murata.com/products/productdetail?partno=GRM155R61H104KE14%23"
			(at 0 0 0)
			(layer "F.Fab")
			(hide yes)
			(effects
				(font
					(size 1.27 1.27)
					(thickness 0.15)
				)
			)
		)
		(property "Description" "SMD Multilayer Ceramic Capacitor, 0.1 µF, 50 V, 0402 [1005 Metric], ± 10%, X5R, GRM Series"
			(at 0 0 0)
			(layer "F.Fab")
			(hide yes)
			(effects
				(font
					(size 1.27 1.27)
					(thickness 0.15)
				)
			)
		)
		(property "MPN" "GRM155R61H104KE14D"
			(at 0 0 180)
			(unlocked yes)
			(layer "F.Fab")
			(hide yes)
			(effects
				(font
					(size 1 1)
					(thickness 0.15)
				)
			)
		)
		(property "Manufacturer" "Murata"
			(at 0 0 180)
			(unlocked yes)
			(layer "F.Fab")
			(hide yes)
			(effects
				(font
					(size 1 1)
					(thickness 0.15)
				)
			)
		)
		(property "License" "Apache-2.0"
			(at 0 0 180)
			(unlocked yes)
			(layer "F.Fab")
			(hide yes)
			(effects
				(font
					(size 1 1)
					(thickness 0.15)
				)
			)
		)
		(property "Author" "Antmicro"
			(at 0 0 180)
			(unlocked yes)
			(layer "F.Fab")
			(hide yes)
			(effects
				(font
					(size 1 1)
					(thickness 0.15)
				)
			)
		)
		(property "Val" "100n"
			(at 0 0 180)
			(unlocked yes)
			(layer "F.Fab")
			(hide yes)
			(effects
				(font
					(size 1 1)
					(thickness 0.15)
				)
			)
		)
		(property "Voltage" "50V"
			(at 0 0 180)
			(unlocked yes)
			(layer "F.Fab")
			(hide yes)
			(effects
				(font
					(size 1 1)
					(thickness 0.15)
				)
			)
		)
		(property "Dielectric" "X5R"
			(at 0 0 180)
			(unlocked yes)
			(layer "F.Fab")
			(hide yes)
			(effects
				(font
					(size 1 1)
					(thickness 0.15)
				)
			)
		)
		(sheetname "Root")
		(sheetfile "jetson-orin-baseboard-oculink-expansion.kicad_sch")
		(attr smd)
		(fp_rect
			(start -0.925 -0.47)
			(end 0.925 0.47)
			(stroke
				(width 0.05)
				(type default)
			)
			(fill none)
			(layer "F.CrtYd")
		)
		(fp_line
			(start 0.504 0.248)
			(end -0.494 0.248)
			(stroke
				(width 0.15)
				(type solid)
			)
			(layer "F.Fab")
		)
		(fp_line
			(start 0.504 -0.25)
			(end 0.504 0.248)
			(stroke
				(width 0.15)
				(type solid)
			)
			(layer "F.Fab")
		)
		(fp_line
			(start -0.494 0.248)
			(end -0.494 -0.25)
			(stroke
				(width 0.15)
				(type solid)
			)
			(layer "F.Fab")
		)
		(fp_line
			(start -0.494 -0.25)
			(end 0.504 -0.25)
			(stroke
				(width 0.15)
				(type solid)
			)
			(layer "F.Fab")
		)
		(fp_text user "Author: Antmicro"
			(at -0.939 3.399 0)
			(layer "F.Fab")
			(hide yes)
			(effects
				(font
					(size 0.7 0.7)
					(thickness 0.15)
				)
				(justify right top)
			)
		)
		(fp_text user "${REFERENCE}"
			(at -0.939 4.599 0)
			(layer "F.Fab")
			(hide yes)
			(effects
				(font
					(size 0.7 0.7)
					(thickness 0.15)
				)
				(justify right top)
			)
		)
		(fp_text user "License: Apache-2.0"
			(at -0.939 5.799 0)
			(layer "F.Fab")
			(hide yes)
			(effects
				(font
					(size 0.7 0.7)
					(thickness 0.15)
				)
				(justify right top)
			)
		)
		(pad "1" smd roundrect
			(at -0.48 0 180)
			(size 0.59 0.64)
			(layers "F.Cu" "F.Paste" "F.Mask")
			(roundrect_rratio 0.25)
			(net 51 "GND")
			(pintype "passive")
		)
		(pad "2" smd roundrect
			(at 0.48 0 180)
			(size 0.59 0.64)
			(layers "F.Cu" "F.Paste" "F.Mask")
			(roundrect_rratio 0.25)
			(net 134 "Net-(U4-OUT)")
			(pintype "passive")
		)
	)
	(footprint "antmicro-footprints:TP_SMD_0.75mm"
		(layer "F.Cu")
		(at 117.785 123.6675 180)
		(property "Reference" "TP16"
			(at -1.895 1.4075 0)
			(layer "F.SilkS")
			(effects
				(font
					(size 0.7 0.7)
					(thickness 0.15)
				)
				(justify right top)
			)
		)
		(property "Value" "TP_0.75mm_SMD"
			(at 0 1.2 0)
			(layer "F.Fab")
			(effects
				(font
					(size 0.7 0.7)
					(thickness 0.15)
				)
				(justify right top)
			)
		)
		(property "Footprint" "antmicro-footprints:TP_SMD_0.75mm"
			(at 0 0 0)
			(layer "F.Fab")
			(hide yes)
			(effects
				(font
					(size 1.27 1.27)
					(thickness 0.15)
				)
			)
		)
		(property "Description" "SMT test point"
			(at 0 0 0)
			(layer "F.Fab")
			(hide yes)
			(effects
				(font
					(size 1.27 1.27)
					(thickness 0.15)
				)
			)
		)
		(property "MPN" ""
			(at 0 0 180)
			(unlocked yes)
			(layer "F.Fab")
			(hide yes)
			(effects
				(font
					(size 1 1)
					(thickness 0.15)
				)
			)
		)
		(property "Manufacturer" ""
			(at 0 0 180)
			(unlocked yes)
			(layer "F.Fab")
			(hide yes)
			(effects
				(font
					(size 1 1)
					(thickness 0.15)
				)
			)
		)
		(property "Author" "Antmicro"
			(at 0 0 180)
			(unlocked yes)
			(layer "F.Fab")
			(hide yes)
			(effects
				(font
					(size 1 1)
					(thickness 0.15)
				)
			)
		)
		(property "License" "Apache-2.0"
			(at 0 0 180)
			(unlocked yes)
			(layer "F.Fab")
			(hide yes)
			(effects
				(font
					(size 1 1)
					(thickness 0.15)
				)
			)
		)
		(property "Public" "False"
			(at 0 0 180)
			(unlocked yes)
			(layer "F.Fab")
			(hide yes)
			(effects
				(font
					(size 1 1)
					(thickness 0.15)
				)
			)
		)
		(sheetname "Root")
		(sheetfile "jetson-orin-baseboard-oculink-expansion.kicad_sch")
		(attr exclude_from_pos_files exclude_from_bom)
		(fp_circle
			(center 0 0)
			(end 0.475 0)
			(stroke
				(width 0.05)
				(type default)
			)
			(fill none)
			(layer "F.CrtYd")
		)
		(fp_text user "${REFERENCE}"
			(at -0.4 2.7 0)
			(layer "F.Fab")
			(hide yes)
			(effects
				(font
					(size 0.7 0.7)
					(thickness 0.15)
				)
				(justify right top)
			)
		)
		(fp_text user "Author: Antmicro"
			(at -0.4 3.901 0)
			(layer "F.Fab")
			(hide yes)
			(effects
				(font
					(size 0.7 0.7)
					(thickness 0.15)
				)
				(justify right top)
			)
		)
		(fp_text user "License: Apache-2.0"
			(at -0.4 5.101 0)
			(layer "F.Fab")
			(hide yes)
			(effects
				(font
					(size 0.7 0.7)
					(thickness 0.15)
				)
				(justify right top)
			)
		)
		(pad "1" smd circle
			(at 0 0 180)
			(size 0.75 0.75)
			(layers "F.Cu" "F.Mask")
			(net 112 "Net-(U3-~{I2C_{RESET}})")
			(pinfunction "1")
			(pintype "passive")
		)
	)
	(footprint "antmicro-footprints:R_0402_1005Metric"
		(layer "F.Cu")
		(at 144.6 108.6 -90)
		(descr "Resistor SMD 0402")
		(tags "resistor SMD 0402")
		(property "Reference" "R46"
			(at -1.1 1.3 90)
			(layer "F.SilkS")
			(effects
				(font
					(size 0.7 0.7)
					(thickness 0.15)
				)
				(justify right top)
			)
		)
		(property "Value" "R_5k6_0402"
			(at -1.011843 1.772047 90)
			(layer "F.Fab")
			(effects
				(font
					(size 0.7 0.7)
					(thickness 0.15)
				)
				(justify right top)
			)
		)
		(property "Footprint" "antmicro-footprints:R_0402_1005Metric"
			(at 0 0 90)
			(layer "F.Fab")
			(hide yes)
			(effects
				(font
					(size 1.27 1.27)
					(thickness 0.15)
				)
			)
		)
		(property "Datasheet" "https://www.bourns.com/docs/product-datasheets/cr.pdf"
			(at 0 0 90)
			(layer "F.Fab")
			(hide yes)
			(effects
				(font
					(size 1.27 1.27)
					(thickness 0.15)
				)
			)
		)
		(property "Description" "SMD Chip Resistor, 5.6 kohm, ± 1%, 62.5 mW, 0402 [1005 Metric], Thick Film, General Purpose"
			(at 0 0 90)
			(layer "F.Fab")
			(hide yes)
			(effects
				(font
					(size 1.27 1.27)
					(thickness 0.15)
				)
			)
		)
		(property "MPN" "CR0402-FX-5601GLF"
			(at 0 0 -90)
			(unlocked yes)
			(layer "F.Fab")
			(hide yes)
			(effects
				(font
					(size 1 1)
					(thickness 0.15)
				)
			)
		)
		(property "Manufacturer" "Bourns"
			(at 0 0 -90)
			(unlocked yes)
			(layer "F.Fab")
			(hide yes)
			(effects
				(font
					(size 1 1)
					(thickness 0.15)
				)
			)
		)
		(property "License" "Apache-2.0"
			(at 0 0 -90)
			(unlocked yes)
			(layer "F.Fab")
			(hide yes)
			(effects
				(font
					(size 1 1)
					(thickness 0.15)
				)
			)
		)
		(property "Author" "Antmicro"
			(at 0 0 -90)
			(unlocked yes)
			(layer "F.Fab")
			(hide yes)
			(effects
				(font
					(size 1 1)
					(thickness 0.15)
				)
			)
		)
		(property "Val" "5k6"
			(at 0 0 -90)
			(unlocked yes)
			(layer "F.Fab")
			(hide yes)
			(effects
				(font
					(size 1 1)
					(thickness 0.15)
				)
			)
		)
		(property "Tolerance" "1%"
			(at 0 0 -90)
			(unlocked yes)
			(layer "F.Fab")
			(hide yes)
			(effects
				(font
					(size 1 1)
					(thickness 0.15)
				)
			)
		)
		(sheetname "Root")
		(sheetfile "jetson-orin-baseboard-oculink-expansion.kicad_sch")
		(attr smd)
		(fp_rect
			(start -0.925 -0.47)
			(end 0.925 0.47)
			(stroke
				(width 0.05)
				(type default)
			)
			(fill none)
			(layer "F.CrtYd")
		)
		(fp_rect
			(start -0.5 -0.25)
			(end 0.5 0.25)
			(stroke
				(width 0.15)
				(type solid)
			)
			(fill none)
			(layer "F.Fab")
		)
		(fp_text user "Author: Antmicro"
			(at -0.95 4.169 90)
			(layer "F.Fab")
			(hide yes)
			(effects
				(font
					(size 0.7 0.7)
					(thickness 0.15)
				)
				(justify right top)
			)
		)
		(fp_text user "${REFERENCE}"
			(at -0.95 3.168 90)
			(layer "F.Fab")
			(hide yes)
			(effects
				(font
					(size 0.7 0.7)
					(thickness 0.15)
				)
				(justify right top)
			)
		)
		(fp_text user "License: Apache-2.0"
			(at -0.95 5.169 90)
			(layer "F.Fab")
			(hide yes)
			(effects
				(font
					(size 0.7 0.7)
					(thickness 0.15)
				)
				(justify right top)
			)
		)
		(pad "1" smd roundrect
			(at -0.48 0 270)
			(size 0.59 0.64)
			(layers "F.Cu" "F.Paste" "F.Mask")
			(roundrect_rratio 0.25)
			(net 51 "GND")
			(pintype "passive")
		)
		(pad "2" smd roundrect
			(at 0.48 0 270)
			(size 0.59 0.64)
			(layers "F.Cu" "F.Paste" "F.Mask")
			(roundrect_rratio 0.25)
			(net 137 "Net-(U4-ISET)")
			(pintype "passive")
		)
	)
	(footprint "antmicro-footprints:MP_Pad5.4mm_Drill2.7mm"
		(layer "F.Cu")
		(at 135.9 93.5)
		(descr "Mounting Hole 2.7mm, M2.5")
		(tags "mounting hole 2.7mm m2.5")
		(property "Reference" "MP2"
			(at -3.6 -0.4 90)
			(layer "F.SilkS")
			(effects
				(font
					(size 0.7 0.7)
					(thickness 0.15)
				)
				(justify left bottom)
			)
		)
		(property "Value" "MP_Pad5.4mm_Drill2.7mm"
			(at 0 3.6 0)
			(layer "F.Fab")
			(effects
				(font
					(size 0.7 0.7)
					(thickness 0.15)
				)
				(justify left bottom)
			)
		)
		(property "Footprint" "antmicro-footprints:MP_Pad5.4mm_Drill2.7mm"
			(at 0 0 0)
			(layer "F.Fab")
			(hide yes)
			(effects
				(font
					(size 1.27 1.27)
					(thickness 0.15)
				)
			)
		)
		(property "Description" "Mechanical part"
			(at 0 0 0)
			(layer "F.Fab")
			(hide yes)
			(effects
				(font
					(size 1.27 1.27)
					(thickness 0.15)
				)
			)
		)
		(property "Author" "Antmicro"
			(at 0 0 0)
			(unlocked yes)
			(layer "F.Fab")
			(hide yes)
			(effects
				(font
					(size 1 1)
					(thickness 0.15)
				)
			)
		)
		(property "License" "Apache-2.0"
			(at 0 0 0)
			(unlocked yes)
			(layer "F.Fab")
			(hide yes)
			(effects
				(font
					(size 1 1)
					(thickness 0.15)
				)
			)
		)
		(sheetname "Root")
		(sheetfile "jetson-orin-baseboard-oculink-expansion.kicad_sch")
		(attr exclude_from_pos_files exclude_from_bom)
		(fp_circle
			(center 0 0)
			(end 2.95 0)
			(stroke
				(width 0.05)
				(type default)
			)
			(fill none)
			(layer "F.CrtYd")
		)
		(fp_text user "License: Apache-2.0"
			(at -8.4 8.4 0)
			(layer "F.Fab")
			(hide yes)
			(effects
				(font
					(size 0.7 0.7)
					(thickness 0.15)
				)
				(justify left bottom)
			)
		)
		(fp_text user "Author: Antmicro"
			(at -8.4 7.2 0)
			(layer "F.Fab")
			(hide yes)
			(effects
				(font
					(size 0.7 0.7)
					(thickness 0.15)
				)
				(justify left bottom)
			)
		)
		(fp_text user "${REFERENCE}"
			(at -8.4 6 0)
			(layer "F.Fab")
			(hide yes)
			(effects
				(font
					(size 0.7 0.7)
					(thickness 0.15)
				)
				(justify left bottom)
			)
		)
		(pad "1" thru_hole circle
			(at 0 0)
			(size 5.4 5.4)
			(drill 2.7)
			(layers "*.Cu" "*.Mask")
			(remove_unused_layers no)
			(net 51 "GND")
			(pintype "passive")
			(solder_paste_margin_ratio -1)
		)
	)
	(footprint "antmicro-footprints:C_0402_1005Metric"
		(layer "F.Cu")
		(at 129.2 105.919 180)
		(descr "Capacitor SMD 0402")
		(tags "capacitor SMD 0402")
		(property "Reference" "C41"
			(at 0.91 0.37 0)
			(layer "F.SilkS")
			(effects
				(font
					(size 0.7 0.7)
					(thickness 0.15)
				)
				(justify right top)
			)
		)
		(property "Value" "C_220n_0402"
			(at -1.022927 2.155213 0)
			(layer "F.Fab")
			(effects
				(font
					(size 0.7 0.7)
					(thickness 0.15)
				)
				(justify right top)
			)
		)
		(property "Footprint" "antmicro-footprints:C_0402_1005Metric"
			(at 0 0 0)
			(layer "F.Fab")
			(hide yes)
			(effects
				(font
					(size 1.27 1.27)
					(thickness 0.15)
				)
			)
		)
		(property "Datasheet" "https://www.yageo.com/en/Chart/Download/pdf/CC0402KRX5R6BB224"
			(at 0 0 0)
			(layer "F.Fab")
			(hide yes)
			(effects
				(font
					(size 1.27 1.27)
					(thickness 0.15)
				)
			)
		)
		(property "Description" "SMD Multilayer Ceramic Capacitor, 0.22 µF, 10 V, 0402 [1005 Metric], ± 10%, X5R, CC Series"
			(at 0 0 0)
			(layer "F.Fab")
			(hide yes)
			(effects
				(font
					(size 1.27 1.27)
					(thickness 0.15)
				)
			)
		)
		(property "MPN" "CC0402KRX5R6BB224"
			(at 0 0 180)
			(unlocked yes)
			(layer "F.Fab")
			(hide yes)
			(effects
				(font
					(size 1 1)
					(thickness 0.15)
				)
			)
		)
		(property "Manufacturer" "YAGEO"
			(at 0 0 180)
			(unlocked yes)
			(layer "F.Fab")
			(hide yes)
			(effects
				(font
					(size 1 1)
					(thickness 0.15)
				)
			)
		)
		(property "License" "Apache-2.0"
			(at 0 0 180)
			(unlocked yes)
			(layer "F.Fab")
			(hide yes)
			(effects
				(font
					(size 1 1)
					(thickness 0.15)
				)
			)
		)
		(property "Author" "Antmicro"
			(at 0 0 180)
			(unlocked yes)
			(layer "F.Fab")
			(hide yes)
			(effects
				(font
					(size 1 1)
					(thickness 0.15)
				)
			)
		)
		(property "Val" "220n"
			(at 0 0 180)
			(unlocked yes)
			(layer "F.Fab")
			(hide yes)
			(effects
				(font
					(size 1 1)
					(thickness 0.15)
				)
			)
		)
		(property "Voltage" ""
			(at 0 0 180)
			(unlocked yes)
			(layer "F.Fab")
			(hide yes)
			(effects
				(font
					(size 1 1)
					(thickness 0.15)
				)
			)
		)
		(property "Dielectric" ""
			(at 0 0 180)
			(unlocked yes)
			(layer "F.Fab")
			(hide yes)
			(effects
				(font
					(size 1 1)
					(thickness 0.15)
				)
			)
		)
		(property "Public" "False"
			(at 0 0 180)
			(unlocked yes)
			(layer "F.Fab")
			(hide yes)
			(effects
				(font
					(size 1 1)
					(thickness 0.15)
				)
			)
		)
		(sheetname "Root")
		(sheetfile "jetson-orin-baseboard-oculink-expansion.kicad_sch")
		(attr smd)
		(fp_rect
			(start -0.925 -0.47)
			(end 0.925 0.47)
			(stroke
				(width 0.05)
				(type default)
			)
			(fill none)
			(layer "F.CrtYd")
		)
		(fp_line
			(start 0.504 0.248)
			(end -0.494 0.248)
			(stroke
				(width 0.15)
				(type solid)
			)
			(layer "F.Fab")
		)
		(fp_line
			(start 0.504 -0.25)
			(end 0.504 0.248)
			(stroke
				(width 0.15)
				(type solid)
			)
			(layer "F.Fab")
		)
		(fp_line
			(start -0.494 0.248)
			(end -0.494 -0.25)
			(stroke
				(width 0.15)
				(type solid)
			)
			(layer "F.Fab")
		)
		(fp_line
			(start -0.494 -0.25)
			(end 0.504 -0.25)
			(stroke
				(width 0.15)
				(type solid)
			)
			(layer "F.Fab")
		)
		(fp_text user "${REFERENCE}"
			(at -0.939 4.599 0)
			(layer "F.Fab")
			(hide yes)
			(effects
				(font
					(size 0.7 0.7)
					(thickness 0.15)
				)
				(justify right top)
			)
		)
		(fp_text user "License: Apache-2.0"
			(at -0.939 5.799 0)
			(layer "F.Fab")
			(hide yes)
			(effects
				(font
					(size 0.7 0.7)
					(thickness 0.15)
				)
				(justify right top)
			)
		)
		(fp_text user "Author: Antmicro"
			(at -0.939 3.399 0)
			(layer "F.Fab")
			(hide yes)
			(effects
				(font
					(size 0.7 0.7)
					(thickness 0.15)
				)
				(justify right top)
			)
		)
		(pad "1" smd roundrect
			(at -0.48 0 180)
			(size 0.59 0.64)
			(layers "F.Cu" "F.Paste" "F.Mask")
			(roundrect_rratio 0.25)
			(net 75 "/PCIE_{I}_RX1-")
			(pintype "passive")
		)
		(pad "2" smd roundrect
			(at 0.48 0 180)
			(size 0.59 0.64)
			(layers "F.Cu" "F.Paste" "F.Mask")
			(roundrect_rratio 0.25)
			(net 76 "/PCIE_{I}_C.RX1-")
			(pintype "passive")
		)
	)
	(footprint "antmicro-footprints:R_0402_1005Metric"
		(layer "F.Cu")
		(at 117.79 130.14 180)
		(descr "Resistor SMD 0402")
		(tags "resistor SMD 0402")
		(property "Reference" "R32"
			(at -1.122484 -0.772697 0)
			(layer "F.SilkS")
			(effects
				(font
					(size 0.7 0.7)
					(thickness 0.15)
				)
				(justify right top)
			)
		)
		(property "Value" "R_0R_0402"
			(at -1.011843 1.772047 0)
			(layer "F.Fab")
			(effects
				(font
					(size 0.7 0.7)
					(thickness 0.15)
				)
				(justify right top)
			)
		)
		(property "Footprint" "antmicro-footprints:R_0402_1005Metric"
			(at 0 0 0)
			(layer "F.Fab")
			(hide yes)
			(effects
				(font
					(size 1.27 1.27)
					(thickness 0.15)
				)
			)
		)
		(property "Datasheet" "https://industrial.panasonic.com/cdbs/www-data/pdf/RDA0000/AOA0000C301.pdf"
			(at 0 0 0)
			(layer "F.Fab")
			(hide yes)
			(effects
				(font
					(size 1.27 1.27)
					(thickness 0.15)
				)
			)
		)
		(property "Description" "SMD Chip Resistor, Jumper, 0 ohm, 100 mW, 0402 [1005 Metric], Thick Film, General Purpose"
			(at 0 0 0)
			(layer "F.Fab")
			(hide yes)
			(effects
				(font
					(size 1.27 1.27)
					(thickness 0.15)
				)
			)
		)
		(property "MPN" "ERJ2GE0R00X"
			(at 0 0 180)
			(unlocked yes)
			(layer "F.Fab")
			(hide yes)
			(effects
				(font
					(size 1 1)
					(thickness 0.15)
				)
			)
		)
		(property "Manufacturer" "Panasonic"
			(at 0 0 180)
			(unlocked yes)
			(layer "F.Fab")
			(hide yes)
			(effects
				(font
					(size 1 1)
					(thickness 0.15)
				)
			)
		)
		(property "License" "Apache-2.0"
			(at 0 0 180)
			(unlocked yes)
			(layer "F.Fab")
			(hide yes)
			(effects
				(font
					(size 1 1)
					(thickness 0.15)
				)
			)
		)
		(property "Author" "Antmicro"
			(at 0 0 180)
			(unlocked yes)
			(layer "F.Fab")
			(hide yes)
			(effects
				(font
					(size 1 1)
					(thickness 0.15)
				)
			)
		)
		(property "Val" "0R"
			(at 0 0 180)
			(unlocked yes)
			(layer "F.Fab")
			(hide yes)
			(effects
				(font
					(size 1 1)
					(thickness 0.15)
				)
			)
		)
		(property "Tolerance" ""
			(at 0 0 180)
			(unlocked yes)
			(layer "F.Fab")
			(hide yes)
			(effects
				(font
					(size 1 1)
					(thickness 0.15)
				)
			)
		)
		(property "Current" "1A"
			(at 0 0 180)
			(unlocked yes)
			(layer "F.Fab")
			(hide yes)
			(effects
				(font
					(size 1 1)
					(thickness 0.15)
				)
			)
		)
		(property "Public" "False"
			(at 0 0 180)
			(unlocked yes)
			(layer "F.Fab")
			(hide yes)
			(effects
				(font
					(size 1 1)
					(thickness 0.15)
				)
			)
		)
		(sheetname "Root")
		(sheetfile "jetson-orin-baseboard-oculink-expansion.kicad_sch")
		(attr smd)
		(fp_rect
			(start -0.925 -0.47)
			(end 0.925 0.47)
			(stroke
				(width 0.05)
				(type default)
			)
			(fill none)
			(layer "F.CrtYd")
		)
		(fp_rect
			(start -0.5 -0.25)
			(end 0.5 0.25)
			(stroke
				(width 0.15)
				(type solid)
			)
			(fill none)
			(layer "F.Fab")
		)
		(fp_text user "License: Apache-2.0"
			(at -0.95 5.169 0)
			(layer "F.Fab")
			(hide yes)
			(effects
				(font
					(size 0.7 0.7)
					(thickness 0.15)
				)
				(justify right top)
			)
		)
		(fp_text user "${REFERENCE}"
			(at -0.95 3.168 0)
			(layer "F.Fab")
			(hide yes)
			(effects
				(font
					(size 0.7 0.7)
					(thickness 0.15)
				)
				(justify right top)
			)
		)
		(fp_text user "Author: Antmicro"
			(at -0.95 4.169 0)
			(layer "F.Fab")
			(hide yes)
			(effects
				(font
					(size 0.7 0.7)
					(thickness 0.15)
				)
				(justify right top)
			)
		)
		(pad "1" smd roundrect
			(at -0.48 0 180)
			(size 0.59 0.64)
			(layers "F.Cu" "F.Paste" "F.Mask")
			(roundrect_rratio 0.25)
			(net 23 "+3V3")
			(pintype "passive")
		)
		(pad "2" smd roundrect
			(at 0.48 0 180)
			(size 0.59 0.64)
			(layers "F.Cu" "F.Paste" "F.Mask")
			(roundrect_rratio 0.25)
			(net 104 "Net-(U3-RXDET)")
			(pintype "passive")
		)
	)
	(footprint "antmicro-footprints:R_0402_1005Metric"
		(layer "F.Cu")
		(at 146.2 122.15 -90)
		(descr "Resistor SMD 0402")
		(tags "resistor SMD 0402")
		(property "Reference" "R50"
			(at -1.05 -0.5 90)
			(layer "F.SilkS")
			(effects
				(font
					(size 0.7 0.7)
					(thickness 0.15)
				)
				(justify right top)
			)
		)
		(property "Value" "R_0R_0402"
			(at -1.011843 1.772047 90)
			(layer "F.Fab")
			(effects
				(font
					(size 0.7 0.7)
					(thickness 0.15)
				)
				(justify right top)
			)
		)
		(property "Footprint" "antmicro-footprints:R_0402_1005Metric"
			(at 0 0 90)
			(layer "F.Fab")
			(hide yes)
			(effects
				(font
					(size 1.27 1.27)
					(thickness 0.15)
				)
			)
		)
		(property "Datasheet" "https://industrial.panasonic.com/cdbs/www-data/pdf/RDA0000/AOA0000C301.pdf"
			(at 0 0 90)
			(layer "F.Fab")
			(hide yes)
			(effects
				(font
					(size 1.27 1.27)
					(thickness 0.15)
				)
			)
		)
		(property "Description" "SMD Chip Resistor, Jumper, 0 ohm, 100 mW, 0402 [1005 Metric], Thick Film, General Purpose"
			(at 0 0 90)
			(layer "F.Fab")
			(hide yes)
			(effects
				(font
					(size 1.27 1.27)
					(thickness 0.15)
				)
			)
		)
		(property "MPN" "ERJ2GE0R00X"
			(at 0 0 -90)
			(unlocked yes)
			(layer "F.Fab")
			(hide yes)
			(effects
				(font
					(size 1 1)
					(thickness 0.15)
				)
			)
		)
		(property "Manufacturer" "Panasonic"
			(at 0 0 -90)
			(unlocked yes)
			(layer "F.Fab")
			(hide yes)
			(effects
				(font
					(size 1 1)
					(thickness 0.15)
				)
			)
		)
		(property "License" "Apache-2.0"
			(at 0 0 -90)
			(unlocked yes)
			(layer "F.Fab")
			(hide yes)
			(effects
				(font
					(size 1 1)
					(thickness 0.15)
				)
			)
		)
		(property "Author" "Antmicro"
			(at 0 0 -90)
			(unlocked yes)
			(layer "F.Fab")
			(hide yes)
			(effects
				(font
					(size 1 1)
					(thickness 0.15)
				)
			)
		)
		(property "Val" "0R"
			(at 0 0 -90)
			(unlocked yes)
			(layer "F.Fab")
			(hide yes)
			(effects
				(font
					(size 1 1)
					(thickness 0.15)
				)
			)
		)
		(property "Tolerance" ""
			(at 0 0 -90)
			(unlocked yes)
			(layer "F.Fab")
			(hide yes)
			(effects
				(font
					(size 1 1)
					(thickness 0.15)
				)
			)
		)
		(property "Current" "1A"
			(at 0 0 -90)
			(unlocked yes)
			(layer "F.Fab")
			(hide yes)
			(effects
				(font
					(size 1 1)
					(thickness 0.15)
				)
			)
		)
		(sheetname "Root")
		(sheetfile "jetson-orin-baseboard-oculink-expansion.kicad_sch")
		(attr smd)
		(fp_rect
			(start -0.925 -0.47)
			(end 0.925 0.47)
			(stroke
				(width 0.05)
				(type default)
			)
			(fill none)
			(layer "F.CrtYd")
		)
		(fp_rect
			(start -0.5 -0.25)
			(end 0.5 0.25)
			(stroke
				(width 0.15)
				(type solid)
			)
			(fill none)
			(layer "F.Fab")
		)
		(fp_text user "License: Apache-2.0"
			(at -0.95 5.169 90)
			(layer "F.Fab")
			(hide yes)
			(effects
				(font
					(size 0.7 0.7)
					(thickness 0.15)
				)
				(justify right top)
			)
		)
		(fp_text user "${REFERENCE}"
			(at -0.95 3.168 90)
			(layer "F.Fab")
			(hide yes)
			(effects
				(font
					(size 0.7 0.7)
					(thickness 0.15)
				)
				(justify right top)
			)
		)
		(fp_text user "Author: Antmicro"
			(at -0.95 4.169 90)
			(layer "F.Fab")
			(hide yes)
			(effects
				(font
					(size 0.7 0.7)
					(thickness 0.15)
				)
				(justify right top)
			)
		)
		(pad "1" smd roundrect
			(at -0.48 0 270)
			(size 0.59 0.64)
			(layers "F.Cu" "F.Paste" "F.Mask")
			(roundrect_rratio 0.25)
			(net 135 "Net-(U5-OUT)")
			(pintype "passive")
		)
		(pad "2" smd roundrect
			(at 0.48 0 270)
			(size 0.59 0.64)
			(layers "F.Cu" "F.Paste" "F.Mask")
			(roundrect_rratio 0.25)
			(net 133 "+5V_OCU")
			(pintype "passive")
		)
	)
	(footprint "antmicro-footprints:C_0402_1005Metric"
		(layer "F.Cu")
		(at 143.046 127.151 90)
		(descr "Capacitor SMD 0402")
		(tags "capacitor SMD 0402")
		(property "Reference" "C33"
			(at -1.1 -0.546 90)
			(layer "F.SilkS")
			(effects
				(font
					(size 0.7 0.7)
					(thickness 0.15)
				)
				(justify left bottom)
			)
		)
		(property "Value" "C_10u_0402"
			(at -1.022927 2.155213 90)
			(layer "F.Fab")
			(effects
				(font
					(size 0.7 0.7)
					(thickness 0.15)
				)
				(justify left bottom)
			)
		)
		(property "Footprint" "antmicro-footprints:C_0402_1005Metric"
			(at 0 0 90)
			(layer "F.Fab")
			(hide yes)
			(effects
				(font
					(size 1.27 1.27)
					(thickness 0.15)
				)
			)
		)
		(property "Datasheet" "https://www.yageo.com/en/Chart/Download/pdf/CC0402MRX5R5BB106"
			(at 0 0 90)
			(layer "F.Fab")
			(hide yes)
			(effects
				(font
					(size 1.27 1.27)
					(thickness 0.15)
				)
			)
		)
		(property "Description" "SMD Multilayer Ceramic Capacitor, 10 µF, 6.3 V, 0402 [1005 Metric], ± 20%, X5R, CC Series"
			(at 0 0 90)
			(layer "F.Fab")
			(hide yes)
			(effects
				(font
					(size 1.27 1.27)
					(thickness 0.15)
				)
			)
		)
		(property "MPN" "CC0402MRX5R5BB106"
			(at 0 0 90)
			(unlocked yes)
			(layer "F.Fab")
			(hide yes)
			(effects
				(font
					(size 1 1)
					(thickness 0.15)
				)
			)
		)
		(property "Manufacturer" "YAGEO"
			(at 0 0 90)
			(unlocked yes)
			(layer "F.Fab")
			(hide yes)
			(effects
				(font
					(size 1 1)
					(thickness 0.15)
				)
			)
		)
		(property "License" "Apache-2.0"
			(at 0 0 90)
			(unlocked yes)
			(layer "F.Fab")
			(hide yes)
			(effects
				(font
					(size 1 1)
					(thickness 0.15)
				)
			)
		)
		(property "Author" "Antmicro"
			(at 0 0 90)
			(unlocked yes)
			(layer "F.Fab")
			(hide yes)
			(effects
				(font
					(size 1 1)
					(thickness 0.15)
				)
			)
		)
		(property "Val" "10u"
			(at 0 0 90)
			(unlocked yes)
			(layer "F.Fab")
			(hide yes)
			(effects
				(font
					(size 1 1)
					(thickness 0.15)
				)
			)
		)
		(property "Voltage" ""
			(at 0 0 90)
			(unlocked yes)
			(layer "F.Fab")
			(hide yes)
			(effects
				(font
					(size 1 1)
					(thickness 0.15)
				)
			)
		)
		(property "Dielectric" ""
			(at 0 0 90)
			(unlocked yes)
			(layer "F.Fab")
			(hide yes)
			(effects
				(font
					(size 1 1)
					(thickness 0.15)
				)
			)
		)
		(sheetname "Root")
		(sheetfile "jetson-orin-baseboard-oculink-expansion.kicad_sch")
		(attr smd)
		(fp_rect
			(start -0.925 -0.47)
			(end 0.925 0.47)
			(stroke
				(width 0.05)
				(type default)
			)
			(fill none)
			(layer "F.CrtYd")
		)
		(fp_line
			(start 0.504 -0.25)
			(end 0.504 0.248)
			(stroke
				(width 0.15)
				(type solid)
			)
			(layer "F.Fab")
		)
		(fp_line
			(start -0.494 -0.25)
			(end 0.504 -0.25)
			(stroke
				(width 0.15)
				(type solid)
			)
			(layer "F.Fab")
		)
		(fp_line
			(start 0.504 0.248)
			(end -0.494 0.248)
			(stroke
				(width 0.15)
				(type solid)
			)
			(layer "F.Fab")
		)
		(fp_line
			(start -0.494 0.248)
			(end -0.494 -0.25)
			(stroke
				(width 0.15)
				(type solid)
			)
			(layer "F.Fab")
		)
		(fp_text user "Author: Antmicro"
			(at -0.939 3.399 90)
			(layer "F.Fab")
			(hide yes)
			(effects
				(font
					(size 0.7 0.7)
					(thickness 0.15)
				)
				(justify left bottom)
			)
		)
		(fp_text user "License: Apache-2.0"
			(at -0.939 5.799 90)
			(layer "F.Fab")
			(hide yes)
			(effects
				(font
					(size 0.7 0.7)
					(thickness 0.15)
				)
				(justify left bottom)
			)
		)
		(fp_text user "${REFERENCE}"
			(at -0.939 4.599 90)
			(layer "F.Fab")
			(hide yes)
			(effects
				(font
					(size 0.7 0.7)
					(thickness 0.15)
				)
				(justify left bottom)
			)
		)
		(pad "1" smd roundrect
			(at -0.48 0 90)
			(size 0.59 0.64)
			(layers "F.Cu" "F.Paste" "F.Mask")
			(roundrect_rratio 0.25)
			(net 51 "GND")
			(pintype "passive")
		)
		(pad "2" smd roundrect
			(at 0.48 0 90)
			(size 0.59 0.64)
			(layers "F.Cu" "F.Paste" "F.Mask")
			(roundrect_rratio 0.25)
			(net 52 "+5V")
			(pintype "passive")
		)
	)
	(footprint "antmicro-footprints:R_0402_1005Metric"
		(layer "F.Cu")
		(at 145.554 114.56 90)
		(descr "Resistor SMD 0402")
		(tags "resistor SMD 0402")
		(property "Reference" "R43"
			(at -1.04 1.646 90)
			(layer "F.SilkS")
			(effects
				(font
					(size 0.7 0.7)
					(thickness 0.15)
				)
				(justify left bottom)
			)
		)
		(property "Value" "R_10k_0402"
			(at -1.011843 1.772047 90)
			(layer "F.Fab")
			(effects
				(font
					(size 0.7 0.7)
					(thickness 0.15)
				)
				(justify left bottom)
			)
		)
		(property "Footprint" "antmicro-footprints:R_0402_1005Metric"
			(at 0 0 90)
			(layer "F.Fab")
			(hide yes)
			(effects
				(font
					(size 1.27 1.27)
					(thickness 0.15)
				)
			)
		)
		(property "Datasheet" "https://www.bourns.com/docs/product-datasheets/cr.pdf"
			(at 0 0 90)
			(layer "F.Fab")
			(hide yes)
			(effects
				(font
					(size 1.27 1.27)
					(thickness 0.15)
				)
			)
		)
		(property "Description" "SMD Chip Resistor, 10 kohm, ± 1%, 62.5 mW, 0402 [1005 Metric], Thick Film, General Purpose"
			(at 0 0 90)
			(layer "F.Fab")
			(hide yes)
			(effects
				(font
					(size 1.27 1.27)
					(thickness 0.15)
				)
			)
		)
		(property "MPN" "CR0402-FX-1002GLF"
			(at 0 0 90)
			(unlocked yes)
			(layer "F.Fab")
			(hide yes)
			(effects
				(font
					(size 1 1)
					(thickness 0.15)
				)
			)
		)
		(property "Manufacturer" "Bourns"
			(at 0 0 90)
			(unlocked yes)
			(layer "F.Fab")
			(hide yes)
			(effects
				(font
					(size 1 1)
					(thickness 0.15)
				)
			)
		)
		(property "License" "Apache-2.0"
			(at 0 0 90)
			(unlocked yes)
			(layer "F.Fab")
			(hide yes)
			(effects
				(font
					(size 1 1)
					(thickness 0.15)
				)
			)
		)
		(property "Author" "Antmicro"
			(at 0 0 90)
			(unlocked yes)
			(layer "F.Fab")
			(hide yes)
			(effects
				(font
					(size 1 1)
					(thickness 0.15)
				)
			)
		)
		(property "Val" "10k"
			(at 0 0 90)
			(unlocked yes)
			(layer "F.Fab")
			(hide yes)
			(effects
				(font
					(size 1 1)
					(thickness 0.15)
				)
			)
		)
		(property "Tolerance" "1%"
			(at 0 0 90)
			(unlocked yes)
			(layer "F.Fab")
			(hide yes)
			(effects
				(font
					(size 1 1)
					(thickness 0.15)
				)
			)
		)
		(sheetname "Root")
		(sheetfile "jetson-orin-baseboard-oculink-expansion.kicad_sch")
		(attr smd)
		(fp_rect
			(start -0.925 -0.47)
			(end 0.925 0.47)
			(stroke
				(width 0.05)
				(type default)
			)
			(fill none)
			(layer "F.CrtYd")
		)
		(fp_rect
			(start -0.5 -0.25)
			(end 0.5 0.25)
			(stroke
				(width 0.15)
				(type solid)
			)
			(fill none)
			(layer "F.Fab")
		)
		(fp_text user "License: Apache-2.0"
			(at -0.95 5.169 90)
			(layer "F.Fab")
			(hide yes)
			(effects
				(font
					(size 0.7 0.7)
					(thickness 0.15)
				)
				(justify left bottom)
			)
		)
		(fp_text user "${REFERENCE}"
			(at -0.95 3.168 90)
			(layer "F.Fab")
			(hide yes)
			(effects
				(font
					(size 0.7 0.7)
					(thickness 0.15)
				)
				(justify left bottom)
			)
		)
		(fp_text user "Author: Antmicro"
			(at -0.95 4.169 90)
			(layer "F.Fab")
			(hide yes)
			(effects
				(font
					(size 0.7 0.7)
					(thickness 0.15)
				)
				(justify left bottom)
			)
		)
		(pad "1" smd roundrect
			(at -0.48 0 90)
			(size 0.59 0.64)
			(layers "F.Cu" "F.Paste" "F.Mask")
			(roundrect_rratio 0.25)
			(net 23 "+3V3")
			(pintype "passive")
		)
		(pad "2" smd roundrect
			(at 0.48 0 90)
			(size 0.59 0.64)
			(layers "F.Cu" "F.Paste" "F.Mask")
			(roundrect_rratio 0.25)
			(net 136 "Net-(U4-FLG)")
			(pintype "passive")
		)
	)
	(footprint "antmicro-footprints:Conn_Plug_Samtec_ERM8_2x40_ERM8-040-05.0-L-DV-K-TR"
		(layer "F.Cu")
		(at 136.901 119.999 -90)
		(property "Reference" "J2"
			(at -17.699 3.301 90)
			(layer "F.SilkS")
			(effects
				(font
					(size 0.7 0.7)
					(thickness 0.15)
				)
				(justify left bottom)
			)
		)
		(property "Value" "Plug_Samtec_ERM8_2x40_ERM8-040-05.0-L-DV-K-TR"
			(at 0 4.2 90)
			(layer "F.Fab")
			(effects
				(font
					(size 0.7 0.7)
					(thickness 0.15)
				)
				(justify right top)
			)
		)
		(property "Footprint" "antmicro-footprints:Conn_Plug_Samtec_ERM8_2x40_ERM8-040-05.0-L-DV-K-TR"
			(at 0 0 90)
			(layer "F.Fab")
			(hide yes)
			(effects
				(font
					(size 1.27 1.27)
					(thickness 0.15)
				)
			)
		)
		(property "Datasheet" "https://suddendocs.samtec.com/catalog_english/erf8.pdf"
			(at 0 0 90)
			(layer "F.Fab")
			(hide yes)
			(effects
				(font
					(size 1.27 1.27)
					(thickness 0.15)
				)
			)
		)
		(property "Description" "80 Position Connector Header, Center Strip Contacts Surface Mount Gold"
			(at 0 0 90)
			(layer "F.Fab")
			(hide yes)
			(effects
				(font
					(size 1.27 1.27)
					(thickness 0.15)
				)
			)
		)
		(property "MPN" "ERM8-040-05.0-L-DV-K-TR"
			(at 0 0 -90)
			(unlocked yes)
			(layer "F.Fab")
			(hide yes)
			(effects
				(font
					(size 1 1)
					(thickness 0.15)
				)
			)
		)
		(property "Manufacturer" "Samtec"
			(at 0 0 -90)
			(unlocked yes)
			(layer "F.Fab")
			(hide yes)
			(effects
				(font
					(size 1 1)
					(thickness 0.15)
				)
			)
		)
		(property "Author" "Antmicro"
			(at 0 0 -90)
			(unlocked yes)
			(layer "F.Fab")
			(hide yes)
			(effects
				(font
					(size 1 1)
					(thickness 0.15)
				)
			)
		)
		(property "License" "Apache-2.0"
			(at 0 0 -90)
			(unlocked yes)
			(layer "F.Fab")
			(hide yes)
			(effects
				(font
					(size 1 1)
					(thickness 0.15)
				)
			)
		)
		(property "Pitch" "0.8 mm"
			(at 0 0 -90)
			(unlocked yes)
			(layer "F.Fab")
			(hide yes)
			(effects
				(font
					(size 1 1)
					(thickness 0.15)
				)
			)
		)
		(sheetname "Root")
		(sheetfile "jetson-orin-baseboard-oculink-expansion.kicad_sch")
		(attr smd)
		(fp_line
			(start -19 2.797)
			(end 18.998 2.797)
			(stroke
				(width 0.15)
				(type solid)
			)
			(layer "F.SilkS")
		)
		(fp_line
			(start -19 2.797)
			(end -19 -1.2)
			(stroke
				(width 0.15)
				(type solid)
			)
			(layer "F.SilkS")
		)
		(fp_line
			(start -17.401 -2.801)
			(end -19 -1.2)
			(stroke
				(width 0.15)
				(type solid)
			)
			(layer "F.SilkS")
		)
		(fp_line
			(start 18.998 -2.801)
			(end 18.998 2.797)
			(stroke
				(width 0.15)
				(type solid)
			)
			(layer "F.SilkS")
		)
		(fp_line
			(start 18.998 -2.801)
			(end -17.401 -2.801)
			(stroke
				(width 0.15)
				(type solid)
			)
			(layer "F.SilkS")
		)
		(fp_circle
			(center -16.15 -3.4)
			(end -16.1 -3.4)
			(stroke
				(width 0.15)
				(type solid)
			)
			(fill none)
			(layer "F.SilkS")
		)
		(fp_rect
			(start -19.25 -3.06)
			(end 19.23 3.03)
			(stroke
				(width 0.05)
				(type solid)
			)
			(fill none)
			(layer "F.CrtYd")
		)
		(fp_line
			(start -19 2.797)
			(end -19 -1.2)
			(stroke
				(width 0.15)
				(type solid)
			)
			(layer "F.Fab")
		)
		(fp_line
			(start 18.998 2.797)
			(end -19 2.797)
			(stroke
				(width 0.15)
				(type solid)
			)
			(layer "F.Fab")
		)
		(fp_line
			(start -19 -1.2)
			(end -17.401 -2.801)
			(stroke
				(width 0.15)
				(type solid)
			)
			(layer "F.Fab")
		)
		(fp_line
			(start -17.401 -2.801)
			(end 18.998 -2.801)
			(stroke
				(width 0.15)
				(type solid)
			)
			(layer "F.Fab")
		)
		(fp_line
			(start 18.998 -2.801)
			(end 18.998 2.797)
			(stroke
				(width 0.15)
				(type solid)
			)
			(layer "F.Fab")
		)
		(fp_text user "License: Apache-2.0"
			(at -20 6.134 90)
			(layer "F.Fab")
			(hide yes)
			(effects
				(font
					(size 0.7 0.7)
					(thickness 0.15)
				)
				(justify right top)
			)
		)
		(fp_text user "Author: Antmicro"
			(at -20 7.334 90)
			(layer "F.Fab")
			(hide yes)
			(effects
				(font
					(size 0.7 0.7)
					(thickness 0.15)
				)
				(justify right top)
			)
		)
		(fp_text user "${REFERENCE}"
			(at -20 8.534 90)
			(layer "F.Fab")
			(hide yes)
			(effects
				(font
					(size 0.7 0.7)
					(thickness 0.15)
				)
				(justify right top)
			)
		)
		(pad "" np_thru_hole circle
			(at -17.401 1.499 270)
			(size 1.45 1.45)
			(drill 1.45)
			(layers "*.Cu" "*.Mask")
		)
		(pad "" np_thru_hole circle
			(at 17.399 1.499 270)
			(size 1.45 1.45)
			(drill 1.45)
			(layers "*.Cu" "*.Mask")
		)
		(pad "1" smd rect
			(at -15.599 -1.901 270)
			(size 0.5 1.1)
			(layers "F.Cu" "F.Paste" "F.Mask")
			(net 51 "GND")
			(pintype "passive")
		)
		(pad "2" smd rect
			(at -15.599 1.898 270)
			(size 0.5 1.1)
			(layers "F.Cu" "F.Paste" "F.Mask")
			(net 51 "GND")
			(pintype "passive")
		)
		(pad "3" smd rect
			(at -14.801 -1.901 270)
			(size 0.5 1.1)
			(layers "F.Cu" "F.Paste" "F.Mask")
			(net 87 "/PCIE_{I}_TX1-")
			(pintype "passive")
		)
		(pad "4" smd rect
			(at -14.801 1.898 270)
			(size 0.5 1.1)
			(layers "F.Cu" "F.Paste" "F.Mask")
			(net 51 "GND")
			(pintype "passive")
		)
		(pad "5" smd rect
			(at -14 -1.901 270)
			(size 0.5 1.1)
			(layers "F.Cu" "F.Paste" "F.Mask")
			(net 86 "/PCIE_{I}_TX1+")
			(pintype "passive")
		)
		(pad "6" smd rect
			(at -14 1.898 270)
			(size 0.5 1.1)
			(layers "F.Cu" "F.Paste" "F.Mask")
			(net 75 "/PCIE_{I}_RX1-")
			(pintype "passive")
		)
		(pad "7" smd rect
			(at -13.202 -1.901 270)
			(size 0.5 1.1)
			(layers "F.Cu" "F.Paste" "F.Mask")
			(net 51 "GND")
			(pintype "passive")
		)
		(pad "8" smd rect
			(at -13.202 1.898 270)
			(size 0.5 1.1)
			(layers "F.Cu" "F.Paste" "F.Mask")
			(net 79 "/PCIE_{I}_RX1+")
			(pintype "passive")
		)
		(pad "9" smd rect
			(at -12.401 -1.901 270)
			(size 0.5 1.1)
			(layers "F.Cu" "F.Paste" "F.Mask")
			(net 85 "/PCIE_{I}_TX0-")
			(pintype "passive")
		)
		(pad "10" smd rect
			(at -12.401 1.898 270)
			(size 0.5 1.1)
			(layers "F.Cu" "F.Paste" "F.Mask")
			(net 51 "GND")
			(pintype "passive")
		)
		(pad "11" smd rect
			(at -11.599 -1.901 270)
			(size 0.5 1.1)
			(layers "F.Cu" "F.Paste" "F.Mask")
			(net 88 "/PCIE_{I}_TX0+")
			(pintype "passive")
		)
		(pad "12" smd rect
			(at -11.599 1.898 270)
			(size 0.5 1.1)
			(layers "F.Cu" "F.Paste" "F.Mask")
			(net 74 "/PCIE_{I}_RX0-")
			(pintype "passive")
		)
		(pad "13" smd rect
			(at -10.801 -1.901 270)
			(size 0.5 1.1)
			(layers "F.Cu" "F.Paste" "F.Mask")
			(net 51 "GND")
			(pintype "passive")
		)
		(pad "14" smd rect
			(at -10.801 1.898 270)
			(size 0.5 1.1)
			(layers "F.Cu" "F.Paste" "F.Mask")
			(net 78 "/PCIE_{I}_RX0+")
			(pintype "passive")
		)
		(pad "15" smd rect
			(at -10 -1.901 270)
			(size 0.5 1.1)
			(layers "F.Cu" "F.Paste" "F.Mask")
			(net 55 "/PCIE_CLK-")
			(pintype "passive")
		)
		(pad "16" smd rect
			(at -10 1.898 270)
			(size 0.5 1.1)
			(layers "F.Cu" "F.Paste" "F.Mask")
			(net 51 "GND")
			(pintype "passive")
		)
		(pad "17" smd rect
			(at -9.202 -1.901 270)
			(size 0.5 1.1)
			(layers "F.Cu" "F.Paste" "F.Mask")
			(net 53 "/PCIE_CLK+")
			(pintype "passive")
		)
		(pad "18" smd rect
			(at -9.202 1.898 270)
			(size 0.5 1.1)
			(layers "F.Cu" "F.Paste" "F.Mask")
			(net 15 "unconnected-(J2-Pad18)")
			(pintype "passive+no_connect")
		)
		(pad "19" smd rect
			(at -8.401 -1.901 270)
			(size 0.5 1.1)
			(layers "F.Cu" "F.Paste" "F.Mask")
			(net 51 "GND")
			(pintype "passive")
		)
		(pad "20" smd rect
			(at -8.401 1.898 270)
			(size 0.5 1.1)
			(layers "F.Cu" "F.Paste" "F.Mask")
			(net 48 "unconnected-(J2-Pad20)")
			(pintype "passive+no_connect")
		)
		(pad "21" smd rect
			(at -7.601 -1.901 270)
			(size 0.5 1.1)
			(layers "F.Cu" "F.Paste" "F.Mask")
			(net 35 "unconnected-(J2-Pad21)")
			(pintype "passive+no_connect")
		)
		(pad "22" smd rect
			(at -7.601 1.898 270)
			(size 0.5 1.1)
			(layers "F.Cu" "F.Paste" "F.Mask")
			(net 51 "GND")
			(pintype "passive")
		)
		(pad "23" smd rect
			(at -6.8 -1.901 270)
			(size 0.5 1.1)
			(layers "F.Cu" "F.Paste" "F.Mask")
			(net 13 "unconnected-(J2-Pad23)")
			(pintype "passive+no_connect")
		)
		(pad "24" smd rect
			(at -6.8 1.898 270)
			(size 0.5 1.1)
			(layers "F.Cu" "F.Paste" "F.Mask")
			(net 11 "unconnected-(J2-Pad24)")
			(pintype "passive+no_connect")
		)
		(pad "25" smd rect
			(at -6 -1.901 270)
			(size 0.5 1.1)
			(layers "F.Cu" "F.Paste" "F.Mask")
			(net 51 "GND")
			(pintype "passive")
		)
		(pad "26" smd rect
			(at -6 1.898 270)
			(size 0.5 1.1)
			(layers "F.Cu" "F.Paste" "F.Mask")
			(net 14 "unconnected-(J2-Pad26)")
			(pintype "passive+no_connect")
		)
		(pad "27" smd rect
			(at -5.202 -1.901 270)
			(size 0.5 1.1)
			(layers "F.Cu" "F.Paste" "F.Mask")
			(net 59 "/~{PCIE_RST}")
			(pintype "passive")
		)
		(pad "28" smd rect
			(at -5.202 1.898 270)
			(size 0.5 1.1)
			(layers "F.Cu" "F.Paste" "F.Mask")
			(net 51 "GND")
			(pintype "passive")
		)
		(pad "29" smd rect
			(at -4.401 -1.901 270)
			(size 0.5 1.1)
			(layers "F.Cu" "F.Paste" "F.Mask")
			(net 46 "unconnected-(J2-Pad29)")
			(pintype "passive+no_connect")
		)
		(pad "30" smd rect
			(at -4.401 1.898 270)
			(size 0.5 1.1)
			(layers "F.Cu" "F.Paste" "F.Mask")
			(net 33 "unconnected-(J2-Pad30)")
			(pintype "passive+no_connect")
		)
		(pad "31" smd rect
			(at -3.601 -1.901 270)
			(size 0.5 1.1)
			(layers "F.Cu" "F.Paste" "F.Mask")
			(net 27 "unconnected-(J2-Pad31)")
			(pintype "passive+no_connect")
		)
		(pad "32" smd rect
			(at -3.601 1.898 270)
			(size 0.5 1.1)
			(layers "F.Cu" "F.Paste" "F.Mask")
			(net 50 "unconnected-(J2-Pad32)")
			(pintype "passive+no_connect")
		)
		(pad "33" smd rect
			(at -2.802 -1.901 270)
			(size 0.5 1.1)
			(layers "F.Cu" "F.Paste" "F.Mask")
			(net 67 "/JOB_GPIO07")
			(pintype "passive")
		)
		(pad "34" smd rect
			(at -2.802 1.898 270)
			(size 0.5 1.1)
			(layers "F.Cu" "F.Paste" "F.Mask")
			(net 68 "unconnected-(J2-Pad34)")
			(pintype "passive+no_connect")
		)
		(pad "35" smd rect
			(at -2 -1.901 270)
			(size 0.5 1.1)
			(layers "F.Cu" "F.Paste" "F.Mask")
			(net 65 "/JOB_GPIO09")
			(pintype "passive")
		)
		(pad "36" smd rect
			(at -2 1.898 270)
			(size 0.5 1.1)
			(layers "F.Cu" "F.Paste" "F.Mask")
			(net 45 "unconnected-(J2-Pad36)")
			(pintype "passive+no_connect")
		)
		(pad "37" smd rect
			(at -1.2 -1.901 270)
			(size 0.5 1.1)
			(layers "F.Cu" "F.Paste" "F.Mask")
			(net 51 "GND")
			(pintype "passive")
		)
		(pad "38" smd rect
			(at -1.2 1.898 270)
			(size 0.5 1.1)
			(layers "F.Cu" "F.Paste" "F.Mask")
			(net 51 "GND")
			(pintype "passive")
		)
		(pad "39" smd rect
			(at -0.404 -1.901 270)
			(size 0.5 1.1)
			(layers "F.Cu" "F.Paste" "F.Mask")
			(net 38 "unconnected-(J2-Pad39)")
			(pintype "passive+no_connect")
		)
		(pad "40" smd rect
			(at -0.404 1.898 270)
			(size 0.5 1.1)
			(layers "F.Cu" "F.Paste" "F.Mask")
			(net 26 "unconnected-(J2-Pad40)")
			(pintype "passive+no_connect")
		)
		(pad "41" smd rect
			(at 0.4 -1.901 270)
			(size 0.5 1.1)
			(layers "F.Cu" "F.Paste" "F.Mask")
			(net 40 "unconnected-(J2-Pad41)")
			(pintype "passive+no_connect")
		)
		(pad "42" smd rect
			(at 0.4 1.898 270)
			(size 0.5 1.1)
			(layers "F.Cu" "F.Paste" "F.Mask")
			(net 29 "unconnected-(J2-Pad42)")
			(pintype "passive+no_connect")
		)
		(pad "43" smd rect
			(at 1.199 -1.901 270)
			(size 0.5 1.1)
			(layers "F.Cu" "F.Paste" "F.Mask")
			(net 24 "unconnected-(J2-Pad43)")
			(pintype "passive+no_connect")
		)
		(pad "44" smd rect
			(at 1.199 1.898 270)
			(size 0.5 1.1)
			(layers "F.Cu" "F.Paste" "F.Mask")
			(net 42 "unconnected-(J2-Pad44)")
			(pintype "passive+no_connect")
		)
		(pad "45" smd rect
			(at 1.999 -1.901 270)
			(size 0.5 1.1)
			(layers "F.Cu" "F.Paste" "F.Mask")
			(net 39 "unconnected-(J2-Pad45)")
			(pintype "passive+no_connect")
		)
		(pad "46" smd rect
			(at 1.999 1.898 270)
			(size 0.5 1.1)
			(layers "F.Cu" "F.Paste" "F.Mask")
			(net 49 "unconnected-(J2-Pad46)")
			(pintype "passive+no_connect")
		)
		(pad "47" smd rect
			(at 2.797 -1.901 270)
			(size 0.5 1.1)
			(layers "F.Cu" "F.Paste" "F.Mask")
			(net 19 "unconnected-(J2-Pad47)")
			(pintype "passive+no_connect")
		)
		(pad "48" smd rect
			(at 2.797 1.898 270)
			(size 0.5 1.1)
			(layers "F.Cu" "F.Paste" "F.Mask")
			(net 43 "unconnected-(J2-Pad48)")
			(pintype "passive+no_connect")
		)
		(pad "49" smd rect
			(at 3.6 -1.901 270)
			(size 0.5 1.1)
			(layers "F.Cu" "F.Paste" "F.Mask")
			(net 51 "GND")
			(pintype "passive")
		)
		(pad "50" smd rect
			(at 3.6 1.898 270)
			(size 0.5 1.1)
			(layers "F.Cu" "F.Paste" "F.Mask")
			(net 51 "GND")
			(pintype "passive")
		)
		(pad "51" smd rect
			(at 4.4 -1.901 270)
			(size 0.5 1.1)
			(layers "F.Cu" "F.Paste" "F.Mask")
			(net 22 "unconnected-(J2-Pad51)")
			(pintype "passive+no_connect")
		)
		(pad "52" smd rect
			(at 4.4 1.898 270)
			(size 0.5 1.1)
			(layers "F.Cu" "F.Paste" "F.Mask")
			(net 28 "unconnected-(J2-Pad52)")
			(pintype "passive+no_connect")
		)
		(pad "53" smd rect
			(at 5.2 -1.901 270)
			(size 0.5 1.1)
			(layers "F.Cu" "F.Paste" "F.Mask")
			(net 10 "unconnected-(J2-Pad53)")
			(pintype "passive+no_connect")
		)
		(pad "54" smd rect
			(at 5.2 1.898 270)
			(size 0.5 1.1)
			(layers "F.Cu" "F.Paste" "F.Mask")
			(net 18 "unconnected-(J2-Pad54)")
			(pintype "passive+no_connect")
		)
		(pad "55" smd rect
			(at 5.998 -1.901 270)
			(size 0.5 1.1)
			(layers "F.Cu" "F.Paste" "F.Mask")
			(net 25 "unconnected-(J2-Pad55)")
			(pintype "passive+no_connect")
		)
		(pad "56" smd rect
			(at 5.998 1.898 270)
			(size 0.5 1.1)
			(layers "F.Cu" "F.Paste" "F.Mask")
			(net 34 "unconnected-(J2-Pad56)")
			(pintype "passive+no_connect")
		)
		(pad "57" smd rect
			(at 6.799 -1.901 270)
			(size 0.5 1.1)
			(layers "F.Cu" "F.Paste" "F.Mask")
			(net 21 "unconnected-(J2-Pad57)")
			(pintype "passive+no_connect")
		)
		(pad "58" smd rect
			(at 6.799 1.898 270)
			(size 0.5 1.1)
			(layers "F.Cu" "F.Paste" "F.Mask")
			(net 12 "unconnected-(J2-Pad58)")
			(pintype "passive+no_connect")
		)
		(pad "59" smd rect
			(at 7.599 -1.901 270)
			(size 0.5 1.1)
			(layers "F.Cu" "F.Paste" "F.Mask")
			(net 17 "unconnected-(J2-Pad59)")
			(pintype "passive+no_connect")
		)
		(pad "60" smd rect
			(at 7.599 1.898 270)
			(size 0.5 1.1)
			(layers "F.Cu" "F.Paste" "F.Mask")
			(net 41 "unconnected-(J2-Pad60)")
			(pintype "passive+no_connect")
		)
		(pad "61" smd rect
			(at 8.4 -1.901 270)
			(size 0.5 1.1)
			(layers "F.Cu" "F.Paste" "F.Mask")
			(net 51 "GND")
			(pintype "passive")
		)
		(pad "62" smd rect
			(at 8.4 1.898 270)
			(size 0.5 1.1)
			(layers "F.Cu" "F.Paste" "F.Mask")
			(net 51 "GND")
			(pintype "passive")
		)
		(pad "63" smd rect
			(at 9.198 -1.901 270)
			(size 0.5 1.1)
			(layers "F.Cu" "F.Paste" "F.Mask")
			(net 61 "/I2C_SDA")
			(pintype "passive")
		)
		(pad "64" smd rect
			(at 9.198 1.898 270)
			(size 0.5 1.1)
			(layers "F.Cu" "F.Paste" "F.Mask")
			(net 32 "unconnected-(J2-Pad64)")
			(pintype "passive+no_connect")
		)
		(pad "65" smd rect
			(at 9.999 -1.901 270)
			(size 0.5 1.1)
			(layers "F.Cu" "F.Paste" "F.Mask")
			(net 64 "/I2C_SCL")
			(pintype "passive")
		)
		(pad "66" smd rect
			(at 9.999 1.898 270)
			(size 0.5 1.1)
			(layers "F.Cu" "F.Paste" "F.Mask")
			(net 47 "unconnected-(J2-Pad66)")
			(pintype "passive+no_connect")
		)
		(pad "67" smd rect
			(at 10.8 -1.901 270)
			(size 0.5 1.1)
			(layers "F.Cu" "F.Paste" "F.Mask")
			(net 23 "+3V3")
			(pintype "passive")
		)
		(pad "68" smd rect
			(at 10.8 1.898 270)
			(size 0.5 1.1)
			(layers "F.Cu" "F.Paste" "F.Mask")
			(net 16 "unconnected-(J2-Pad68)")
			(pintype "passive+no_connect")
		)
		(pad "69" smd rect
			(at 11.598 -1.901 270)
			(size 0.5 1.1)
			(layers "F.Cu" "F.Paste" "F.Mask")
			(net 23 "+3V3")
			(pintype "passive")
		)
		(pad "70" smd rect
			(at 11.598 1.898 270)
			(size 0.5 1.1)
			(layers "F.Cu" "F.Paste" "F.Mask")
			(net 30 "unconnected-(J2-Pad70)")
			(pintype "passive+no_connect")
		)
		(pad "71" smd rect
			(at 12.4 -1.901 270)
			(size 0.5 1.1)
			(layers "F.Cu" "F.Paste" "F.Mask")
			(net 51 "GND")
			(pintype "passive")
		)
		(pad "72" smd rect
			(at 12.4 1.898 270)
			(size 0.5 1.1)
			(layers "F.Cu" "F.Paste" "F.Mask")
			(net 51 "GND")
			(pintype "passive")
		)
		(pad "73" smd rect
			(at 13.198 -1.901 270)
			(size 0.5 1.1)
			(layers "F.Cu" "F.Paste" "F.Mask")
			(net 20 "+1V8")
			(pintype "passive")
		)
		(pad "74" smd rect
			(at 13.198 1.898 270)
			(size 0.5 1.1)
			(layers "F.Cu" "F.Paste" "F.Mask")
			(net 44 "unconnected-(J2-Pad74)")
			(pintype "passive+no_connect")
		)
		(pad "75" smd rect
			(at 13.999 -1.901 270)
			(size 0.5 1.1)
			(layers "F.Cu" "F.Paste" "F.Mask")
			(net 51 "GND")
			(pintype "passive")
		)
		(pad "76" smd rect
			(at 13.999 1.898 270)
			(size 0.5 1.1)
			(layers "F.Cu" "F.Paste" "F.Mask")
			(net 51 "GND")
			(pintype "passive")
		)
		(pad "77" smd rect
			(at 14.8 -1.901 270)
			(size 0.5 1.1)
			(layers "F.Cu" "F.Paste" "F.Mask")
			(net 52 "+5V")
			(pintype "passive")
		)
		(pad "78" smd rect
			(at 14.8 1.898 270)
			(size 0.5 1.1)
			(layers "F.Cu" "F.Paste" "F.Mask")
			(net 37 "unconnected-(J2-Pad78)")
			(pintype "passive+no_connect")
		)
		(pad "79" smd rect
			(at 15.598 -1.901 270)
			(size 0.5 1.1)
			(layers "F.Cu" "F.Paste" "F.Mask")
			(net 52 "+5V")
			(pintype "passive")
		)
		(pad "80" smd rect
			(at 15.598 1.898 270)
			(size 0.5 1.1)
			(layers "F.Cu" "F.Paste" "F.Mask")
			(net 36 "unconnected-(J2-Pad80)")
			(pintype "passive+no_connect")
		)
	)
	(footprint "antmicro-footprints:C_0805_2012Metric"
		(layer "F.Cu")
		(at 143.6 116.499)
		(descr "Capacitor SMD 0805")
		(tags "capacitor SMD 0805")
		(property "Reference" "C32"
			(at -1.05 -0.899 0)
			(layer "F.SilkS")
			(effects
				(font
					(size 0.7 0.7)
					(thickness 0.15)
				)
				(justify left bottom)
			)
		)
		(property "Value" "C_100u_0805"
			(at -2.055717 1.963152 0)
			(layer "F.Fab")
			(effects
				(font
					(size 0.7 0.7)
					(thickness 0.15)
				)
				(justify left bottom)
			)
		)
		(property "Footprint" "antmicro-footprints:C_0805_2012Metric"
			(at 0 0 0)
			(layer "F.Fab")
			(hide yes)
			(effects
				(font
					(size 1.27 1.27)
					(thickness 0.15)
				)
			)
		)
		(property "Datasheet" "https://www.murata.com/products/productdetail?partno=GRM21BR60J107ME15%23"
			(at 0 0 0)
			(layer "F.Fab")
			(hide yes)
			(effects
				(font
					(size 1.27 1.27)
					(thickness 0.15)
				)
			)
		)
		(property "Description" "SMD Multilayer Ceramic Capacitor, 100 µF, 6.3 V, 0805 [2012 Metric], ± 20%, X5R, GRM Series"
			(at 0 0 0)
			(layer "F.Fab")
			(hide yes)
			(effects
				(font
					(size 1.27 1.27)
					(thickness 0.15)
				)
			)
		)
		(property "MPN" "GRM21BR60J107ME15L"
			(at 0 0 0)
			(unlocked yes)
			(layer "F.Fab")
			(hide yes)
			(effects
				(font
					(size 1 1)
					(thickness 0.15)
				)
			)
		)
		(property "Manufacturer" "Murata"
			(at 0 0 0)
			(unlocked yes)
			(layer "F.Fab")
			(hide yes)
			(effects
				(font
					(size 1 1)
					(thickness 0.15)
				)
			)
		)
		(property "License" "Apache-2.0"
			(at 0 0 0)
			(unlocked yes)
			(layer "F.Fab")
			(hide yes)
			(effects
				(font
					(size 1 1)
					(thickness 0.15)
				)
			)
		)
		(property "Author" "Antmicro"
			(at 0 0 0)
			(unlocked yes)
			(layer "F.Fab")
			(hide yes)
			(effects
				(font
					(size 1 1)
					(thickness 0.15)
				)
			)
		)
		(property "Val" "100u"
			(at 0 0 0)
			(unlocked yes)
			(layer "F.Fab")
			(hide yes)
			(effects
				(font
					(size 1 1)
					(thickness 0.15)
				)
			)
		)
		(property "Voltage" ""
			(at 0 0 0)
			(unlocked yes)
			(layer "F.Fab")
			(hide yes)
			(effects
				(font
					(size 1 1)
					(thickness 0.15)
				)
			)
		)
		(property "Dielectric" ""
			(at 0 0 0)
			(unlocked yes)
			(layer "F.Fab")
			(hide yes)
			(effects
				(font
					(size 1 1)
					(thickness 0.15)
				)
			)
		)
		(property "Public" "False"
			(at 0 0 0)
			(unlocked yes)
			(layer "F.Fab")
			(hide yes)
			(effects
				(font
					(size 1 1)
					(thickness 0.15)
				)
			)
		)
		(sheetname "Root")
		(sheetfile "jetson-orin-baseboard-oculink-expansion.kicad_sch")
		(attr smd)
		(fp_line
			(start -0.3 -0.7)
			(end 0.3 -0.7)
			(stroke
				(width 0.15)
				(type solid)
			)
			(layer "F.SilkS")
		)
		(fp_line
			(start -0.3 0.7)
			(end 0.3 0.7)
			(stroke
				(width 0.15)
				(type solid)
			)
			(layer "F.SilkS")
		)
		(fp_rect
			(start 1.95 -0.9)
			(end -1.95 0.9)
			(stroke
				(width 0.05)
				(type default)
			)
			(fill none)
			(layer "F.CrtYd")
		)
		(fp_rect
			(start -0.95 -0.675)
			(end 0.95 0.675)
			(stroke
				(width 0.15)
				(type solid)
			)
			(fill none)
			(layer "F.Fab")
		)
		(fp_text user "Author: Antmicro"
			(at -1.9 5.947 0)
			(layer "F.Fab")
			(hide yes)
			(effects
				(font
					(size 0.7 0.7)
					(thickness 0.15)
				)
				(justify left bottom)
			)
		)
		(fp_text user "License: Apache-2.0"
			(at -1.9 4.947 0)
			(layer "F.Fab")
			(hide yes)
			(effects
				(font
					(size 0.7 0.7)
					(thickness 0.15)
				)
				(justify left bottom)
			)
		)
		(fp_text user "${REFERENCE}"
			(at -1.9 3.947 0)
			(layer "F.Fab")
			(hide yes)
			(effects
				(font
					(size 0.7 0.7)
					(thickness 0.15)
				)
				(justify left bottom)
			)
		)
		(pad "1" smd roundrect
			(at -1.1 0)
			(size 1.2 1.3)
			(layers "F.Cu" "F.Paste" "F.Mask")
			(roundrect_rratio 0.25)
			(net 51 "GND")
			(pintype "passive")
		)
		(pad "2" smd roundrect
			(at 1.1 0)
			(size 1.2 1.3)
			(layers "F.Cu" "F.Paste" "F.Mask")
			(roundrect_rratio 0.25)
			(net 134 "Net-(U4-OUT)")
			(pintype "passive")
		)
	)
	(footprint "antmicro-footprints:TP_SMD_0.75mm"
		(layer "F.Cu")
		(at 131.01 114.64 180)
		(property "Reference" "TP18"
			(at -1.83 1.27 180)
			(layer "F.SilkS")
			(effects
				(font
					(size 0.7 0.7)
					(thickness 0.15)
				)
				(justify right top)
			)
		)
		(property "Value" "TP_0.75mm_SMD"
			(at 0 1.2 0)
			(layer "F.Fab")
			(effects
				(font
					(size 0.7 0.7)
					(thickness 0.15)
				)
				(justify right top)
			)
		)
		(property "Footprint" "antmicro-footprints:TP_SMD_0.75mm"
			(at 0 0 0)
			(layer "F.Fab")
			(hide yes)
			(effects
				(font
					(size 1.27 1.27)
					(thickness 0.15)
				)
			)
		)
		(property "Description" "SMT test point"
			(at 0 0 0)
			(layer "F.Fab")
			(hide yes)
			(effects
				(font
					(size 1.27 1.27)
					(thickness 0.15)
				)
			)
		)
		(property "MPN" ""
			(at 0 0 180)
			(unlocked yes)
			(layer "F.Fab")
			(hide yes)
			(effects
				(font
					(size 1 1)
					(thickness 0.15)
				)
			)
		)
		(property "Manufacturer" ""
			(at 0 0 180)
			(unlocked yes)
			(layer "F.Fab")
			(hide yes)
			(effects
				(font
					(size 1 1)
					(thickness 0.15)
				)
			)
		)
		(property "Author" "Antmicro"
			(at 0 0 180)
			(unlocked yes)
			(layer "F.Fab")
			(hide yes)
			(effects
				(font
					(size 1 1)
					(thickness 0.15)
				)
			)
		)
		(property "License" "Apache-2.0"
			(at 0 0 180)
			(unlocked yes)
			(layer "F.Fab")
			(hide yes)
			(effects
				(font
					(size 1 1)
					(thickness 0.15)
				)
			)
		)
		(property "Public" "False"
			(at 0 0 180)
			(unlocked yes)
			(layer "F.Fab")
			(hide yes)
			(effects
				(font
					(size 1 1)
					(thickness 0.15)
				)
			)
		)
		(sheetname "Root")
		(sheetfile "jetson-orin-baseboard-oculink-expansion.kicad_sch")
		(attr exclude_from_pos_files exclude_from_bom)
		(fp_circle
			(center 0 0)
			(end 0.475 0)
			(stroke
				(width 0.05)
				(type default)
			)
			(fill none)
			(layer "F.CrtYd")
		)
		(fp_text user "License: Apache-2.0"
			(at -0.4 5.101 0)
			(layer "F.Fab")
			(hide yes)
			(effects
				(font
					(size 0.7 0.7)
					(thickness 0.15)
				)
				(justify right top)
			)
		)
		(fp_text user "Author: Antmicro"
			(at -0.4 3.901 0)
			(layer "F.Fab")
			(hide yes)
			(effects
				(font
					(size 0.7 0.7)
					(thickness 0.15)
				)
				(justify right top)
			)
		)
		(fp_text user "${REFERENCE}"
			(at -0.4 2.7 0)
			(layer "F.Fab")
			(hide yes)
			(effects
				(font
					(size 0.7 0.7)
					(thickness 0.15)
				)
				(justify right top)
			)
		)
		(pad "1" smd circle
			(at 0 0 180)
			(size 0.75 0.75)
			(layers "F.Cu" "F.Mask")
			(net 106 "Net-(U2-SCL)")
			(pinfunction "1")
			(pintype "passive")
		)
	)
	(footprint "antmicro-footprints:MP_Pad5.4mm_Drill2.7mm"
		(layer "F.Cu")
		(at 135.9 144.97)
		(descr "Mounting Hole 2.7mm, M2.5")
		(tags "mounting hole 2.7mm m2.5")
		(property "Reference" "MP1"
			(at -2.6 -2.27 90)
			(layer "F.SilkS")
			(effects
				(font
					(size 0.7 0.7)
					(thickness 0.15)
				)
				(justify left bottom)
			)
		)
		(property "Value" "MP_Pad5.4mm_Drill2.7mm"
			(at 0 3.6 0)
			(layer "F.Fab")
			(effects
				(font
					(size 0.7 0.7)
					(thickness 0.15)
				)
				(justify left bottom)
			)
		)
		(property "Footprint" "antmicro-footprints:MP_Pad5.4mm_Drill2.7mm"
			(at 0 0 0)
			(layer "F.Fab")
			(hide yes)
			(effects
				(font
					(size 1.27 1.27)
					(thickness 0.15)
				)
			)
		)
		(property "Description" "Mechanical part"
			(at 0 0 0)
			(layer "F.Fab")
			(hide yes)
			(effects
				(font
					(size 1.27 1.27)
					(thickness 0.15)
				)
			)
		)
		(property "Author" "Antmicro"
			(at 0 0 0)
			(unlocked yes)
			(layer "F.Fab")
			(hide yes)
			(effects
				(font
					(size 1 1)
					(thickness 0.15)
				)
			)
		)
		(property "License" "Apache-2.0"
			(at 0 0 0)
			(unlocked yes)
			(layer "F.Fab")
			(hide yes)
			(effects
				(font
					(size 1 1)
					(thickness 0.15)
				)
			)
		)
		(sheetname "Root")
		(sheetfile "jetson-orin-baseboard-oculink-expansion.kicad_sch")
		(attr exclude_from_pos_files exclude_from_bom)
		(fp_circle
			(center 0 0)
			(end 2.95 0)
			(stroke
				(width 0.05)
				(type default)
			)
			(fill none)
			(layer "F.CrtYd")
		)
		(fp_text user "License: Apache-2.0"
			(at -8.4 8.4 0)
			(layer "F.Fab")
			(hide yes)
			(effects
				(font
					(size 0.7 0.7)
					(thickness 0.15)
				)
				(justify left bottom)
			)
		)
		(fp_text user "Author: Antmicro"
			(at -8.4 7.2 0)
			(layer "F.Fab")
			(hide yes)
			(effects
				(font
					(size 0.7 0.7)
					(thickness 0.15)
				)
				(justify left bottom)
			)
		)
		(fp_text user "${REFERENCE}"
			(at -8.4 6 0)
			(layer "F.Fab")
			(hide yes)
			(effects
				(font
					(size 0.7 0.7)
					(thickness 0.15)
				)
				(justify left bottom)
			)
		)
		(pad "1" thru_hole circle
			(at 0 0)
			(size 5.4 5.4)
			(drill 2.7)
			(layers "*.Cu" "*.Mask")
			(remove_unused_layers no)
			(net 51 "GND")
			(pintype "passive")
			(solder_paste_margin_ratio -1)
		)
	)
	(footprint "antmicro-footprints:C_0402_1005Metric"
		(layer "F.Cu")
		(at 128.75 144.65 90)
		(descr "Capacitor SMD 0402")
		(tags "capacitor SMD 0402")
		(property "Reference" "C2"
			(at -0.830534 -0.62175 90)
			(layer "F.SilkS")
			(effects
				(font
					(size 0.7 0.7)
					(thickness 0.15)
				)
				(justify left bottom)
			)
		)
		(property "Value" "C_10u_0402"
			(at -1.022927 2.155213 90)
			(layer "F.Fab")
			(effects
				(font
					(size 0.7 0.7)
					(thickness 0.15)
				)
				(justify left bottom)
			)
		)
		(property "Footprint" "antmicro-footprints:C_0402_1005Metric"
			(at 0 0 90)
			(layer "F.Fab")
			(hide yes)
			(effects
				(font
					(size 1.27 1.27)
					(thickness 0.15)
				)
			)
		)
		(property "Datasheet" "https://www.yageo.com/en/Chart/Download/pdf/CC0402MRX5R5BB106"
			(at 0 0 90)
			(layer "F.Fab")
			(hide yes)
			(effects
				(font
					(size 1.27 1.27)
					(thickness 0.15)
				)
			)
		)
		(property "Description" "SMD Multilayer Ceramic Capacitor, 10 µF, 6.3 V, 0402 [1005 Metric], ± 20%, X5R, CC Series"
			(at 0 0 90)
			(layer "F.Fab")
			(hide yes)
			(effects
				(font
					(size 1.27 1.27)
					(thickness 0.15)
				)
			)
		)
		(property "MPN" "CC0402MRX5R5BB106"
			(at 0 0 90)
			(unlocked yes)
			(layer "F.Fab")
			(hide yes)
			(effects
				(font
					(size 1 1)
					(thickness 0.15)
				)
			)
		)
		(property "Manufacturer" "YAGEO"
			(at 0 0 90)
			(unlocked yes)
			(layer "F.Fab")
			(hide yes)
			(effects
				(font
					(size 1 1)
					(thickness 0.15)
				)
			)
		)
		(property "License" "Apache-2.0"
			(at 0 0 90)
			(unlocked yes)
			(layer "F.Fab")
			(hide yes)
			(effects
				(font
					(size 1 1)
					(thickness 0.15)
				)
			)
		)
		(property "Author" "Antmicro"
			(at 0 0 90)
			(unlocked yes)
			(layer "F.Fab")
			(hide yes)
			(effects
				(font
					(size 1 1)
					(thickness 0.15)
				)
			)
		)
		(property "Val" "10u"
			(at 0 0 90)
			(unlocked yes)
			(layer "F.Fab")
			(hide yes)
			(effects
				(font
					(size 1 1)
					(thickness 0.15)
				)
			)
		)
		(property "Voltage" ""
			(at 0 0 90)
			(unlocked yes)
			(layer "F.Fab")
			(hide yes)
			(effects
				(font
					(size 1 1)
					(thickness 0.15)
				)
			)
		)
		(property "Dielectric" ""
			(at 0 0 90)
			(unlocked yes)
			(layer "F.Fab")
			(hide yes)
			(effects
				(font
					(size 1 1)
					(thickness 0.15)
				)
			)
		)
		(sheetname "Root")
		(sheetfile "jetson-orin-baseboard-oculink-expansion.kicad_sch")
		(attr smd)
		(fp_rect
			(start -0.925 -0.47)
			(end 0.925 0.47)
			(stroke
				(width 0.05)
				(type default)
			)
			(fill none)
			(layer "F.CrtYd")
		)
		(fp_line
			(start 0.504 -0.25)
			(end 0.504 0.248)
			(stroke
				(width 0.15)
				(type solid)
			)
			(layer "F.Fab")
		)
		(fp_line
			(start -0.494 -0.25)
			(end 0.504 -0.25)
			(stroke
				(width 0.15)
				(type solid)
			)
			(layer "F.Fab")
		)
		(fp_line
			(start 0.504 0.248)
			(end -0.494 0.248)
			(stroke
				(width 0.15)
				(type solid)
			)
			(layer "F.Fab")
		)
		(fp_line
			(start -0.494 0.248)
			(end -0.494 -0.25)
			(stroke
				(width 0.15)
				(type solid)
			)
			(layer "F.Fab")
		)
		(fp_text user "License: Apache-2.0"
			(at -0.939 5.799 90)
			(layer "F.Fab")
			(hide yes)
			(effects
				(font
					(size 0.7 0.7)
					(thickness 0.15)
				)
				(justify left bottom)
			)
		)
		(fp_text user "${REFERENCE}"
			(at -0.939 4.599 90)
			(layer "F.Fab")
			(hide yes)
			(effects
				(font
					(size 0.7 0.7)
					(thickness 0.15)
				)
				(justify left bottom)
			)
		)
		(fp_text user "Author: Antmicro"
			(at -0.939 3.399 90)
			(layer "F.Fab")
			(hide yes)
			(effects
				(font
					(size 0.7 0.7)
					(thickness 0.15)
				)
				(justify left bottom)
			)
		)
		(pad "1" smd roundrect
			(at -0.48 0 90)
			(size 0.59 0.64)
			(layers "F.Cu" "F.Paste" "F.Mask")
			(roundrect_rratio 0.25)
			(net 51 "GND")
			(pintype "passive")
		)
		(pad "2" smd roundrect
			(at 0.48 0 90)
			(size 0.59 0.64)
			(layers "F.Cu" "F.Paste" "F.Mask")
			(roundrect_rratio 0.25)
			(net 133 "+5V_OCU")
			(pintype "passive")
		)
	)
	(footprint "antmicro-footprints:C_0402_1005Metric"
		(layer "F.Cu")
		(at 124.2 141.1)
		(descr "Capacitor SMD 0402")
		(tags "capacitor SMD 0402")
		(property "Reference" "C1"
			(at 2.37325 -0.501466 0)
			(layer "F.SilkS")
			(effects
				(font
					(size 0.7 0.7)
					(thickness 0.15)
				)
				(justify right top)
			)
		)
		(property "Value" "C_10u_0402"
			(at -1.022927 2.155213 0)
			(layer "F.Fab")
			(effects
				(font
					(size 0.7 0.7)
					(thickness 0.15)
				)
				(justify left bottom)
			)
		)
		(property "Footprint" "antmicro-footprints:C_0402_1005Metric"
			(at 0 0 0)
			(layer "F.Fab")
			(hide yes)
			(effects
				(font
					(size 1.27 1.27)
					(thickness 0.15)
				)
			)
		)
		(property "Datasheet" "https://www.yageo.com/en/Chart/Download/pdf/CC0402MRX5R5BB106"
			(at 0 0 0)
			(layer "F.Fab")
			(hide yes)
			(effects
				(font
					(size 1.27 1.27)
					(thickness 0.15)
				)
			)
		)
		(property "Description" "SMD Multilayer Ceramic Capacitor, 10 µF, 6.3 V, 0402 [1005 Metric], ± 20%, X5R, CC Series"
			(at 0 0 0)
			(layer "F.Fab")
			(hide yes)
			(effects
				(font
					(size 1.27 1.27)
					(thickness 0.15)
				)
			)
		)
		(property "MPN" "CC0402MRX5R5BB106"
			(at 0 0 0)
			(unlocked yes)
			(layer "F.Fab")
			(hide yes)
			(effects
				(font
					(size 1 1)
					(thickness 0.15)
				)
			)
		)
		(property "Manufacturer" "YAGEO"
			(at 0 0 0)
			(unlocked yes)
			(layer "F.Fab")
			(hide yes)
			(effects
				(font
					(size 1 1)
					(thickness 0.15)
				)
			)
		)
		(property "License" "Apache-2.0"
			(at 0 0 0)
			(unlocked yes)
			(layer "F.Fab")
			(hide yes)
			(effects
				(font
					(size 1 1)
					(thickness 0.15)
				)
			)
		)
		(property "Author" "Antmicro"
			(at 0 0 0)
			(unlocked yes)
			(layer "F.Fab")
			(hide yes)
			(effects
				(font
					(size 1 1)
					(thickness 0.15)
				)
			)
		)
		(property "Val" "10u"
			(at 0 0 0)
			(unlocked yes)
			(layer "F.Fab")
			(hide yes)
			(effects
				(font
					(size 1 1)
					(thickness 0.15)
				)
			)
		)
		(property "Voltage" ""
			(at 0 0 0)
			(unlocked yes)
			(layer "F.Fab")
			(hide yes)
			(effects
				(font
					(size 1 1)
					(thickness 0.15)
				)
			)
		)
		(property "Dielectric" ""
			(at 0 0 0)
			(unlocked yes)
			(layer "F.Fab")
			(hide yes)
			(effects
				(font
					(size 1 1)
					(thickness 0.15)
				)
			)
		)
		(sheetname "Root")
		(sheetfile "jetson-orin-baseboard-oculink-expansion.kicad_sch")
		(attr smd)
		(fp_rect
			(start -0.925 -0.47)
			(end 0.925 0.47)
			(stroke
				(width 0.05)
				(type default)
			)
			(fill none)
			(layer "F.CrtYd")
		)
		(fp_line
			(start -0.494 -0.25)
			(end 0.504 -0.25)
			(stroke
				(width 0.15)
				(type solid)
			)
			(layer "F.Fab")
		)
		(fp_line
			(start -0.494 0.248)
			(end -0.494 -0.25)
			(stroke
				(width 0.15)
				(type solid)
			)
			(layer "F.Fab")
		)
		(fp_line
			(start 0.504 -0.25)
			(end 0.504 0.248)
			(stroke
				(width 0.15)
				(type solid)
			)
			(layer "F.Fab")
		)
		(fp_line
			(start 0.504 0.248)
			(end -0.494 0.248)
			(stroke
				(width 0.15)
				(type solid)
			)
			(layer "F.Fab")
		)
		(fp_text user "License: Apache-2.0"
			(at -0.939 5.799 0)
			(layer "F.Fab")
			(hide yes)
			(effects
				(font
					(size 0.7 0.7)
					(thickness 0.15)
				)
				(justify left bottom)
			)
		)
		(fp_text user "Author: Antmicro"
			(at -0.939 3.399 0)
			(layer "F.Fab")
			(hide yes)
			(effects
				(font
					(size 0.7 0.7)
					(thickness 0.15)
				)
				(justify left bottom)
			)
		)
		(fp_text user "${REFERENCE}"
			(at -0.939 4.599 0)
			(layer "F.Fab")
			(hide yes)
			(effects
				(font
					(size 0.7 0.7)
					(thickness 0.15)
				)
				(justify left bottom)
			)
		)
		(pad "1" smd roundrect
			(at -0.48 0)
			(size 0.59 0.64)
			(layers "F.Cu" "F.Paste" "F.Mask")
			(roundrect_rratio 0.25)
			(net 51 "GND")
			(pintype "passive")
		)
		(pad "2" smd roundrect
			(at 0.48 0)
			(size 0.59 0.64)
			(layers "F.Cu" "F.Paste" "F.Mask")
			(roundrect_rratio 0.25)
			(net 132 "+3V3_OCU")
			(pintype "passive")
		)
	)
	(footprint "antmicro-footprints:R_0402_1005Metric"
		(layer "F.Cu")
		(at 146.2 116.979 -90)
		(descr "Resistor SMD 0402")
		(tags "resistor SMD 0402")
		(property "Reference" "R49"
			(at -1.079 -0.4 -90)
			(layer "F.SilkS")
			(effects
				(font
					(size 0.7 0.7)
					(thickness 0.15)
				)
				(justify right top)
			)
		)
		(property "Value" "R_0R_0402"
			(at -1.011843 1.772047 90)
			(layer "F.Fab")
			(effects
				(font
					(size 0.7 0.7)
					(thickness 0.15)
				)
				(justify right top)
			)
		)
		(property "Footprint" "antmicro-footprints:R_0402_1005Metric"
			(at 0 0 90)
			(layer "F.Fab")
			(hide yes)
			(effects
				(font
					(size 1.27 1.27)
					(thickness 0.15)
				)
			)
		)
		(property "Datasheet" "https://industrial.panasonic.com/cdbs/www-data/pdf/RDA0000/AOA0000C301.pdf"
			(at 0 0 90)
			(layer "F.Fab")
			(hide yes)
			(effects
				(font
					(size 1.27 1.27)
					(thickness 0.15)
				)
			)
		)
		(property "Description" "SMD Chip Resistor, Jumper, 0 ohm, 100 mW, 0402 [1005 Metric], Thick Film, General Purpose"
			(at 0 0 90)
			(layer "F.Fab")
			(hide yes)
			(effects
				(font
					(size 1.27 1.27)
					(thickness 0.15)
				)
			)
		)
		(property "MPN" "ERJ2GE0R00X"
			(at 0 0 -90)
			(unlocked yes)
			(layer "F.Fab")
			(hide yes)
			(effects
				(font
					(size 1 1)
					(thickness 0.15)
				)
			)
		)
		(property "Manufacturer" "Panasonic"
			(at 0 0 -90)
			(unlocked yes)
			(layer "F.Fab")
			(hide yes)
			(effects
				(font
					(size 1 1)
					(thickness 0.15)
				)
			)
		)
		(property "License" "Apache-2.0"
			(at 0 0 -90)
			(unlocked yes)
			(layer "F.Fab")
			(hide yes)
			(effects
				(font
					(size 1 1)
					(thickness 0.15)
				)
			)
		)
		(property "Author" "Antmicro"
			(at 0 0 -90)
			(unlocked yes)
			(layer "F.Fab")
			(hide yes)
			(effects
				(font
					(size 1 1)
					(thickness 0.15)
				)
			)
		)
		(property "Val" "0R"
			(at 0 0 -90)
			(unlocked yes)
			(layer "F.Fab")
			(hide yes)
			(effects
				(font
					(size 1 1)
					(thickness 0.15)
				)
			)
		)
		(property "Tolerance" ""
			(at 0 0 -90)
			(unlocked yes)
			(layer "F.Fab")
			(hide yes)
			(effects
				(font
					(size 1 1)
					(thickness 0.15)
				)
			)
		)
		(property "Current" "1A"
			(at 0 0 -90)
			(unlocked yes)
			(layer "F.Fab")
			(hide yes)
			(effects
				(font
					(size 1 1)
					(thickness 0.15)
				)
			)
		)
		(sheetname "Root")
		(sheetfile "jetson-orin-baseboard-oculink-expansion.kicad_sch")
		(attr smd)
		(fp_rect
			(start -0.925 -0.47)
			(end 0.925 0.47)
			(stroke
				(width 0.05)
				(type default)
			)
			(fill none)
			(layer "F.CrtYd")
		)
		(fp_rect
			(start -0.5 -0.25)
			(end 0.5 0.25)
			(stroke
				(width 0.15)
				(type solid)
			)
			(fill none)
			(layer "F.Fab")
		)
		(fp_text user "Author: Antmicro"
			(at -0.95 4.169 90)
			(layer "F.Fab")
			(hide yes)
			(effects
				(font
					(size 0.7 0.7)
					(thickness 0.15)
				)
				(justify right top)
			)
		)
		(fp_text user "License: Apache-2.0"
			(at -0.95 5.169 90)
			(layer "F.Fab")
			(hide yes)
			(effects
				(font
					(size 0.7 0.7)
					(thickness 0.15)
				)
				(justify right top)
			)
		)
		(fp_text user "${REFERENCE}"
			(at -0.95 3.168 90)
			(layer "F.Fab")
			(hide yes)
			(effects
				(font
					(size 0.7 0.7)
					(thickness 0.15)
				)
				(justify right top)
			)
		)
		(pad "1" smd roundrect
			(at -0.48 0 270)
			(size 0.59 0.64)
			(layers "F.Cu" "F.Paste" "F.Mask")
			(roundrect_rratio 0.25)
			(net 134 "Net-(U4-OUT)")
			(pintype "passive")
		)
		(pad "2" smd roundrect
			(at 0.48 0 270)
			(size 0.59 0.64)
			(layers "F.Cu" "F.Paste" "F.Mask")
			(roundrect_rratio 0.25)
			(net 132 "+3V3_OCU")
			(pintype "passive")
		)
	)
	(footprint "antmicro-footprints:TP_SMD_0.75mm"
		(layer "F.Cu")
		(at 116.275 129.5785 180)
		(property "Reference" "TP15"
			(at -0.645 -0.5615 0)
			(layer "F.SilkS")
			(effects
				(font
					(size 0.7 0.7)
					(thickness 0.15)
				)
				(justify right top)
			)
		)
		(property "Value" "TP_0.75mm_SMD"
			(at 0 1.2 0)
			(layer "F.Fab")
			(effects
				(font
					(size 0.7 0.7)
					(thickness 0.15)
				)
				(justify right top)
			)
		)
		(property "Footprint" "antmicro-footprints:TP_SMD_0.75mm"
			(at 0 0 0)
			(layer "F.Fab")
			(hide yes)
			(effects
				(font
					(size 1.27 1.27)
					(thickness 0.15)
				)
			)
		)
		(property "Description" "SMT test point"
			(at 0 0 0)
			(layer "F.Fab")
			(hide yes)
			(effects
				(font
					(size 1.27 1.27)
					(thickness 0.15)
				)
			)
		)
		(property "MPN" ""
			(at 0 0 180)
			(unlocked yes)
			(layer "F.Fab")
			(hide yes)
			(effects
				(font
					(size 1 1)
					(thickness 0.15)
				)
			)
		)
		(property "Manufacturer" ""
			(at 0 0 180)
			(unlocked yes)
			(layer "F.Fab")
			(hide yes)
			(effects
				(font
					(size 1 1)
					(thickness 0.15)
				)
			)
		)
		(property "Author" "Antmicro"
			(at 0 0 180)
			(unlocked yes)
			(layer "F.Fab")
			(hide yes)
			(effects
				(font
					(size 1 1)
					(thickness 0.15)
				)
			)
		)
		(property "License" "Apache-2.0"
			(at 0 0 180)
			(unlocked yes)
			(layer "F.Fab")
			(hide yes)
			(effects
				(font
					(size 1 1)
					(thickness 0.15)
				)
			)
		)
		(property "Public" "False"
			(at 0 0 180)
			(unlocked yes)
			(layer "F.Fab")
			(hide yes)
			(effects
				(font
					(size 1 1)
					(thickness 0.15)
				)
			)
		)
		(sheetname "Root")
		(sheetfile "jetson-orin-baseboard-oculink-expansion.kicad_sch")
		(attr exclude_from_pos_files exclude_from_bom)
		(fp_circle
			(center 0 0)
			(end 0.475 0)
			(stroke
				(width 0.05)
				(type default)
			)
			(fill none)
			(layer "F.CrtYd")
		)
		(fp_text user "${REFERENCE}"
			(at -0.4 2.7 0)
			(layer "F.Fab")
			(hide yes)
			(effects
				(font
					(size 0.7 0.7)
					(thickness 0.15)
				)
				(justify right top)
			)
		)
		(fp_text user "Author: Antmicro"
			(at -0.4 3.901 0)
			(layer "F.Fab")
			(hide yes)
			(effects
				(font
					(size 0.7 0.7)
					(thickness 0.15)
				)
				(justify right top)
			)
		)
		(fp_text user "License: Apache-2.0"
			(at -0.4 5.101 0)
			(layer "F.Fab")
			(hide yes)
			(effects
				(font
					(size 0.7 0.7)
					(thickness 0.15)
				)
				(justify right top)
			)
		)
		(pad "1" smd circle
			(at 0 0 180)
			(size 0.75 0.75)
			(layers "F.Cu" "F.Mask")
			(net 111 "Net-(U3-I2C_{DONE})")
			(pinfunction "1")
			(pintype "passive")
		)
	)
	(footprint "antmicro-footprints:C_0805_2012Metric"
		(layer "F.Cu")
		(at 143.6 119.25)
		(descr "Capacitor SMD 0805")
		(tags "capacitor SMD 0805")
		(property "Reference" "C36"
			(at -1.05 -0.85 0)
			(layer "F.SilkS")
			(effects
				(font
					(size 0.7 0.7)
					(thickness 0.15)
				)
				(justify left bottom)
			)
		)
		(property "Value" "C_100u_0805"
			(at -2.055717 1.963152 0)
			(layer "F.Fab")
			(effects
				(font
					(size 0.7 0.7)
					(thickness 0.15)
				)
				(justify left bottom)
			)
		)
		(property "Footprint" "antmicro-footprints:C_0805_2012Metric"
			(at 0 0 0)
			(layer "F.Fab")
			(hide yes)
			(effects
				(font
					(size 1.27 1.27)
					(thickness 0.15)
				)
			)
		)
		(property "Datasheet" "https://www.murata.com/products/productdetail?partno=GRM21BR60J107ME15%23"
			(at 0 0 0)
			(layer "F.Fab")
			(hide yes)
			(effects
				(font
					(size 1.27 1.27)
					(thickness 0.15)
				)
			)
		)
		(property "Description" "SMD Multilayer Ceramic Capacitor, 100 µF, 6.3 V, 0805 [2012 Metric], ± 20%, X5R, GRM Series"
			(at 0 0 0)
			(layer "F.Fab")
			(hide yes)
			(effects
				(font
					(size 1.27 1.27)
					(thickness 0.15)
				)
			)
		)
		(property "MPN" "GRM21BR60J107ME15L"
			(at 0 0 0)
			(unlocked yes)
			(layer "F.Fab")
			(hide yes)
			(effects
				(font
					(size 1 1)
					(thickness 0.15)
				)
			)
		)
		(property "Manufacturer" "Murata"
			(at 0 0 0)
			(unlocked yes)
			(layer "F.Fab")
			(hide yes)
			(effects
				(font
					(size 1 1)
					(thickness 0.15)
				)
			)
		)
		(property "License" "Apache-2.0"
			(at 0 0 0)
			(unlocked yes)
			(layer "F.Fab")
			(hide yes)
			(effects
				(font
					(size 1 1)
					(thickness 0.15)
				)
			)
		)
		(property "Author" "Antmicro"
			(at 0 0 0)
			(unlocked yes)
			(layer "F.Fab")
			(hide yes)
			(effects
				(font
					(size 1 1)
					(thickness 0.15)
				)
			)
		)
		(property "Val" "100u"
			(at 0 0 0)
			(unlocked yes)
			(layer "F.Fab")
			(hide yes)
			(effects
				(font
					(size 1 1)
					(thickness 0.15)
				)
			)
		)
		(property "Voltage" ""
			(at 0 0 0)
			(unlocked yes)
			(layer "F.Fab")
			(hide yes)
			(effects
				(font
					(size 1 1)
					(thickness 0.15)
				)
			)
		)
		(property "Dielectric" ""
			(at 0 0 0)
			(unlocked yes)
			(layer "F.Fab")
			(hide yes)
			(effects
				(font
					(size 1 1)
					(thickness 0.15)
				)
			)
		)
		(property "Public" "False"
			(at 0 0 0)
			(unlocked yes)
			(layer "F.Fab")
			(hide yes)
			(effects
				(font
					(size 1 1)
					(thickness 0.15)
				)
			)
		)
		(sheetname "Root")
		(sheetfile "jetson-orin-baseboard-oculink-expansion.kicad_sch")
		(attr smd)
		(fp_line
			(start -0.3 -0.7)
			(end 0.3 -0.7)
			(stroke
				(width 0.15)
				(type solid)
			)
			(layer "F.SilkS")
		)
		(fp_line
			(start -0.3 0.7)
			(end 0.3 0.7)
			(stroke
				(width 0.15)
				(type solid)
			)
			(layer "F.SilkS")
		)
		(fp_rect
			(start 1.95 -0.9)
			(end -1.95 0.9)
			(stroke
				(width 0.05)
				(type default)
			)
			(fill none)
			(layer "F.CrtYd")
		)
		(fp_rect
			(start -0.95 -0.675)
			(end 0.95 0.675)
			(stroke
				(width 0.15)
				(type solid)
			)
			(fill none)
			(layer "F.Fab")
		)
		(fp_text user "Author: Antmicro"
			(at -1.9 5.947 0)
			(layer "F.Fab")
			(hide yes)
			(effects
				(font
					(size 0.7 0.7)
					(thickness 0.15)
				)
				(justify left bottom)
			)
		)
		(fp_text user "License: Apache-2.0"
			(at -1.9 4.947 0)
			(layer "F.Fab")
			(hide yes)
			(effects
				(font
					(size 0.7 0.7)
					(thickness 0.15)
				)
				(justify left bottom)
			)
		)
		(fp_text user "${REFERENCE}"
			(at -1.9 3.947 0)
			(layer "F.Fab")
			(hide yes)
			(effects
				(font
					(size 0.7 0.7)
					(thickness 0.15)
				)
				(justify left bottom)
			)
		)
		(pad "1" smd roundrect
			(at -1.1 0)
			(size 1.2 1.3)
			(layers "F.Cu" "F.Paste" "F.Mask")
			(roundrect_rratio 0.25)
			(net 51 "GND")
			(pintype "passive")
		)
		(pad "2" smd roundrect
			(at 1.1 0)
			(size 1.2 1.3)
			(layers "F.Cu" "F.Paste" "F.Mask")
			(roundrect_rratio 0.25)
			(net 135 "Net-(U5-OUT)")
			(pintype "passive")
		)
	)
	(footprint "antmicro-footprints:C_0402_1005Metric"
		(layer "F.Cu")
		(at 113.5 141.25)
		(descr "Capacitor SMD 0402")
		(tags "capacitor SMD 0402")
		(property "Reference" "C4"
			(at -0.8 -0.45 0)
			(layer "F.SilkS")
			(effects
				(font
					(size 0.7 0.7)
					(thickness 0.15)
				)
				(justify left bottom)
			)
		)
		(property "Value" "C_10u_0402"
			(at -1.022927 2.155213 0)
			(layer "F.Fab")
			(effects
				(font
					(size 0.7 0.7)
					(thickness 0.15)
				)
				(justify left bottom)
			)
		)
		(property "Footprint" "antmicro-footprints:C_0402_1005Metric"
			(at 0 0 0)
			(layer "F.Fab")
			(hide yes)
			(effects
				(font
					(size 1.27 1.27)
					(thickness 0.15)
				)
			)
		)
		(property "Datasheet" "https://www.yageo.com/en/Chart/Download/pdf/CC0402MRX5R5BB106"
			(at 0 0 0)
			(layer "F.Fab")
			(hide yes)
			(effects
				(font
					(size 1.27 1.27)
					(thickness 0.15)
				)
			)
		)
		(property "Description" "SMD Multilayer Ceramic Capacitor, 10 µF, 6.3 V, 0402 [1005 Metric], ± 20%, X5R, CC Series"
			(at 0 0 0)
			(layer "F.Fab")
			(hide yes)
			(effects
				(font
					(size 1.27 1.27)
					(thickness 0.15)
				)
			)
		)
		(property "MPN" "CC0402MRX5R5BB106"
			(at 0 0 0)
			(unlocked yes)
			(layer "F.Fab")
			(hide yes)
			(effects
				(font
					(size 1 1)
					(thickness 0.15)
				)
			)
		)
		(property "Manufacturer" "YAGEO"
			(at 0 0 0)
			(unlocked yes)
			(layer "F.Fab")
			(hide yes)
			(effects
				(font
					(size 1 1)
					(thickness 0.15)
				)
			)
		)
		(property "License" "Apache-2.0"
			(at 0 0 0)
			(unlocked yes)
			(layer "F.Fab")
			(hide yes)
			(effects
				(font
					(size 1 1)
					(thickness 0.15)
				)
			)
		)
		(property "Author" "Antmicro"
			(at 0 0 0)
			(unlocked yes)
			(layer "F.Fab")
			(hide yes)
			(effects
				(font
					(size 1 1)
					(thickness 0.15)
				)
			)
		)
		(property "Val" "10u"
			(at 0 0 0)
			(unlocked yes)
			(layer "F.Fab")
			(hide yes)
			(effects
				(font
					(size 1 1)
					(thickness 0.15)
				)
			)
		)
		(property "Voltage" ""
			(at 0 0 0)
			(unlocked yes)
			(layer "F.Fab")
			(hide yes)
			(effects
				(font
					(size 1 1)
					(thickness 0.15)
				)
			)
		)
		(property "Dielectric" ""
			(at 0 0 0)
			(unlocked yes)
			(layer "F.Fab")
			(hide yes)
			(effects
				(font
					(size 1 1)
					(thickness 0.15)
				)
			)
		)
		(sheetname "Root")
		(sheetfile "jetson-orin-baseboard-oculink-expansion.kicad_sch")
		(attr smd)
		(fp_rect
			(start -0.925 -0.47)
			(end 0.925 0.47)
			(stroke
				(width 0.05)
				(type default)
			)
			(fill none)
			(layer "F.CrtYd")
		)
		(fp_line
			(start -0.494 -0.25)
			(end 0.504 -0.25)
			(stroke
				(width 0.15)
				(type solid)
			)
			(layer "F.Fab")
		)
		(fp_line
			(start -0.494 0.248)
			(end -0.494 -0.25)
			(stroke
				(width 0.15)
				(type solid)
			)
			(layer "F.Fab")
		)
		(fp_line
			(start 0.504 -0.25)
			(end 0.504 0.248)
			(stroke
				(width 0.15)
				(type solid)
			)
			(layer "F.Fab")
		)
		(fp_line
			(start 0.504 0.248)
			(end -0.494 0.248)
			(stroke
				(width 0.15)
				(type solid)
			)
			(layer "F.Fab")
		)
		(fp_text user "License: Apache-2.0"
			(at -0.939 5.799 0)
			(layer "F.Fab")
			(hide yes)
			(effects
				(font
					(size 0.7 0.7)
					(thickness 0.15)
				)
				(justify left bottom)
			)
		)
		(fp_text user "Author: Antmicro"
			(at -0.939 3.399 0)
			(layer "F.Fab")
			(hide yes)
			(effects
				(font
					(size 0.7 0.7)
					(thickness 0.15)
				)
				(justify left bottom)
			)
		)
		(fp_text user "${REFERENCE}"
			(at -0.939 4.599 0)
			(layer "F.Fab")
			(hide yes)
			(effects
				(font
					(size 0.7 0.7)
					(thickness 0.15)
				)
				(justify left bottom)
			)
		)
		(pad "1" smd roundrect
			(at -0.48 0)
			(size 0.59 0.64)
			(layers "F.Cu" "F.Paste" "F.Mask")
			(roundrect_rratio 0.25)
			(net 51 "GND")
			(pintype "passive")
		)
		(pad "2" smd roundrect
			(at 0.48 0)
			(size 0.59 0.64)
			(layers "F.Cu" "F.Paste" "F.Mask")
			(roundrect_rratio 0.25)
			(net 133 "+5V_OCU")
			(pintype "passive")
		)
	)
	(footprint "antmicro-footprints:C_0402_1005Metric"
		(layer "F.Cu")
		(at 144.467 121.671)
		(descr "Capacitor SMD 0402")
		(tags "capacitor SMD 0402")
		(property "Reference" "C34"
			(at -1.017 -0.471 0)
			(layer "F.SilkS")
			(effects
				(font
					(size 0.7 0.7)
					(thickness 0.15)
				)
				(justify left bottom)
			)
		)
		(property "Value" "C_100n_0402"
			(at -1.022927 2.155213 0)
			(layer "F.Fab")
			(effects
				(font
					(size 0.7 0.7)
					(thickness 0.15)
				)
				(justify left bottom)
			)
		)
		(property "Footprint" "antmicro-footprints:C_0402_1005Metric"
			(at 0 0 0)
			(layer "F.Fab")
			(hide yes)
			(effects
				(font
					(size 1.27 1.27)
					(thickness 0.15)
				)
			)
		)
		(property "Datasheet" "https://www.murata.com/products/productdetail?partno=GRM155R61H104KE14%23"
			(at 0 0 0)
			(layer "F.Fab")
			(hide yes)
			(effects
				(font
					(size 1.27 1.27)
					(thickness 0.15)
				)
			)
		)
		(property "Description" "SMD Multilayer Ceramic Capacitor, 0.1 µF, 50 V, 0402 [1005 Metric], ± 10%, X5R, GRM Series"
			(at 0 0 0)
			(layer "F.Fab")
			(hide yes)
			(effects
				(font
					(size 1.27 1.27)
					(thickness 0.15)
				)
			)
		)
		(property "MPN" "GRM155R61H104KE14D"
			(at 0 0 0)
			(unlocked yes)
			(layer "F.Fab")
			(hide yes)
			(effects
				(font
					(size 1 1)
					(thickness 0.15)
				)
			)
		)
		(property "Manufacturer" "Murata"
			(at 0 0 0)
			(unlocked yes)
			(layer "F.Fab")
			(hide yes)
			(effects
				(font
					(size 1 1)
					(thickness 0.15)
				)
			)
		)
		(property "License" "Apache-2.0"
			(at 0 0 0)
			(unlocked yes)
			(layer "F.Fab")
			(hide yes)
			(effects
				(font
					(size 1 1)
					(thickness 0.15)
				)
			)
		)
		(property "Author" "Antmicro"
			(at 0 0 0)
			(unlocked yes)
			(layer "F.Fab")
			(hide yes)
			(effects
				(font
					(size 1 1)
					(thickness 0.15)
				)
			)
		)
		(property "Val" "100n"
			(at 0 0 0)
			(unlocked yes)
			(layer "F.Fab")
			(hide yes)
			(effects
				(font
					(size 1 1)
					(thickness 0.15)
				)
			)
		)
		(property "Voltage" "50V"
			(at 0 0 0)
			(unlocked yes)
			(layer "F.Fab")
			(hide yes)
			(effects
				(font
					(size 1 1)
					(thickness 0.15)
				)
			)
		)
		(property "Dielectric" "X5R"
			(at 0 0 0)
			(unlocked yes)
			(layer "F.Fab")
			(hide yes)
			(effects
				(font
					(size 1 1)
					(thickness 0.15)
				)
			)
		)
		(sheetname "Root")
		(sheetfile "jetson-orin-baseboard-oculink-expansion.kicad_sch")
		(attr smd)
		(fp_rect
			(start -0.925 -0.47)
			(end 0.925 0.47)
			(stroke
				(width 0.05)
				(type default)
			)
			(fill none)
			(layer "F.CrtYd")
		)
		(fp_line
			(start -0.494 -0.25)
			(end 0.504 -0.25)
			(stroke
				(width 0.15)
				(type solid)
			)
			(layer "F.Fab")
		)
		(fp_line
			(start -0.494 0.248)
			(end -0.494 -0.25)
			(stroke
				(width 0.15)
				(type solid)
			)
			(layer "F.Fab")
		)
		(fp_line
			(start 0.504 -0.25)
			(end 0.504 0.248)
			(stroke
				(width 0.15)
				(type solid)
			)
			(layer "F.Fab")
		)
		(fp_line
			(start 0.504 0.248)
			(end -0.494 0.248)
			(stroke
				(width 0.15)
				(type solid)
			)
			(layer "F.Fab")
		)
		(fp_text user "License: Apache-2.0"
			(at -0.939 5.799 0)
			(layer "F.Fab")
			(hide yes)
			(effects
				(font
					(size 0.7 0.7)
					(thickness 0.15)
				)
				(justify left bottom)
			)
		)
		(fp_text user "Author: Antmicro"
			(at -0.939 3.399 0)
			(layer "F.Fab")
			(hide yes)
			(effects
				(font
					(size 0.7 0.7)
					(thickness 0.15)
				)
				(justify left bottom)
			)
		)
		(fp_text user "${REFERENCE}"
			(at -0.939 4.599 0)
			(layer "F.Fab")
			(hide yes)
			(effects
				(font
					(size 0.7 0.7)
					(thickness 0.15)
				)
				(justify left bottom)
			)
		)
		(pad "1" smd roundrect
			(at -0.48 0)
			(size 0.59 0.64)
			(layers "F.Cu" "F.Paste" "F.Mask")
			(roundrect_rratio 0.25)
			(net 51 "GND")
			(pintype "passive")
		)
		(pad "2" smd roundrect
			(at 0.48 0)
			(size 0.59 0.64)
			(layers "F.Cu" "F.Paste" "F.Mask")
			(roundrect_rratio 0.25)
			(net 135 "Net-(U5-OUT)")
			(pintype "passive")
		)
	)
	(footprint "antmicro-footprints:R_0402_1005Metric"
		(layer "F.Cu")
		(at 141.247 145.409 -90)
		(descr "Resistor SMD 0402")
		(tags "resistor SMD 0402")
		(property "Reference" "R2"
			(at 1.891 0.347 90)
			(layer "F.SilkS")
			(effects
				(font
					(size 0.7 0.7)
					(thickness 0.15)
				)
				(justify right top)
			)
		)
		(property "Value" "R_0R_0402"
			(at -1.011843 1.772047 90)
			(layer "F.Fab")
			(effects
				(font
					(size 0.7 0.7)
					(thickness 0.15)
				)
				(justify right top)
			)
		)
		(property "Footprint" "antmicro-footprints:R_0402_1005Metric"
			(at 0 0 90)
			(layer "F.Fab")
			(hide yes)
			(effects
				(font
					(size 1.27 1.27)
					(thickness 0.15)
				)
			)
		)
		(property "Datasheet" "https://industrial.panasonic.com/cdbs/www-data/pdf/RDA0000/AOA0000C301.pdf"
			(at 0 0 90)
			(layer "F.Fab")
			(hide yes)
			(effects
				(font
					(size 1.27 1.27)
					(thickness 0.15)
				)
			)
		)
		(property "Description" "SMD Chip Resistor, Jumper, 0 ohm, 100 mW, 0402 [1005 Metric], Thick Film, General Purpose"
			(at 0 0 90)
			(layer "F.Fab")
			(hide yes)
			(effects
				(font
					(size 1.27 1.27)
					(thickness 0.15)
				)
			)
		)
		(property "MPN" "ERJ2GE0R00X"
			(at 0 0 -90)
			(unlocked yes)
			(layer "F.Fab")
			(hide yes)
			(effects
				(font
					(size 1 1)
					(thickness 0.15)
				)
			)
		)
		(property "Manufacturer" "Panasonic"
			(at 0 0 -90)
			(unlocked yes)
			(layer "F.Fab")
			(hide yes)
			(effects
				(font
					(size 1 1)
					(thickness 0.15)
				)
			)
		)
		(property "License" "Apache-2.0"
			(at 0 0 -90)
			(unlocked yes)
			(layer "F.Fab")
			(hide yes)
			(effects
				(font
					(size 1 1)
					(thickness 0.15)
				)
			)
		)
		(property "Author" "Antmicro"
			(at 0 0 -90)
			(unlocked yes)
			(layer "F.Fab")
			(hide yes)
			(effects
				(font
					(size 1 1)
					(thickness 0.15)
				)
			)
		)
		(property "Val" "0R"
			(at 0 0 -90)
			(unlocked yes)
			(layer "F.Fab")
			(hide yes)
			(effects
				(font
					(size 1 1)
					(thickness 0.15)
				)
			)
		)
		(property "Tolerance" ""
			(at 0 0 -90)
			(unlocked yes)
			(layer "F.Fab")
			(hide yes)
			(effects
				(font
					(size 1 1)
					(thickness 0.15)
				)
			)
		)
		(property "Current" "1A"
			(at 0 0 -90)
			(unlocked yes)
			(layer "F.Fab")
			(hide yes)
			(effects
				(font
					(size 1 1)
					(thickness 0.15)
				)
			)
		)
		(sheetname "Root")
		(sheetfile "jetson-orin-baseboard-oculink-expansion.kicad_sch")
		(attr smd)
		(fp_rect
			(start -0.925 -0.47)
			(end 0.925 0.47)
			(stroke
				(width 0.05)
				(type default)
			)
			(fill none)
			(layer "F.CrtYd")
		)
		(fp_rect
			(start -0.5 -0.25)
			(end 0.5 0.25)
			(stroke
				(width 0.15)
				(type solid)
			)
			(fill none)
			(layer "F.Fab")
		)
		(fp_text user "${REFERENCE}"
			(at -0.95 3.168 90)
			(layer "F.Fab")
			(hide yes)
			(effects
				(font
					(size 0.7 0.7)
					(thickness 0.15)
				)
				(justify right top)
			)
		)
		(fp_text user "License: Apache-2.0"
			(at -0.95 5.169 90)
			(layer "F.Fab")
			(hide yes)
			(effects
				(font
					(size 0.7 0.7)
					(thickness 0.15)
				)
				(justify right top)
			)
		)
		(fp_text user "Author: Antmicro"
			(at -0.95 4.169 90)
			(layer "F.Fab")
			(hide yes)
			(effects
				(font
					(size 0.7 0.7)
					(thickness 0.15)
				)
				(justify right top)
			)
		)
		(pad "1" smd roundrect
			(at -0.48 0 270)
			(size 0.59 0.64)
			(layers "F.Cu" "F.Paste" "F.Mask")
			(roundrect_rratio 0.25)
			(net 69 "/~{PCIE_CWAKE}")
			(pintype "passive")
		)
		(pad "2" smd roundrect
			(at 0.48 0 270)
			(size 0.59 0.64)
			(layers "F.Cu" "F.Paste" "F.Mask")
			(roundrect_rratio 0.25)
			(net 54 "Net-(J1-~{CWAKE})")
			(pintype "passive")
		)
	)
	(footprint "antmicro-footprints:C_0402_1005Metric"
		(layer "F.Cu")
		(at 117.65 137.64 -90)
		(descr "Capacitor SMD 0402")
		(tags "capacitor SMD 0402")
		(property "Reference" "C13"
			(at 0.86 0.34 90)
			(layer "F.SilkS")
			(effects
				(font
					(size 0.7 0.7)
					(thickness 0.15)
				)
				(justify right top)
			)
		)
		(property "Value" "C_220n_0402"
			(at -1.022927 2.155213 90)
			(layer "F.Fab")
			(effects
				(font
					(size 0.7 0.7)
					(thickness 0.15)
				)
				(justify right top)
			)
		)
		(property "Footprint" "antmicro-footprints:C_0402_1005Metric"
			(at 0 0 90)
			(layer "F.Fab")
			(hide yes)
			(effects
				(font
					(size 1.27 1.27)
					(thickness 0.15)
				)
			)
		)
		(property "Datasheet" "https://www.yageo.com/en/Chart/Download/pdf/CC0402KRX5R6BB224"
			(at 0 0 90)
			(layer "F.Fab")
			(hide yes)
			(effects
				(font
					(size 1.27 1.27)
					(thickness 0.15)
				)
			)
		)
		(property "Description" "SMD Multilayer Ceramic Capacitor, 0.22 µF, 10 V, 0402 [1005 Metric], ± 10%, X5R, CC Series"
			(at 0 0 90)
			(layer "F.Fab")
			(hide yes)
			(effects
				(font
					(size 1.27 1.27)
					(thickness 0.15)
				)
			)
		)
		(property "MPN" "CC0402KRX5R6BB224"
			(at 0 0 -90)
			(unlocked yes)
			(layer "F.Fab")
			(hide yes)
			(effects
				(font
					(size 1 1)
					(thickness 0.15)
				)
			)
		)
		(property "Manufacturer" "YAGEO"
			(at 0 0 -90)
			(unlocked yes)
			(layer "F.Fab")
			(hide yes)
			(effects
				(font
					(size 1 1)
					(thickness 0.15)
				)
			)
		)
		(property "License" "Apache-2.0"
			(at 0 0 -90)
			(unlocked yes)
			(layer "F.Fab")
			(hide yes)
			(effects
				(font
					(size 1 1)
					(thickness 0.15)
				)
			)
		)
		(property "Author" "Antmicro"
			(at 0 0 -90)
			(unlocked yes)
			(layer "F.Fab")
			(hide yes)
			(effects
				(font
					(size 1 1)
					(thickness 0.15)
				)
			)
		)
		(property "Val" "220n"
			(at 0 0 -90)
			(unlocked yes)
			(layer "F.Fab")
			(hide yes)
			(effects
				(font
					(size 1 1)
					(thickness 0.15)
				)
			)
		)
		(property "Voltage" ""
			(at 0 0 -90)
			(unlocked yes)
			(layer "F.Fab")
			(hide yes)
			(effects
				(font
					(size 1 1)
					(thickness 0.15)
				)
			)
		)
		(property "Dielectric" ""
			(at 0 0 -90)
			(unlocked yes)
			(layer "F.Fab")
			(hide yes)
			(effects
				(font
					(size 1 1)
					(thickness 0.15)
				)
			)
		)
		(property "Public" "False"
			(at 0 0 -90)
			(unlocked yes)
			(layer "F.Fab")
			(hide yes)
			(effects
				(font
					(size 1 1)
					(thickness 0.15)
				)
			)
		)
		(sheetname "Root")
		(sheetfile "jetson-orin-baseboard-oculink-expansion.kicad_sch")
		(attr smd)
		(fp_rect
			(start -0.925 -0.47)
			(end 0.925 0.47)
			(stroke
				(width 0.05)
				(type default)
			)
			(fill none)
			(layer "F.CrtYd")
		)
		(fp_line
			(start -0.494 0.248)
			(end -0.494 -0.25)
			(stroke
				(width 0.15)
				(type solid)
			)
			(layer "F.Fab")
		)
		(fp_line
			(start 0.504 0.248)
			(end -0.494 0.248)
			(stroke
				(width 0.15)
				(type solid)
			)
			(layer "F.Fab")
		)
		(fp_line
			(start -0.494 -0.25)
			(end 0.504 -0.25)
			(stroke
				(width 0.15)
				(type solid)
			)
			(layer "F.Fab")
		)
		(fp_line
			(start 0.504 -0.25)
			(end 0.504 0.248)
			(stroke
				(width 0.15)
				(type solid)
			)
			(layer "F.Fab")
		)
		(fp_text user "${REFERENCE}"
			(at -0.939 4.599 90)
			(layer "F.Fab")
			(hide yes)
			(effects
				(font
					(size 0.7 0.7)
					(thickness 0.15)
				)
				(justify right top)
			)
		)
		(fp_text user "Author: Antmicro"
			(at -0.939 3.399 90)
			(layer "F.Fab")
			(hide yes)
			(effects
				(font
					(size 0.7 0.7)
					(thickness 0.15)
				)
				(justify right top)
			)
		)
		(fp_text user "License: Apache-2.0"
			(at -0.939 5.799 90)
			(layer "F.Fab")
			(hide yes)
			(effects
				(font
					(size 0.7 0.7)
					(thickness 0.15)
				)
				(justify right top)
			)
		)
		(pad "1" smd roundrect
			(at -0.48 0 270)
			(size 0.59 0.64)
			(layers "F.Cu" "F.Paste" "F.Mask")
			(roundrect_rratio 0.25)
			(net 57 "/PCIE_{O}_C.TX1+")
			(pintype "passive")
		)
		(pad "2" smd roundrect
			(at 0.48 0 270)
			(size 0.59 0.64)
			(layers "F.Cu" "F.Paste" "F.Mask")
			(roundrect_rratio 0.25)
			(net 58 "/PCIE_{O}_TX1+")
			(pintype "passive")
		)
	)
	(footprint "antmicro-footprints:R_0402_1005Metric"
		(layer "F.Cu")
		(at 120.79 136.96 -90)
		(descr "Resistor SMD 0402")
		(tags "resistor SMD 0402")
		(property "Reference" "R20"
			(at -1.13 -1.66 90)
			(layer "F.SilkS")
			(effects
				(font
					(size 0.7 0.7)
					(thickness 0.15)
				)
				(justify right top)
			)
		)
		(property "Value" "R_0R_0402"
			(at -1.011843 1.772047 90)
			(layer "F.Fab")
			(effects
				(font
					(size 0.7 0.7)
					(thickness 0.15)
				)
				(justify right top)
			)
		)
		(property "Footprint" "antmicro-footprints:R_0402_1005Metric"
			(at 0 0 90)
			(layer "F.Fab")
			(hide yes)
			(effects
				(font
					(size 1.27 1.27)
					(thickness 0.15)
				)
			)
		)
		(property "Datasheet" "https://industrial.panasonic.com/cdbs/www-data/pdf/RDA0000/AOA0000C301.pdf"
			(at 0 0 90)
			(layer "F.Fab")
			(hide yes)
			(effects
				(font
					(size 1.27 1.27)
					(thickness 0.15)
				)
			)
		)
		(property "Description" "SMD Chip Resistor, Jumper, 0 ohm, 100 mW, 0402 [1005 Metric], Thick Film, General Purpose"
			(at 0 0 90)
			(layer "F.Fab")
			(hide yes)
			(effects
				(font
					(size 1.27 1.27)
					(thickness 0.15)
				)
			)
		)
		(property "MPN" "ERJ2GE0R00X"
			(at 0 0 -90)
			(unlocked yes)
			(layer "F.Fab")
			(hide yes)
			(effects
				(font
					(size 1 1)
					(thickness 0.15)
				)
			)
		)
		(property "Manufacturer" "Panasonic"
			(at 0 0 -90)
			(unlocked yes)
			(layer "F.Fab")
			(hide yes)
			(effects
				(font
					(size 1 1)
					(thickness 0.15)
				)
			)
		)
		(property "License" "Apache-2.0"
			(at 0 0 -90)
			(unlocked yes)
			(layer "F.Fab")
			(hide yes)
			(effects
				(font
					(size 1 1)
					(thickness 0.15)
				)
			)
		)
		(property "Author" "Antmicro"
			(at 0 0 -90)
			(unlocked yes)
			(layer "F.Fab")
			(hide yes)
			(effects
				(font
					(size 1 1)
					(thickness 0.15)
				)
			)
		)
		(property "Val" "0R"
			(at 0 0 -90)
			(unlocked yes)
			(layer "F.Fab")
			(hide yes)
			(effects
				(font
					(size 1 1)
					(thickness 0.15)
				)
			)
		)
		(property "Tolerance" ""
			(at 0 0 -90)
			(unlocked yes)
			(layer "F.Fab")
			(hide yes)
			(effects
				(font
					(size 1 1)
					(thickness 0.15)
				)
			)
		)
		(property "Current" "1A"
			(at 0 0 -90)
			(unlocked yes)
			(layer "F.Fab")
			(hide yes)
			(effects
				(font
					(size 1 1)
					(thickness 0.15)
				)
			)
		)
		(sheetname "Root")
		(sheetfile "jetson-orin-baseboard-oculink-expansion.kicad_sch")
		(attr smd)
		(fp_rect
			(start -0.925 -0.47)
			(end 0.925 0.47)
			(stroke
				(width 0.05)
				(type default)
			)
			(fill none)
			(layer "F.CrtYd")
		)
		(fp_rect
			(start -0.5 -0.25)
			(end 0.5 0.25)
			(stroke
				(width 0.15)
				(type solid)
			)
			(fill none)
			(layer "F.Fab")
		)
		(fp_text user "License: Apache-2.0"
			(at -0.95 5.169 90)
			(layer "F.Fab")
			(hide yes)
			(effects
				(font
					(size 0.7 0.7)
					(thickness 0.15)
				)
				(justify right top)
			)
		)
		(fp_text user "Author: Antmicro"
			(at -0.95 4.169 90)
			(layer "F.Fab")
			(hide yes)
			(effects
				(font
					(size 0.7 0.7)
					(thickness 0.15)
				)
				(justify right top)
			)
		)
		(fp_text user "${REFERENCE}"
			(at -0.95 3.168 90)
			(layer "F.Fab")
			(hide yes)
			(effects
				(font
					(size 0.7 0.7)
					(thickness 0.15)
				)
				(justify right top)
			)
		)
		(pad "1" smd roundrect
			(at -0.48 0 270)
			(size 0.59 0.64)
			(layers "F.Cu" "F.Paste" "F.Mask")
			(roundrect_rratio 0.25)
			(net 64 "/I2C_SCL")
			(pintype "passive")
		)
		(pad "2" smd roundrect
			(at 0.48 0 270)
			(size 0.59 0.64)
			(layers "F.Cu" "F.Paste" "F.Mask")
			(roundrect_rratio 0.25)
			(net 126 "Net-(J1-SCL)")
			(pintype "passive")
		)
	)
	(footprint "antmicro-footprints:TP_SMD_0.75mm"
		(layer "F.Cu")
		(at 114.6 127.508)
		(property "Reference" "TP4"
			(at -1.05 1.432 0)
			(layer "F.SilkS")
			(effects
				(font
					(size 0.7 0.7)
					(thickness 0.15)
				)
				(justify left bottom)
			)
		)
		(property "Value" "TP_0.75mm_SMD"
			(at 0 1.2 0)
			(layer "F.Fab")
			(effects
				(font
					(size 0.7 0.7)
					(thickness 0.15)
				)
				(justify left bottom)
			)
		)
		(property "Footprint" "antmicro-footprints:TP_SMD_0.75mm"
			(at 0 0 0)
			(layer "F.Fab")
			(hide yes)
			(effects
				(font
					(size 1.27 1.27)
					(thickness 0.15)
				)
			)
		)
		(property "Description" "SMT test point"
			(at 0 0 0)
			(layer "F.Fab")
			(hide yes)
			(effects
				(font
					(size 1.27 1.27)
					(thickness 0.15)
				)
			)
		)
		(property "MPN" ""
			(at 0 0 0)
			(unlocked yes)
			(layer "F.Fab")
			(hide yes)
			(effects
				(font
					(size 1 1)
					(thickness 0.15)
				)
			)
		)
		(property "Manufacturer" ""
			(at 0 0 0)
			(unlocked yes)
			(layer "F.Fab")
			(hide yes)
			(effects
				(font
					(size 1 1)
					(thickness 0.15)
				)
			)
		)
		(property "Author" "Antmicro"
			(at 0 0 0)
			(unlocked yes)
			(layer "F.Fab")
			(hide yes)
			(effects
				(font
					(size 1 1)
					(thickness 0.15)
				)
			)
		)
		(property "License" "Apache-2.0"
			(at 0 0 0)
			(unlocked yes)
			(layer "F.Fab")
			(hide yes)
			(effects
				(font
					(size 1 1)
					(thickness 0.15)
				)
			)
		)
		(property "Public" "False"
			(at 0 0 0)
			(unlocked yes)
			(layer "F.Fab")
			(hide yes)
			(effects
				(font
					(size 1 1)
					(thickness 0.15)
				)
			)
		)
		(sheetname "Root")
		(sheetfile "jetson-orin-baseboard-oculink-expansion.kicad_sch")
		(attr exclude_from_pos_files exclude_from_bom)
		(fp_circle
			(center 0 0)
			(end 0.475 0)
			(stroke
				(width 0.05)
				(type default)
			)
			(fill none)
			(layer "F.CrtYd")
		)
		(fp_text user "Author: Antmicro"
			(at -0.4 3.901 0)
			(layer "F.Fab")
			(hide yes)
			(effects
				(font
					(size 0.7 0.7)
					(thickness 0.15)
				)
				(justify left bottom)
			)
		)
		(fp_text user "${REFERENCE}"
			(at -0.4 2.7 0)
			(layer "F.Fab")
			(hide yes)
			(effects
				(font
					(size 0.7 0.7)
					(thickness 0.15)
				)
				(justify left bottom)
			)
		)
		(fp_text user "License: Apache-2.0"
			(at -0.4 5.101 0)
			(layer "F.Fab")
			(hide yes)
			(effects
				(font
					(size 0.7 0.7)
					(thickness 0.15)
				)
				(justify left bottom)
			)
		)
		(pad "1" smd circle
			(at 0 0)
			(size 0.75 0.75)
			(layers "F.Cu" "F.Mask")
			(net 108 "Net-(U3-SCL)")
			(pinfunction "1")
			(pintype "passive")
		)
	)
	(footprint "antmicro-footprints:C_0402_1005Metric"
		(layer "F.Cu")
		(at 116.41875 137.65 -90)
		(descr "Capacitor SMD 0402")
		(tags "capacitor SMD 0402")
		(property "Reference" "C14"
			(at 0.85 0.32875 90)
			(layer "F.SilkS")
			(effects
				(font
					(size 0.7 0.7)
					(thickness 0.15)
				)
				(justify right top)
			)
		)
		(property "Value" "C_220n_0402"
			(at -1.022927 2.155213 90)
			(layer "F.Fab")
			(effects
				(font
					(size 0.7 0.7)
					(thickness 0.15)
				)
				(justify right top)
			)
		)
		(property "Footprint" "antmicro-footprints:C_0402_1005Metric"
			(at 0 0 90)
			(layer "F.Fab")
			(hide yes)
			(effects
				(font
					(size 1.27 1.27)
					(thickness 0.15)
				)
			)
		)
		(property "Datasheet" "https://www.yageo.com/en/Chart/Download/pdf/CC0402KRX5R6BB224"
			(at 0 0 90)
			(layer "F.Fab")
			(hide yes)
			(effects
				(font
					(size 1.27 1.27)
					(thickness 0.15)
				)
			)
		)
		(property "Description" "SMD Multilayer Ceramic Capacitor, 0.22 µF, 10 V, 0402 [1005 Metric], ± 10%, X5R, CC Series"
			(at 0 0 90)
			(layer "F.Fab")
			(hide yes)
			(effects
				(font
					(size 1.27 1.27)
					(thickness 0.15)
				)
			)
		)
		(property "MPN" "CC0402KRX5R6BB224"
			(at 0 0 -90)
			(unlocked yes)
			(layer "F.Fab")
			(hide yes)
			(effects
				(font
					(size 1 1)
					(thickness 0.15)
				)
			)
		)
		(property "Manufacturer" "YAGEO"
			(at 0 0 -90)
			(unlocked yes)
			(layer "F.Fab")
			(hide yes)
			(effects
				(font
					(size 1 1)
					(thickness 0.15)
				)
			)
		)
		(property "License" "Apache-2.0"
			(at 0 0 -90)
			(unlocked yes)
			(layer "F.Fab")
			(hide yes)
			(effects
				(font
					(size 1 1)
					(thickness 0.15)
				)
			)
		)
		(property "Author" "Antmicro"
			(at 0 0 -90)
			(unlocked yes)
			(layer "F.Fab")
			(hide yes)
			(effects
				(font
					(size 1 1)
					(thickness 0.15)
				)
			)
		)
		(property "Val" "220n"
			(at 0 0 -90)
			(unlocked yes)
			(layer "F.Fab")
			(hide yes)
			(effects
				(font
					(size 1 1)
					(thickness 0.15)
				)
			)
		)
		(property "Voltage" ""
			(at 0 0 -90)
			(unlocked yes)
			(layer "F.Fab")
			(hide yes)
			(effects
				(font
					(size 1 1)
					(thickness 0.15)
				)
			)
		)
		(property "Dielectric" ""
			(at 0 0 -90)
			(unlocked yes)
			(layer "F.Fab")
			(hide yes)
			(effects
				(font
					(size 1 1)
					(thickness 0.15)
				)
			)
		)
		(property "Public" "False"
			(at 0 0 -90)
			(unlocked yes)
			(layer "F.Fab")
			(hide yes)
			(effects
				(font
					(size 1 1)
					(thickness 0.15)
				)
			)
		)
		(sheetname "Root")
		(sheetfile "jetson-orin-baseboard-oculink-expansion.kicad_sch")
		(attr smd)
		(fp_rect
			(start -0.925 -0.47)
			(end 0.925 0.47)
			(stroke
				(width 0.05)
				(type default)
			)
			(fill none)
			(layer "F.CrtYd")
		)
		(fp_line
			(start -0.494 0.248)
			(end -0.494 -0.25)
			(stroke
				(width 0.15)
				(type solid)
			)
			(layer "F.Fab")
		)
		(fp_line
			(start 0.504 0.248)
			(end -0.494 0.248)
			(stroke
				(width 0.15)
				(type solid)
			)
			(layer "F.Fab")
		)
		(fp_line
			(start -0.494 -0.25)
			(end 0.504 -0.25)
			(stroke
				(width 0.15)
				(type solid)
			)
			(layer "F.Fab")
		)
		(fp_line
			(start 0.504 -0.25)
			(end 0.504 0.248)
			(stroke
				(width 0.15)
				(type solid)
			)
			(layer "F.Fab")
		)
		(fp_text user "License: Apache-2.0"
			(at -0.939 5.799 90)
			(layer "F.Fab")
			(hide yes)
			(effects
				(font
					(size 0.7 0.7)
					(thickness 0.15)
				)
				(justify right top)
			)
		)
		(fp_text user "Author: Antmicro"
			(at -0.939 3.399 90)
			(layer "F.Fab")
			(hide yes)
			(effects
				(font
					(size 0.7 0.7)
					(thickness 0.15)
				)
				(justify right top)
			)
		)
		(fp_text user "${REFERENCE}"
			(at -0.939 4.599 90)
			(layer "F.Fab")
			(hide yes)
			(effects
				(font
					(size 0.7 0.7)
					(thickness 0.15)
				)
				(justify right top)
			)
		)
		(pad "1" smd roundrect
			(at -0.48 0 270)
			(size 0.59 0.64)
			(layers "F.Cu" "F.Paste" "F.Mask")
			(roundrect_rratio 0.25)
			(net 31 "/PCIE_{O}_C.TX0-")
			(pintype "passive")
		)
		(pad "2" smd roundrect
			(at 0.48 0 270)
			(size 0.59 0.64)
			(layers "F.Cu" "F.Paste" "F.Mask")
			(roundrect_rratio 0.25)
			(net 56 "/PCIE_{O}_TX0-")
			(pintype "passive")
		)
	)
	(footprint "antmicro-footprints:WQFN-42-1EP_3.5x9mm_P0.5mm"
		(layer "F.Cu")
		(at 125.005 115.628251 90)
		(descr "WQFN, 42 Pin (http://www.ti.com/lit/ds/symlink/ts3l501e.pdf#page=23), generated with kicad-footprint-generator ipc_noLead_generator.py")
		(tags "WQFN NoLead")
		(property "Reference" "U2"
			(at 0.868251 -4.985 90)
			(layer "F.SilkS")
			(effects
				(font
					(size 0.7 0.7)
					(thickness 0.15)
				)
				(justify left bottom)
			)
		)
		(property "Value" "PI3EQX16904GL"
			(at 0 5.82 90)
			(layer "F.Fab")
			(effects
				(font
					(size 0.7 0.7)
					(thickness 0.15)
				)
				(justify left bottom)
			)
		)
		(property "Footprint" "antmicro-footprints:WQFN-42-1EP_3.5x9mm_P0.5mm"
			(at 0 0 90)
			(layer "F.Fab")
			(hide yes)
			(effects
				(font
					(size 1.27 1.27)
					(thickness 0.15)
				)
			)
		)
		(property "Datasheet" "https://www.diodes.com/part/view/PI3EQX16904GL"
			(at 0 0 90)
			(layer "F.Fab")
			(hide yes)
			(effects
				(font
					(size 1.27 1.27)
					(thickness 0.15)
				)
			)
		)
		(property "Description" "16Gbps 4-Channel ReDriver with Linear Equalization"
			(at 0 0 90)
			(layer "F.Fab")
			(hide yes)
			(effects
				(font
					(size 1.27 1.27)
					(thickness 0.15)
				)
			)
		)
		(property "MPN" "PI3EQX16904GLZHEX"
			(at 0 0 90)
			(unlocked yes)
			(layer "F.Fab")
			(hide yes)
			(effects
				(font
					(size 1 1)
					(thickness 0.15)
				)
			)
		)
		(property "Manufacturer" "Diodes Incorporated"
			(at 0 0 90)
			(unlocked yes)
			(layer "F.Fab")
			(hide yes)
			(effects
				(font
					(size 1 1)
					(thickness 0.15)
				)
			)
		)
		(property "Author" "Antmicro"
			(at 0 0 90)
			(unlocked yes)
			(layer "F.Fab")
			(hide yes)
			(effects
				(font
					(size 1 1)
					(thickness 0.15)
				)
			)
		)
		(property "License" "Apache-2.0"
			(at 0 0 90)
			(unlocked yes)
			(layer "F.Fab")
			(hide yes)
			(effects
				(font
					(size 1 1)
					(thickness 0.15)
				)
			)
		)
		(sheetname "Root")
		(sheetfile "jetson-orin-baseboard-oculink-expansion.kicad_sch")
		(attr smd)
		(fp_line
			(start 1.86 -4.611)
			(end 1.86 -4.385)
			(stroke
				(width 0.15)
				(type solid)
			)
			(layer "F.SilkS")
		)
		(fp_line
			(start 1.134 -4.611)
			(end 1.86 -4.611)
			(stroke
				(width 0.15)
				(type solid)
			)
			(layer "F.SilkS")
		)
		(fp_line
			(start -1.135 -4.611)
			(end -1.861 -4.611)
			(stroke
				(width 0.15)
				(type solid)
			)
			(layer "F.SilkS")
		)
		(fp_line
			(start 1.86 4.61)
			(end 1.86 4.384)
			(stroke
				(width 0.15)
				(type solid)
			)
			(layer "F.SilkS")
		)
		(fp_line
			(start 1.134 4.61)
			(end 1.86 4.61)
			(stroke
				(width 0.15)
				(type solid)
			)
			(layer "F.SilkS")
		)
		(fp_line
			(start -1.135 4.61)
			(end -1.861 4.61)
			(stroke
				(width 0.15)
				(type solid)
			)
			(layer "F.SilkS")
		)
		(fp_line
			(start -1.861 4.61)
			(end -1.861 4.384)
			(stroke
				(width 0.15)
				(type solid)
			)
			(layer "F.SilkS")
		)
		(fp_circle
			(center -2.68 -4)
			(end -2.63 -4)
			(stroke
				(width 0.15)
				(type solid)
			)
			(fill solid)
			(layer "F.SilkS")
		)
		(fp_rect
			(start -2.25 -5)
			(end 2.249 4.998)
			(stroke
				(width 0.05)
				(type solid)
			)
			(fill none)
			(layer "F.CrtYd")
		)
		(fp_line
			(start 1.749 -4.5)
			(end 1.749 4.498)
			(stroke
				(width 0.15)
				(type solid)
			)
			(layer "F.Fab")
		)
		(fp_line
			(start -0.875 -4.5)
			(end 1.749 -4.5)
			(stroke
				(width 0.15)
				(type solid)
			)
			(layer "F.Fab")
		)
		(fp_line
			(start -1.75 -3.625)
			(end -0.875 -4.5)
			(stroke
				(width 0.15)
				(type solid)
			)
			(layer "F.Fab")
		)
		(fp_line
			(start 1.749 4.498)
			(end -1.75 4.498)
			(stroke
				(width 0.15)
				(type solid)
			)
			(layer "F.Fab")
		)
		(fp_line
			(start -1.75 4.498)
			(end -1.75 -3.625)
			(stroke
				(width 0.15)
				(type solid)
			)
			(layer "F.Fab")
		)
		(fp_text user "License: Apache-2.0"
			(at -2.73 9.02 90)
			(layer "F.Fab")
			(hide yes)
			(effects
				(font
					(size 0.7 0.7)
					(thickness 0.15)
				)
				(justify left bottom)
			)
		)
		(fp_text user "${REFERENCE}"
			(at -2.73 10.22 90)
			(layer "F.Fab")
			(hide yes)
			(effects
				(font
					(size 0.7 0.7)
					(thickness 0.15)
				)
				(justify left bottom)
			)
		)
		(fp_text user "Author: Antmicro"
			(at -2.73 7.82 90)
			(layer "F.Fab")
			(hide yes)
			(effects
				(font
					(size 0.7 0.7)
					(thickness 0.15)
				)
				(justify left bottom)
			)
		)
		(pad "" smd roundrect
			(at -0.51 -3.242 90)
			(size 0.83 0.87)
			(layers "F.Paste")
			(roundrect_rratio 0.25)
		)
		(pad "" smd roundrect
			(at -0.51 -2.161 90)
			(size 0.83 0.87)
			(layers "F.Paste")
			(roundrect_rratio 0.25)
		)
		(pad "" smd roundrect
			(at -0.51 -1.081 90)
			(size 0.83 0.87)
			(layers "F.Paste")
			(roundrect_rratio 0.25)
		)
		(pad "" smd roundrect
			(at -0.51 0 90)
			(size 0.83 0.87)
			(layers "F.Paste")
			(roundrect_rratio 0.25)
		)
		(pad "" smd roundrect
			(at -0.51 1.08 90)
			(size 0.83 0.87)
			(layers "F.Paste")
			(roundrect_rratio 0.25)
		)
		(pad "" smd roundrect
			(at -0.51 2.16 90)
			(size 0.83 0.87)
			(layers "F.Paste")
			(roundrect_rratio 0.25)
		)
		(pad "" smd roundrect
			(at -0.51 3.24 90)
			(size 0.83 0.87)
			(layers "F.Paste")
			(roundrect_rratio 0.25)
		)
		(pad "" smd roundrect
			(at 0.508 -3.242 90)
			(size 0.83 0.87)
			(layers "F.Paste")
			(roundrect_rratio 0.25)
		)
		(pad "" smd roundrect
			(at 0.508 -2.161 90)
			(size 0.83 0.87)
			(layers "F.Paste")
			(roundrect_rratio 0.25)
		)
		(pad "" smd roundrect
			(at 0.508 -1.081 90)
			(size 0.83 0.87)
			(layers "F.Paste")
			(roundrect_rratio 0.25)
		)
		(pad "" smd roundrect
			(at 0.508 0 90)
			(size 0.83 0.87)
			(layers "F.Paste")
			(roundrect_rratio 0.25)
		)
		(pad "" smd roundrect
			(at 0.508 1.08 90)
			(size 0.83 0.87)
			(layers "F.Paste")
			(roundrect_rratio 0.25)
		)
		(pad "" smd roundrect
			(at 0.508 2.16 90)
			(size 0.83 0.87)
			(layers "F.Paste")
			(roundrect_rratio 0.25)
		)
		(pad "" smd roundrect
			(at 0.508 3.24 90)
			(size 0.83 0.87)
			(layers "F.Paste")
			(roundrect_rratio 0.25)
		)
		(pad "1" smd roundrect
			(at -1.688 -4 90)
			(size 0.875 0.25)
			(layers "F.Cu" "F.Paste" "F.Mask")
			(roundrect_rratio 0.25)
			(net 91 "/RX_EQ2")
			(pinfunction "EQ2")
			(pintype "passive")
		)
		(pad "2" smd roundrect
			(at -1.688 -3.5 90)
			(size 0.875 0.25)
			(layers "F.Cu" "F.Paste" "F.Mask")
			(roundrect_rratio 0.25)
			(net 94 "/RX_SW")
			(pinfunction "SW1")
			(pintype "input")
		)
		(pad "3" smd roundrect
			(at -1.688 -3 90)
			(size 0.875 0.25)
			(layers "F.Cu" "F.Paste" "F.Mask")
			(roundrect_rratio 0.25)
			(net 23 "+3V3")
			(pinfunction "VCC")
			(pintype "passive")
		)
		(pad "4" smd roundrect
			(at -1.688 -2.5 90)
			(size 0.875 0.25)
			(layers "F.Cu" "F.Paste" "F.Mask")
			(roundrect_rratio 0.25)
			(net 84 "/PCIE_{O}_RX1-")
			(pinfunction "A0RX+")
			(pintype "input")
		)
		(pad "5" smd roundrect
			(at -1.688 -2 90)
			(size 0.875 0.25)
			(layers "F.Cu" "F.Paste" "F.Mask")
			(roundrect_rratio 0.25)
			(net 82 "/PCIE_{O}_RX1+")
			(pinfunction "A0RX-")
			(pintype "input")
		)
		(pad "6" smd roundrect
			(at -1.688 -1.5 90)
			(size 0.875 0.25)
			(layers "F.Cu" "F.Paste" "F.Mask")
			(roundrect_rratio 0.25)
			(net 23 "+3V3")
			(pinfunction "VCC")
			(pintype "passive")
		)
		(pad "7" smd roundrect
			(at -1.688 -1 90)
			(size 0.875 0.25)
			(layers "F.Cu" "F.Paste" "F.Mask")
			(roundrect_rratio 0.25)
			(net 83 "/PCIE_{O}_RX0-")
			(pinfunction "A1RX+")
			(pintype "input")
		)
		(pad "8" smd roundrect
			(at -1.688 -0.5 90)
			(size 0.875 0.25)
			(layers "F.Cu" "F.Paste" "F.Mask")
			(roundrect_rratio 0.25)
			(net 81 "/PCIE_{O}_RX0+")
			(pinfunction "A1RX-")
			(pintype "input")
		)
		(pad "9" smd roundrect
			(at -1.688 0 90)
			(size 0.875 0.25)
			(layers "F.Cu" "F.Paste" "F.Mask")
			(roundrect_rratio 0.25)
			(net 23 "+3V3")
			(pinfunction "VCC")
			(pintype "passive")
		)
		(pad "10" smd roundrect
			(at -1.688 0.5 90)
			(size 0.875 0.25)
			(layers "F.Cu" "F.Paste" "F.Mask")
			(roundrect_rratio 0.25)
			(net 118 "unconnected-(U2-A2RX+-Pad10)")
			(pinfunction "A2RX+")
			(pintype "input+no_connect")
		)
		(pad "11" smd roundrect
			(at -1.688 1 90)
			(size 0.875 0.25)
			(layers "F.Cu" "F.Paste" "F.Mask")
			(roundrect_rratio 0.25)
			(net 113 "unconnected-(U2-A2RX--Pad11)")
			(pinfunction "A2RX-")
			(pintype "input+no_connect")
		)
		(pad "12" smd roundrect
			(at -1.688 1.5 90)
			(size 0.875 0.25)
			(layers "F.Cu" "F.Paste" "F.Mask")
			(roundrect_rratio 0.25)
			(net 23 "+3V3")
			(pinfunction "VCC")
			(pintype "power_in")
		)
		(pad "13" smd roundrect
			(at -1.688 2 90)
			(size 0.875 0.25)
			(layers "F.Cu" "F.Paste" "F.Mask")
			(roundrect_rratio 0.25)
			(net 127 "unconnected-(U2-A3RX+-Pad13)")
			(pinfunction "A3RX+")
			(pintype "input+no_connect")
		)
		(pad "14" smd roundrect
			(at -1.688 2.5 90)
			(size 0.875 0.25)
			(layers "F.Cu" "F.Paste" "F.Mask")
			(roundrect_rratio 0.25)
			(net 114 "unconnected-(U2-A3RX--Pad14)")
			(pinfunction "A3RX-")
			(pintype "input+no_connect")
		)
		(pad "15" smd roundrect
			(at -1.688 3 90)
			(size 0.875 0.25)
			(layers "F.Cu" "F.Paste" "F.Mask")
			(roundrect_rratio 0.25)
			(net 23 "+3V3")
			(pinfunction "VCC")
			(pintype "passive")
		)
		(pad "16" smd roundrect
			(at -1.688 3.5 90)
			(size 0.875 0.25)
			(layers "F.Cu" "F.Paste" "F.Mask")
			(roundrect_rratio 0.25)
			(net 110 "Net-(U2-~{I2C_{RESET}})")
			(pinfunction "~{I2C_{RESET}}")
			(pintype "input")
		)
		(pad "17" smd roundrect
			(at -1.688 4 90)
			(size 0.875 0.25)
			(layers "F.Cu" "F.Paste" "F.Mask")
			(roundrect_rratio 0.25)
			(net 51 "GND")
			(pinfunction "AD1")
			(pintype "passive")
		)
		(pad "18" smd roundrect
			(at -0.75 4.437 90)
			(size 0.25 0.875)
			(layers "F.Cu" "F.Paste" "F.Mask")
			(roundrect_rratio 0.25)
			(net 95 "Net-(U2-SDA)")
			(pinfunction "SDA")
			(pintype "open_collector")
		)
		(pad "19" smd roundrect
			(at -0.25 4.437 90)
			(size 0.25 0.875)
			(layers "F.Cu" "F.Paste" "F.Mask")
			(roundrect_rratio 0.25)
			(net 106 "Net-(U2-SCL)")
			(pinfunction "SCL")
			(pintype "open_collector")
		)
		(pad "20" smd roundrect
			(at 0.25 4.437 90)
			(size 0.25 0.875)
			(layers "F.Cu" "F.Paste" "F.Mask")
			(roundrect_rratio 0.25)
			(net 71 "/~{CPRSNT}")
			(pinfunction "~{PRSNT}")
			(pintype "input")
		)
		(pad "21" smd roundrect
			(at 0.75 4.437 90)
			(size 0.25 0.875)
			(layers "F.Cu" "F.Paste" "F.Mask")
			(roundrect_rratio 0.25)
			(net 103 "Net-(U2-EN_{I2C})")
			(pinfunction "EN_{I2C}")
			(pintype "input")
		)
		(pad "22" smd roundrect
			(at 1.687 4 90)
			(size 0.875 0.25)
			(layers "F.Cu" "F.Paste" "F.Mask")
			(roundrect_rratio 0.25)
			(net 109 "Net-(U2-I2C_{DONE})")
			(pinfunction "I2C_{DONE}")
			(pintype "input")
		)
		(pad "23" smd roundrect
			(at 1.687 3.5 90)
			(size 0.875 0.25)
			(layers "F.Cu" "F.Paste" "F.Mask")
			(roundrect_rratio 0.25)
			(net 97 "Net-(U2-RXDET)")
			(pinfunction "RXDET")
			(pintype "input")
		)
		(pad "24" smd roundrect
			(at 1.687 3 90)
			(size 0.875 0.25)
			(layers "F.Cu" "F.Paste" "F.Mask")
			(roundrect_rratio 0.25)
			(net 23 "+3V3")
			(pinfunction "VCC")
			(pintype "passive")
		)
		(pad "25" smd roundrect
			(at 1.687 2.5 90)
			(size 0.875 0.25)
			(layers "F.Cu" "F.Paste" "F.Mask")
			(roundrect_rratio 0.25)
			(net 115 "unconnected-(U2-A3TX--Pad25)")
			(pinfunction "A3TX-")
			(pintype "output+no_connect")
		)
		(pad "26" smd roundrect
			(at 1.687 2 90)
			(size 0.875 0.25)
			(layers "F.Cu" "F.Paste" "F.Mask")
			(roundrect_rratio 0.25)
			(net 128 "unconnected-(U2-A3TX+-Pad26)")
			(pinfunction "A3TX+")
			(pintype "input+no_connect")
		)
		(pad "27" smd roundrect
			(at 1.687 1.5 90)
			(size 0.875 0.25)
			(layers "F.Cu" "F.Paste" "F.Mask")
			(roundrect_rratio 0.25)
			(net 23 "+3V3")
			(pinfunction "VCC")
			(pintype "passive")
		)
		(pad "28" smd roundrect
			(at 1.687 1 90)
			(size 0.875 0.25)
			(layers "F.Cu" "F.Paste" "F.Mask")
			(roundrect_rratio 0.25)
			(net 117 "unconnected-(U2-A2TX--Pad28)")
			(pinfunction "A2TX-")
			(pintype "output+no_connect")
		)
		(pad "29" smd roundrect
			(at 1.687 0.5 90)
			(size 0.875 0.25)
			(layers "F.Cu" "F.Paste" "F.Mask")
			(roundrect_rratio 0.25)
			(net 116 "unconnected-(U2-A2TX+-Pad29)")
			(pinfunction "A2TX+")
			(pintype "input+no_connect")
		)
		(pad "30" smd roundrect
			(at 1.687 0 90)
			(size 0.875 0.25)
			(layers "F.Cu" "F.Paste" "F.Mask")
			(roundrect_rratio 0.25)
			(net 23 "+3V3")
			(pinfunction "VCC")
			(pintype "passive")
		)
		(pad "31" smd roundrect
			(at 1.687 -0.5 90)
			(size 0.875 0.25)
			(layers "F.Cu" "F.Paste" "F.Mask")
			(roundrect_rratio 0.25)
			(net 77 "/PCIE_{I}_C.RX0+")
			(pinfunction "A1TX-")
			(pintype "output")
		)
		(pad "32" smd roundrect
			(at 1.687 -1 90)
			(size 0.875 0.25)
			(layers "F.Cu" "F.Paste" "F.Mask")
			(roundrect_rratio 0.25)
			(net 73 "/PCIE_{I}_C.RX0-")
			(pinfunction "A1TX+")
			(pintype "input")
		)
		(pad "33" smd roundrect
			(at 1.687 -1.5 90)
			(size 0.875 0.25)
			(layers "F.Cu" "F.Paste" "F.Mask")
			(roundrect_rratio 0.25)
			(net 23 "+3V3")
			(pinfunction "VCC")
			(pintype "passive")
		)
		(pad "34" smd roundrect
			(at 1.687 -2 90)
			(size 0.875 0.25)
			(layers "F.Cu" "F.Paste" "F.Mask")
			(roundrect_rratio 0.25)
			(net 80 "/PCIE_{I}_C.RX1+")
			(pinfunction "A0TX-")
			(pintype "output")
		)
		(pad "35" smd roundrect
			(at 1.687 -2.5 90)
			(size 0.875 0.25)
			(layers "F.Cu" "F.Paste" "F.Mask")
			(roundrect_rratio 0.25)
			(net 76 "/PCIE_{I}_C.RX1-")
			(pinfunction "A0TX+")
			(pintype "input")
		)
		(pad "36" smd roundrect
			(at 1.687 -3 90)
			(size 0.875 0.25)
			(layers "F.Cu" "F.Paste" "F.Mask")
			(roundrect_rratio 0.25)
			(net 23 "+3V3")
			(pinfunction "VCC")
			(pintype "passive")
		)
		(pad "37" smd roundrect
			(at 1.687 -3.5 90)
			(size 0.875 0.25)
			(layers "F.Cu" "F.Paste" "F.Mask")
			(roundrect_rratio 0.25)
			(net 92 "/RX_FG0")
			(pinfunction "FG0")
			(pintype "passive")
		)
		(pad "38" smd roundrect
			(at 1.687 -4 90)
			(size 0.875 0.25)
			(layers "F.Cu" "F.Paste" "F.Mask")
			(roundrect_rratio 0.25)
			(net 93 "/RX_FG1")
			(pinfunction "FG1")
			(pintype "passive")
		)
		(pad "39" smd roundrect
			(at 0.75 -4.438 90)
			(size 0.25 0.875)
			(layers "F.Cu" "F.Paste" "F.Mask")
			(roundrect_rratio 0.25)
			(net 89 "/RX_EQ0")
			(pinfunction "EQ0")
			(pintype "passive")
		)
		(pad "40" smd roundrect
			(at 0.25 -4.438 90)
			(size 0.25 0.875)
			(layers "F.Cu" "F.Paste" "F.Mask")
			(roundrect_rratio 0.25)
			(net 90 "/RX_EQ1")
			(pinfunction "EQ1")
			(pintype "passive")
		)
		(pad "41" smd roundrect
			(at -0.25 -4.438 90)
			(size 0.25 0.875)
			(layers "F.Cu" "F.Paste" "F.Mask")
			(roundrect_rratio 0.25)
			(net 51 "GND")
			(pinfunction "AD2")
			(pintype "passive")
		)
		(pad "42" smd roundrect
			(at -0.75 -4.438 90)
			(size 0.25 0.875)
			(layers "F.Cu" "F.Paste" "F.Mask")
			(roundrect_rratio 0.25)
			(net 51 "GND")
			(pinfunction "AD3")
			(pintype "passive")
		)
		(pad "43" smd rect
			(at 0 0 90)
			(size 2.05 7.55)
			(layers "F.Cu" "F.Mask")
			(net 51 "GND")
			(pinfunction "GND")
			(pintype "power_in")
		)
	)
	(footprint "antmicro-footprints:oshw-logo"
		(layer "F.Cu")
		(at 143.8 94.1 90)
		(descr "OSHW Logo")
		(tags "OSHW Logo")
		(property "Reference" "N3"
			(at 0 -4.4 90)
			(layer "F.SilkS")
			(hide yes)
			(effects
				(font
					(size 0.7 0.7)
					(thickness 0.15)
				)
				(justify left bottom)
			)
		)
		(property "Value" "oshw_logo"
			(at 0 -3.4 90)
			(layer "F.Fab")
			(hide yes)
			(effects
				(font
					(size 0.7 0.7)
					(thickness 0.15)
				)
				(justify left bottom)
			)
		)
		(property "Footprint" "antmicro-footprints:oshw-logo"
			(at 0 0 90)
			(layer "F.Fab")
			(hide yes)
			(effects
				(font
					(size 1.27 1.27)
					(thickness 0.15)
				)
			)
		)
		(property "Description" "Mechanical part"
			(at 0 0 90)
			(layer "F.Fab")
			(hide yes)
			(effects
				(font
					(size 1.27 1.27)
					(thickness 0.15)
				)
			)
		)
		(property "Author" "Antmicro"
			(at 0 0 90)
			(unlocked yes)
			(layer "F.Fab")
			(hide yes)
			(effects
				(font
					(size 1 1)
					(thickness 0.15)
				)
			)
		)
		(property "License" "Apache-2.0"
			(at 0 0 90)
			(unlocked yes)
			(layer "F.Fab")
			(hide yes)
			(effects
				(font
					(size 1 1)
					(thickness 0.15)
				)
			)
		)
		(property "MPN" ""
			(at 0 0 90)
			(unlocked yes)
			(layer "F.Fab")
			(hide yes)
			(effects
				(font
					(size 1 1)
					(thickness 0.15)
				)
			)
		)
		(property "Manufacturer" ""
			(at 0 0 90)
			(unlocked yes)
			(layer "F.Fab")
			(hide yes)
			(effects
				(font
					(size 1 1)
					(thickness 0.15)
				)
			)
		)
		(sheetname "Root")
		(sheetfile "jetson-orin-baseboard-oculink-expansion.kicad_sch")
		(attr exclude_from_pos_files exclude_from_bom allow_soldermask_bridges)
		(fp_poly
			(pts
				(xy -0.843 2.558) (xy -0.815 2.564) (xy -0.794 2.572) (xy -0.773 2.581) (xy -0.759 2.589) (xy -0.738 2.603)
				(xy -0.783 2.658) (xy -0.8 2.677) (xy -0.814 2.694) (xy -0.825 2.706) (xy -0.831 2.712) (xy -0.832 2.712)
				(xy -0.837 2.71) (xy -0.847 2.703) (xy -0.849 2.702) (xy -0.874 2.69) (xy -0.904 2.684) (xy -0.935 2.685)
				(xy -0.942 2.686) (xy -0.975 2.698) (xy -1.001 2.717) (xy -1.02 2.741) (xy -1.034 2.766) (xy -1.039 3.197)
				(xy -1.164 3.2) (xy -1.164 2.565) (xy -1.037 2.565) (xy -1.037 2.626) (xy -1.009 2.604) (xy -0.972 2.579)
				(xy -0.931 2.563) (xy -0.887 2.556) (xy -0.843 2.558)
			)
			(stroke
				(width 0.01)
				(type solid)
			)
			(fill solid)
			(layer "F.Cu")
		)
		(fp_poly
			(pts
				(xy 1.889 1.554) (xy 1.907 1.559) (xy 1.927 1.566) (xy 1.948 1.574) (xy 1.966 1.583) (xy 1.979 1.592)
				(xy 1.984 1.597) (xy 1.982 1.604) (xy 1.974 1.616) (xy 1.962 1.633) (xy 1.946 1.652) (xy 1.945 1.654)
				(xy 1.929 1.673) (xy 1.915 1.689) (xy 1.906 1.7) (xy 1.901 1.706) (xy 1.896 1.705) (xy 1.885 1.7)
				(xy 1.873 1.695) (xy 1.84 1.683) (xy 1.808 1.68) (xy 1.776 1.685) (xy 1.747 1.698) (xy 1.723 1.717)
				(xy 1.704 1.742) (xy 1.696 1.763) (xy 1.695 1.772) (xy 1.694 1.79) (xy 1.693 1.817) (xy 1.692 1.85)
				(xy 1.692 1.89) (xy 1.691 1.934) (xy 1.691 1.983) (xy 1.691 2.194) (xy 1.559 2.194) (xy 1.559 1.559)
				(xy 1.691 1.559) (xy 1.691 1.626) (xy 1.71 1.607) (xy 1.739 1.585) (xy 1.775 1.568) (xy 1.814 1.556)
				(xy 1.855 1.552) (xy 1.889 1.554)
			)
			(stroke
				(width 0.01)
				(type solid)
			)
			(fill solid)
			(layer "F.Cu")
		)
		(fp_poly
			(pts
				(xy -0.837 1.56) (xy -0.797 1.576) (xy -0.761 1.6) (xy -0.73 1.63) (xy -0.706 1.667) (xy -0.69 1.709)
				(xy -0.687 1.721) (xy -0.685 1.734) (xy -0.684 1.757) (xy -0.683 1.79) (xy -0.682 1.833) (xy -0.681 1.884)
				(xy -0.681 1.945) (xy -0.681 1.971) (xy -0.681 2.194) (xy -0.808 2.194) (xy -0.809 1.984) (xy -0.811 1.774)
				(xy -0.826 1.744) (xy -0.845 1.716) (xy -0.868 1.697) (xy -0.897 1.686) (xy -0.925 1.682) (xy -0.947 1.682)
				(xy -0.967 1.684) (xy -0.979 1.686) (xy -1.001 1.698) (xy -1.023 1.716) (xy -1.041 1.738) (xy -1.049 1.752)
				(xy -1.052 1.758) (xy -1.054 1.765) (xy -1.056 1.773) (xy -1.057 1.783) (xy -1.058 1.797) (xy -1.059 1.815)
				(xy -1.06 1.839) (xy -1.06 1.869) (xy -1.061 1.907) (xy -1.061 1.953) (xy -1.061 1.985) (xy -1.063 2.194)
				(xy -1.189 2.194) (xy -1.189 1.559) (xy -1.062 1.559) (xy -1.062 1.625) (xy -1.033 1.602) (xy -1.001 1.579)
				(xy -0.969 1.564) (xy -0.934 1.555) (xy -0.927 1.554) (xy -0.881 1.553) (xy -0.837 1.56)
			)
			(stroke
				(width 0.01)
				(type solid)
			)
			(fill solid)
			(layer "F.Cu")
		)
		(fp_poly
			(pts
				(xy 1.042 1.769) (xy 1.043 1.979) (xy 1.059 2.009) (xy 1.077 2.036) (xy 1.1 2.056) (xy 1.129 2.067)
				(xy 1.159 2.071) (xy 1.193 2.07) (xy 1.221 2.063) (xy 1.245 2.047) (xy 1.258 2.034) (xy 1.266 2.025)
				(xy 1.273 2.016) (xy 1.278 2.008) (xy 1.282 1.997) (xy 1.286 1.985) (xy 1.288 1.969) (xy 1.29 1.948)
				(xy 1.291 1.922) (xy 1.292 1.89) (xy 1.293 1.85) (xy 1.293 1.801) (xy 1.294 1.766) (xy 1.295 1.559)
				(xy 1.422 1.559) (xy 1.422 2.194) (xy 1.295 2.194) (xy 1.295 2.161) (xy 1.295 2.144) (xy 1.293 2.132)
				(xy 1.292 2.128) (xy 1.287 2.131) (xy 1.278 2.14) (xy 1.271 2.147) (xy 1.256 2.159) (xy 1.236 2.171)
				(xy 1.219 2.181) (xy 1.202 2.188) (xy 1.186 2.193) (xy 1.17 2.196) (xy 1.148 2.197) (xy 1.135 2.198)
				(xy 1.107 2.198) (xy 1.087 2.197) (xy 1.07 2.194) (xy 1.059 2.19) (xy 1.036 2.181) (xy 1.019 2.172)
				(xy 1.003 2.161) (xy 0.985 2.146) (xy 0.981 2.141) (xy 0.952 2.107) (xy 0.931 2.068) (xy 0.92 2.033)
				(xy 0.918 2.019) (xy 0.917 1.996) (xy 0.916 1.963) (xy 0.915 1.92) (xy 0.914 1.869) (xy 0.914 1.808)
				(xy 0.914 1.782) (xy 0.914 1.559) (xy 1.04 1.559) (xy 1.042 1.769)
			)
			(stroke
				(width 0.01)
				(type solid)
			)
			(fill solid)
			(layer "F.Cu")
		)
		(fp_poly
			(pts
				(xy 1.753 2.563) (xy 1.768 2.568) (xy 1.787 2.577) (xy 1.804 2.586) (xy 1.818 2.595) (xy 1.826 2.602)
				(xy 1.827 2.606) (xy 1.824 2.611) (xy 1.815 2.621) (xy 1.803 2.636) (xy 1.789 2.654) (xy 1.775 2.671)
				(xy 1.761 2.688) (xy 1.749 2.701) (xy 1.742 2.71) (xy 1.739 2.712) (xy 1.735 2.71) (xy 1.724 2.704)
				(xy 1.713 2.698) (xy 1.697 2.69) (xy 1.682 2.686) (xy 1.664 2.685) (xy 1.653 2.685) (xy 1.618 2.688)
				(xy 1.59 2.699) (xy 1.566 2.718) (xy 1.561 2.723) (xy 1.554 2.732) (xy 1.548 2.74) (xy 1.544 2.748)
				(xy 1.54 2.758) (xy 1.537 2.769) (xy 1.534 2.785) (xy 1.533 2.804) (xy 1.532 2.829) (xy 1.531 2.861)
				(xy 1.53 2.899) (xy 1.53 2.947) (xy 1.53 2.988) (xy 1.528 3.2) (xy 1.468 3.2) (xy 1.444 3.2) (xy 1.425 3.199)
				(xy 1.411 3.198) (xy 1.405 3.197) (xy 1.404 3.191) (xy 1.404 3.176) (xy 1.403 3.153) (xy 1.403 3.122)
				(xy 1.402 3.085) (xy 1.402 3.042) (xy 1.402 2.993) (xy 1.402 2.941) (xy 1.402 2.886) (xy 1.402 2.565)
				(xy 1.529 2.565) (xy 1.529 2.595) (xy 1.529 2.611) (xy 1.53 2.623) (xy 1.532 2.626) (xy 1.537 2.623)
				(xy 1.547 2.615) (xy 1.554 2.608) (xy 1.588 2.584) (xy 1.627 2.567) (xy 1.669 2.558) (xy 1.712 2.556)
				(xy 1.753 2.563)
			)
			(stroke
				(width 0.01)
				(type solid)
			)
			(fill solid)
			(layer "F.Cu")
		)
		(fp_poly
			(pts
				(xy 2.316 1.557) (xy 2.365 1.57) (xy 2.41 1.593) (xy 2.453 1.625) (xy 2.46 1.631) (xy 2.491 1.661)
				(xy 2.466 1.684) (xy 2.448 1.699) (xy 2.43 1.715) (xy 2.419 1.725) (xy 2.397 1.743) (xy 2.376 1.724)
				(xy 2.345 1.701) (xy 2.312 1.687) (xy 2.274 1.681) (xy 2.265 1.681) (xy 2.226 1.684) (xy 2.195 1.693)
				(xy 2.167 1.708) (xy 2.159 1.715) (xy 2.136 1.741) (xy 2.118 1.776) (xy 2.107 1.817) (xy 2.103 1.866)
				(xy 2.103 1.876) (xy 2.106 1.926) (xy 2.116 1.97) (xy 2.132 2.006) (xy 2.155 2.034) (xy 2.184 2.055)
				(xy 2.219 2.067) (xy 2.259 2.072) (xy 2.274 2.071) (xy 2.309 2.066) (xy 2.339 2.056) (xy 2.366 2.038)
				(xy 2.377 2.028) (xy 2.386 2.02) (xy 2.393 2.016) (xy 2.4 2.015) (xy 2.409 2.018) (xy 2.42 2.027)
				(xy 2.436 2.041) (xy 2.456 2.059) (xy 2.491 2.092) (xy 2.476 2.108) (xy 2.449 2.132) (xy 2.416 2.155)
				(xy 2.38 2.174) (xy 2.35 2.186) (xy 2.327 2.193) (xy 2.306 2.197) (xy 2.283 2.199) (xy 2.259 2.199)
				(xy 2.233 2.198) (xy 2.209 2.196) (xy 2.189 2.193) (xy 2.182 2.191) (xy 2.133 2.173) (xy 2.089 2.146)
				(xy 2.053 2.112) (xy 2.023 2.071) (xy 2.012 2.051) (xy 2 2.023) (xy 1.991 1.999) (xy 1.984 1.975)
				(xy 1.981 1.948) (xy 1.979 1.917) (xy 1.978 1.879) (xy 1.978 1.877) (xy 1.979 1.838) (xy 1.98 1.806)
				(xy 1.984 1.78) (xy 1.99 1.756) (xy 1.999 1.731) (xy 2.011 1.704) (xy 2.012 1.701) (xy 2.039 1.657)
				(xy 2.072 1.62) (xy 2.111 1.591) (xy 2.156 1.57) (xy 2.207 1.557) (xy 2.263 1.552) (xy 2.316 1.557)
			)
			(stroke
				(width 0.01)
				(type solid)
			)
			(fill solid)
			(layer "F.Cu")
		)
		(fp_poly
			(pts
				(xy -1.494 1.56) (xy -1.447 1.576) (xy -1.405 1.6) (xy -1.368 1.633) (xy -1.341 1.668) (xy -1.326 1.692)
				(xy -1.316 1.716) (xy -1.308 1.743) (xy -1.302 1.774) (xy -1.299 1.811) (xy -1.297 1.845) (xy -1.294 1.925)
				(xy -1.692 1.925) (xy -1.692 1.942) (xy -1.687 1.977) (xy -1.673 2.011) (xy -1.65 2.039) (xy -1.626 2.059)
				(xy -1.601 2.071) (xy -1.572 2.078) (xy -1.537 2.079) (xy -1.497 2.074) (xy -1.458 2.06) (xy -1.422 2.036)
				(xy -1.421 2.036) (xy -1.402 2.021) (xy -1.359 2.057) (xy -1.342 2.072) (xy -1.327 2.085) (xy -1.317 2.094)
				(xy -1.314 2.098) (xy -1.316 2.103) (xy -1.324 2.113) (xy -1.338 2.126) (xy -1.354 2.139) (xy -1.372 2.152)
				(xy -1.389 2.163) (xy -1.399 2.168) (xy -1.421 2.178) (xy -1.445 2.187) (xy -1.461 2.191) (xy -1.488 2.196)
				(xy -1.522 2.199) (xy -1.557 2.199) (xy -1.591 2.196) (xy -1.62 2.192) (xy -1.629 2.19) (xy -1.677 2.171)
				(xy -1.718 2.146) (xy -1.752 2.114) (xy -1.779 2.074) (xy -1.8 2.026) (xy -1.802 2.02) (xy -1.81 1.989)
				(xy -1.815 1.951) (xy -1.818 1.908) (xy -1.819 1.865) (xy -1.818 1.823) (xy -1.816 1.804) (xy -1.692 1.804)
				(xy -1.692 1.818) (xy -1.428 1.818) (xy -1.428 1.801) (xy -1.432 1.775) (xy -1.442 1.748) (xy -1.457 1.722)
				(xy -1.469 1.707) (xy -1.495 1.688) (xy -1.526 1.676) (xy -1.56 1.672) (xy -1.593 1.676) (xy -1.619 1.685)
				(xy -1.646 1.704) (xy -1.668 1.73) (xy -1.683 1.76) (xy -1.691 1.792) (xy -1.692 1.804) (xy -1.816 1.804)
				(xy -1.814 1.786) (xy -1.812 1.777) (xy -1.797 1.724) (xy -1.775 1.676) (xy -1.747 1.636) (xy -1.713 1.603)
				(xy -1.673 1.578) (xy -1.629 1.561) (xy -1.597 1.554) (xy -1.544 1.552) (xy -1.494 1.56)
			)
			(stroke
				(width 0.01)
				(type solid)
			)
			(fill solid)
			(layer "F.Cu")
		)
		(fp_poly
			(pts
				(xy 2.835 1.557) (xy 2.883 1.57) (xy 2.926 1.592) (xy 2.964 1.621) (xy 2.996 1.657) (xy 3.021 1.699)
				(xy 3.038 1.747) (xy 3.04 1.757) (xy 3.043 1.776) (xy 3.045 1.802) (xy 3.047 1.832) (xy 3.047 1.858)
				(xy 3.047 1.925) (xy 2.65 1.925) (xy 2.653 1.951) (xy 2.663 1.991) (xy 2.68 2.024) (xy 2.703 2.049)
				(xy 2.733 2.067) (xy 2.77 2.077) (xy 2.801 2.079) (xy 2.845 2.075) (xy 2.883 2.063) (xy 2.916 2.042)
				(xy 2.92 2.039) (xy 2.929 2.031) (xy 2.935 2.026) (xy 2.941 2.025) (xy 2.949 2.027) (xy 2.959 2.034)
				(xy 2.974 2.047) (xy 2.994 2.064) (xy 3.01 2.078) (xy 3.023 2.088) (xy 3.03 2.095) (xy 3.032 2.096)
				(xy 3.03 2.1) (xy 3.022 2.11) (xy 3.01 2.122) (xy 3.009 2.123) (xy 2.98 2.147) (xy 2.945 2.169)
				(xy 2.906 2.185) (xy 2.887 2.191) (xy 2.861 2.196) (xy 2.828 2.198) (xy 2.793 2.198) (xy 2.759 2.197)
				(xy 2.729 2.193) (xy 2.721 2.191) (xy 2.675 2.175) (xy 2.634 2.15) (xy 2.599 2.118) (xy 2.569 2.077)
				(xy 2.547 2.029) (xy 2.536 1.996) (xy 2.532 1.973) (xy 2.529 1.942) (xy 2.527 1.906) (xy 2.527 1.869)
				(xy 2.528 1.832) (xy 2.529 1.818) (xy 2.65 1.818) (xy 2.922 1.818) (xy 2.918 1.799) (xy 2.908 1.758)
				(xy 2.891 1.725) (xy 2.869 1.7) (xy 2.84 1.683) (xy 2.826 1.678) (xy 2.788 1.672) (xy 2.753 1.675)
				(xy 2.722 1.687) (xy 2.695 1.706) (xy 2.674 1.734) (xy 2.659 1.768) (xy 2.654 1.794) (xy 2.65 1.818)
				(xy 2.529 1.818) (xy 2.53 1.798) (xy 2.534 1.769) (xy 2.536 1.76) (xy 2.554 1.707) (xy 2.578 1.662)
				(xy 2.609 1.624) (xy 2.645 1.593) (xy 2.687 1.571) (xy 2.734 1.557) (xy 2.783 1.553) (xy 2.835 1.557)
			)
			(stroke
				(width 0.01)
				(type solid)
			)
			(fill solid)
			(layer "F.Cu")
		)
		(fp_poly
			(pts
				(xy -2.733 1.557) (xy -2.685 1.57) (xy -2.642 1.592) (xy -2.604 1.622) (xy -2.581 1.649) (xy -2.562 1.676)
				(xy -2.548 1.706) (xy -2.537 1.739) (xy -2.53 1.777) (xy -2.527 1.821) (xy -2.526 1.873) (xy -2.527 1.907)
				(xy -2.529 1.956) (xy -2.534 1.997) (xy -2.542 2.031) (xy -2.553 2.06) (xy -2.567 2.086) (xy -2.587 2.111)
				(xy -2.603 2.129) (xy -2.637 2.158) (xy -2.673 2.178) (xy -2.714 2.192) (xy -2.76 2.198) (xy -2.789 2.199)
				(xy -2.813 2.198) (xy -2.835 2.196) (xy -2.852 2.194) (xy -2.857 2.194) (xy -2.898 2.179) (xy -2.937 2.155)
				(xy -2.97 2.126) (xy -2.993 2.101) (xy -3.011 2.077) (xy -3.024 2.051) (xy -3.034 2.022) (xy -3.041 1.988)
				(xy -3.045 1.947) (xy -3.047 1.91) (xy -3.047 1.882) (xy -2.919 1.882) (xy -2.919 1.968) (xy -2.903 2.001)
				(xy -2.885 2.031) (xy -2.863 2.051) (xy -2.837 2.064) (xy -2.804 2.07) (xy -2.779 2.07) (xy -2.755 2.069)
				(xy -2.737 2.065) (xy -2.722 2.058) (xy -2.717 2.055) (xy -2.697 2.041) (xy -2.681 2.025) (xy -2.67 2.004)
				(xy -2.662 1.978) (xy -2.657 1.945) (xy -2.654 1.903) (xy -2.654 1.899) (xy -2.653 1.848) (xy -2.656 1.806)
				(xy -2.662 1.772) (xy -2.673 1.744) (xy -2.687 1.722) (xy -2.707 1.705) (xy -2.723 1.695) (xy -2.755 1.684)
				(xy -2.788 1.68) (xy -2.821 1.684) (xy -2.851 1.695) (xy -2.877 1.713) (xy -2.892 1.729) (xy -2.901 1.745)
				(xy -2.908 1.76) (xy -2.913 1.778) (xy -2.916 1.8) (xy -2.918 1.828) (xy -2.919 1.864) (xy -2.919 1.882)
				(xy -3.047 1.882) (xy -3.048 1.844) (xy -3.043 1.786) (xy -3.034 1.736) (xy -3.021 1.695) (xy -3.004 1.664)
				(xy -2.972 1.624) (xy -2.935 1.594) (xy -2.893 1.571) (xy -2.846 1.558) (xy -2.794 1.553) (xy -2.787 1.553)
				(xy -2.733 1.557)
			)
			(stroke
				(width 0.01)
				(type solid)
			)
			(fill solid)
			(layer "F.Cu")
		)
		(fp_poly
			(pts
				(xy 2.148 2.561) (xy 2.193 2.574) (xy 2.235 2.595) (xy 2.273 2.623) (xy 2.304 2.657) (xy 2.326 2.691)
				(xy 2.338 2.718) (xy 2.346 2.745) (xy 2.352 2.774) (xy 2.355 2.808) (xy 2.357 2.85) (xy 2.357 2.858)
				(xy 2.357 2.931) (xy 1.96 2.931) (xy 1.963 2.955) (xy 1.973 2.993) (xy 1.991 3.026) (xy 2.015 3.053)
				(xy 2.039 3.069) (xy 2.057 3.076) (xy 2.08 3.08) (xy 2.103 3.082) (xy 2.144 3.081) (xy 2.18 3.071)
				(xy 2.214 3.054) (xy 2.227 3.045) (xy 2.24 3.035) (xy 2.25 3.029) (xy 2.253 3.027) (xy 2.258 3.03)
				(xy 2.269 3.039) (xy 2.284 3.05) (xy 2.3 3.064) (xy 2.315 3.078) (xy 2.329 3.09) (xy 2.338 3.099)
				(xy 2.341 3.103) (xy 2.337 3.11) (xy 2.327 3.121) (xy 2.312 3.134) (xy 2.294 3.148) (xy 2.276 3.161)
				(xy 2.259 3.171) (xy 2.252 3.175) (xy 2.204 3.192) (xy 2.152 3.202) (xy 2.098 3.204) (xy 2.046 3.198)
				(xy 2.032 3.195) (xy 1.984 3.178) (xy 1.943 3.154) (xy 1.909 3.123) (xy 1.881 3.084) (xy 1.859 3.037)
				(xy 1.847 3.003) (xy 1.841 2.972) (xy 1.838 2.934) (xy 1.836 2.893) (xy 1.837 2.851) (xy 1.839 2.824)
				(xy 1.96 2.824) (xy 2.23 2.824) (xy 2.23 2.813) (xy 2.225 2.783) (xy 2.214 2.753) (xy 2.196 2.725)
				(xy 2.175 2.702) (xy 2.151 2.686) (xy 2.128 2.68) (xy 2.101 2.677) (xy 2.072 2.678) (xy 2.051 2.683)
				(xy 2.023 2.696) (xy 2 2.717) (xy 1.981 2.746) (xy 1.968 2.779) (xy 1.963 2.8) (xy 1.96 2.824) (xy 1.839 2.824)
				(xy 1.839 2.811) (xy 1.844 2.776) (xy 1.848 2.76) (xy 1.866 2.708) (xy 1.889 2.663) (xy 1.919 2.627)
				(xy 1.954 2.598) (xy 1.996 2.575) (xy 2.007 2.571) (xy 2.054 2.559) (xy 2.101 2.556) (xy 2.148 2.561)
			)
			(stroke
				(width 0.01)
				(type solid)
			)
			(fill solid)
			(layer "F.Cu")
		)
		(fp_poly
			(pts
				(xy -0.229 3.2) (xy -0.354 3.197) (xy -0.355 3.165) (xy -0.357 3.133) (xy -0.374 3.148) (xy -0.411 3.175)
				(xy -0.453 3.193) (xy -0.497 3.203) (xy -0.542 3.204) (xy -0.585 3.195) (xy -0.586 3.195) (xy -0.621 3.181)
				(xy -0.651 3.16) (xy -0.673 3.141) (xy -0.689 3.123) (xy -0.702 3.106) (xy -0.712 3.086) (xy -0.72 3.064)
				(xy -0.726 3.038) (xy -0.73 3.007) (xy -0.732 2.968) (xy -0.733 2.922) (xy -0.733 2.88) (xy -0.602 2.88)
				(xy -0.602 2.915) (xy -0.602 2.942) (xy -0.601 2.962) (xy -0.6 2.977) (xy -0.598 2.988) (xy -0.596 2.998)
				(xy -0.592 3.007) (xy -0.591 3.01) (xy -0.574 3.039) (xy -0.552 3.059) (xy -0.525 3.071) (xy -0.492 3.076)
				(xy -0.472 3.076) (xy -0.442 3.072) (xy -0.418 3.063) (xy -0.398 3.048) (xy -0.382 3.029) (xy -0.371 3.004)
				(xy -0.363 2.972) (xy -0.358 2.933) (xy -0.356 2.885) (xy -0.356 2.88) (xy -0.358 2.828) (xy -0.363 2.785)
				(xy -0.373 2.75) (xy -0.387 2.724) (xy -0.406 2.704) (xy -0.43 2.692) (xy -0.46 2.686) (xy -0.483 2.685)
				(xy -0.517 2.687) (xy -0.544 2.696) (xy -0.565 2.711) (xy -0.583 2.734) (xy -0.591 2.751) (xy -0.595 2.76)
				(xy -0.598 2.769) (xy -0.6 2.779) (xy -0.601 2.793) (xy -0.602 2.811) (xy -0.602 2.836) (xy -0.602 2.869)
				(xy -0.602 2.88) (xy -0.733 2.88) (xy -0.733 2.827) (xy -0.732 2.783) (xy -0.729 2.746) (xy -0.725 2.716)
				(xy -0.719 2.691) (xy -0.71 2.67) (xy -0.699 2.651) (xy -0.685 2.633) (xy -0.668 2.616) (xy -0.668 2.615)
				(xy -0.632 2.587) (xy -0.592 2.567) (xy -0.55 2.557) (xy -0.506 2.556) (xy -0.463 2.564) (xy -0.421 2.582)
				(xy -0.411 2.587) (xy -0.394 2.598) (xy -0.377 2.61) (xy -0.373 2.614) (xy -0.356 2.627) (xy -0.356 2.306)
				(xy -0.229 2.306) (xy -0.229 3.2)
			)
			(stroke
				(width 0.01)
				(type solid)
			)
			(fill solid)
			(layer "F.Cu")
		)
		(fp_poly
			(pts
				(xy 0.605 1.558) (xy 0.651 1.574) (xy 0.694 1.598) (xy 0.728 1.627) (xy 0.75 1.652) (xy 0.768 1.678)
				(xy 0.781 1.707) (xy 0.791 1.739) (xy 0.797 1.777) (xy 0.801 1.822) (xy 0.802 1.876) (xy 0.802 1.877)
				(xy 0.801 1.929) (xy 0.798 1.973) (xy 0.792 2.009) (xy 0.784 2.04) (xy 0.774 2.062) (xy 0.748 2.103)
				(xy 0.715 2.139) (xy 0.675 2.167) (xy 0.632 2.187) (xy 0.626 2.189) (xy 0.599 2.195) (xy 0.567 2.198)
				(xy 0.532 2.199) (xy 0.499 2.197) (xy 0.471 2.193) (xy 0.466 2.192) (xy 0.428 2.177) (xy 0.391 2.155)
				(xy 0.359 2.129) (xy 0.354 2.123) (xy 0.332 2.098) (xy 0.316 2.073) (xy 0.303 2.047) (xy 0.294 2.017)
				(xy 0.287 1.983) (xy 0.284 1.943) (xy 0.282 1.894) (xy 0.282 1.877) (xy 0.409 1.877) (xy 0.41 1.918)
				(xy 0.412 1.95) (xy 0.416 1.976) (xy 0.423 1.997) (xy 0.432 2.015) (xy 0.445 2.03) (xy 0.451 2.037)
				(xy 0.471 2.054) (xy 0.491 2.064) (xy 0.514 2.07) (xy 0.543 2.072) (xy 0.569 2.07) (xy 0.59 2.065)
				(xy 0.601 2.06) (xy 0.625 2.047) (xy 0.642 2.031) (xy 0.656 2.009) (xy 0.661 1.998) (xy 0.665 1.989)
				(xy 0.668 1.98) (xy 0.67 1.969) (xy 0.671 1.954) (xy 0.672 1.935) (xy 0.673 1.909) (xy 0.673 1.877)
				(xy 0.673 1.842) (xy 0.672 1.817) (xy 0.671 1.798) (xy 0.67 1.784) (xy 0.668 1.773) (xy 0.665 1.764)
				(xy 0.661 1.755) (xy 0.647 1.73) (xy 0.632 1.712) (xy 0.612 1.698) (xy 0.601 1.693) (xy 0.569 1.683)
				(xy 0.535 1.681) (xy 0.501 1.686) (xy 0.471 1.7) (xy 0.447 1.719) (xy 0.434 1.736) (xy 0.424 1.753)
				(xy 0.417 1.774) (xy 0.412 1.8) (xy 0.41 1.833) (xy 0.409 1.873) (xy 0.409 1.877) (xy 0.282 1.877)
				(xy 0.283 1.824) (xy 0.286 1.78) (xy 0.292 1.742) (xy 0.301 1.711) (xy 0.313 1.683) (xy 0.33 1.657)
				(xy 0.35 1.633) (xy 0.351 1.632) (xy 0.385 1.601) (xy 0.42 1.578) (xy 0.46 1.563) (xy 0.505 1.554)
				(xy 0.555 1.551) (xy 0.605 1.558)
			)
			(stroke
				(width 0.01)
				(type solid)
			)
			(fill solid)
			(layer "F.Cu")
		)
		(fp_poly
			(pts
				(xy 0.004 1.556) (xy 0.054 1.566) (xy 0.102 1.582) (xy 0.146 1.605) (xy 0.154 1.61) (xy 0.193 1.636)
				(xy 0.178 1.655) (xy 0.166 1.668) (xy 0.152 1.686) (xy 0.138 1.7) (xy 0.114 1.727) (xy 0.07 1.705)
				(xy 0.032 1.688) (xy -0.007 1.677) (xy -0.044 1.672) (xy -0.079 1.672) (xy -0.11 1.678) (xy -0.136 1.69)
				(xy -0.154 1.707) (xy -0.162 1.724) (xy -0.164 1.745) (xy -0.164 1.761) (xy -0.159 1.772) (xy -0.15 1.782)
				(xy -0.149 1.783) (xy -0.139 1.791) (xy -0.128 1.797) (xy -0.114 1.802) (xy -0.095 1.805) (xy -0.07 1.808)
				(xy -0.037 1.811) (xy -0.02 1.813) (xy 0.027 1.817) (xy 0.065 1.823) (xy 0.096 1.832) (xy 0.122 1.842)
				(xy 0.14 1.854) (xy 0.166 1.879) (xy 0.186 1.91) (xy 0.2 1.947) (xy 0.206 1.987) (xy 0.206 2.018)
				(xy 0.198 2.06) (xy 0.181 2.097) (xy 0.155 2.129) (xy 0.122 2.156) (xy 0.08 2.177) (xy 0.042 2.189)
				(xy 0.005 2.196) (xy -0.038 2.199) (xy -0.083 2.198) (xy -0.125 2.194) (xy -0.153 2.189) (xy -0.177 2.181)
				(xy -0.204 2.171) (xy -0.229 2.16) (xy -0.232 2.159) (xy -0.251 2.148) (xy -0.272 2.136) (xy -0.292 2.122)
				(xy -0.309 2.109) (xy -0.323 2.098) (xy -0.33 2.09) (xy -0.331 2.088) (xy -0.327 2.084) (xy -0.318 2.073)
				(xy -0.304 2.059) (xy -0.288 2.043) (xy -0.246 2) (xy -0.221 2.021) (xy -0.184 2.047) (xy -0.145 2.065)
				(xy -0.102 2.075) (xy -0.053 2.079) (xy -0.049 2.079) (xy -0.023 2.079) (xy -0.004 2.078) (xy 0.011 2.074)
				(xy 0.025 2.069) (xy 0.029 2.068) (xy 0.054 2.052) (xy 0.071 2.033) (xy 0.079 2.01) (xy 0.078 1.986)
				(xy 0.074 1.975) (xy 0.068 1.964) (xy 0.06 1.956) (xy 0.048 1.949) (xy 0.031 1.944) (xy 0.007 1.939)
				(xy -0.024 1.935) (xy -0.052 1.932) (xy -0.089 1.929) (xy -0.119 1.925) (xy -0.142 1.921) (xy -0.16 1.917)
				(xy -0.176 1.912) (xy -0.192 1.906) (xy -0.201 1.901) (xy -0.235 1.879) (xy -0.262 1.85) (xy -0.28 1.816)
				(xy -0.29 1.776) (xy -0.292 1.75) (xy -0.291 1.727) (xy -0.289 1.705) (xy -0.286 1.689) (xy -0.286 1.688)
				(xy -0.273 1.659) (xy -0.253 1.63) (xy -0.229 1.604) (xy -0.221 1.599) (xy -0.185 1.577) (xy -0.143 1.562)
				(xy -0.096 1.554) (xy -0.047 1.552) (xy 0.004 1.556)
			)
			(stroke
				(width 0.01)
				(type solid)
			)
			(fill solid)
			(layer "F.Cu")
		)
		(fp_poly
			(pts
				(xy 1.038 2.556) (xy 1.091 2.563) (xy 1.137 2.576) (xy 1.177 2.595) (xy 1.209 2.62) (xy 1.234 2.65)
				(xy 1.242 2.665) (xy 1.247 2.677) (xy 1.251 2.691) (xy 1.255 2.708) (xy 1.258 2.727) (xy 1.26 2.751)
				(xy 1.262 2.78) (xy 1.263 2.815) (xy 1.263 2.858) (xy 1.264 2.908) (xy 1.263 2.967) (xy 1.263 2.989)
				(xy 1.262 3.197) (xy 1.135 3.197) (xy 1.133 3.171) (xy 1.132 3.144) (xy 1.119 3.159) (xy 1.096 3.179)
				(xy 1.065 3.193) (xy 1.026 3.202) (xy 0.98 3.204) (xy 0.976 3.204) (xy 0.955 3.204) (xy 0.937 3.203)
				(xy 0.925 3.202) (xy 0.924 3.201) (xy 0.879 3.189) (xy 0.839 3.17) (xy 0.806 3.144) (xy 0.781 3.113)
				(xy 0.763 3.077) (xy 0.753 3.037) (xy 0.753 3.005) (xy 0.873 3.005) (xy 0.874 3.023) (xy 0.878 3.035)
				(xy 0.887 3.047) (xy 0.89 3.05) (xy 0.903 3.063) (xy 0.917 3.072) (xy 0.935 3.078) (xy 0.957 3.081)
				(xy 0.986 3.082) (xy 1.013 3.082) (xy 1.043 3.081) (xy 1.065 3.079) (xy 1.08 3.077) (xy 1.091 3.073)
				(xy 1.096 3.071) (xy 1.112 3.058) (xy 1.123 3.039) (xy 1.13 3.012) (xy 1.132 2.977) (xy 1.132 2.975)
				(xy 1.132 2.931) (xy 1.035 2.931) (xy 0.999 2.931) (xy 0.973 2.931) (xy 0.953 2.932) (xy 0.939 2.934)
				(xy 0.928 2.936) (xy 0.919 2.939) (xy 0.916 2.94) (xy 0.893 2.954) (xy 0.88 2.971) (xy 0.874 2.994)
				(xy 0.873 3.005) (xy 0.753 3.005) (xy 0.753 2.994) (xy 0.761 2.951) (xy 0.768 2.931) (xy 0.776 2.915)
				(xy 0.786 2.901) (xy 0.802 2.884) (xy 0.804 2.882) (xy 0.82 2.867) (xy 0.835 2.854) (xy 0.85 2.845)
				(xy 0.867 2.838) (xy 0.887 2.833) (xy 0.912 2.829) (xy 0.943 2.827) (xy 0.982 2.826) (xy 1.015 2.825)
				(xy 1.133 2.823) (xy 1.132 2.771) (xy 1.131 2.746) (xy 1.129 2.73) (xy 1.127 2.719) (xy 1.123 2.711)
				(xy 1.117 2.705) (xy 1.098 2.691) (xy 1.07 2.682) (xy 1.032 2.677) (xy 1.006 2.677) (xy 0.972 2.678)
				(xy 0.945 2.682) (xy 0.924 2.688) (xy 0.907 2.699) (xy 0.9 2.706) (xy 0.882 2.723) (xy 0.834 2.686)
				(xy 0.816 2.672) (xy 0.801 2.66) (xy 0.79 2.652) (xy 0.787 2.648) (xy 0.791 2.639) (xy 0.801 2.626)
				(xy 0.816 2.612) (xy 0.832 2.6) (xy 0.864 2.581) (xy 0.902 2.568) (xy 0.946 2.559) (xy 0.98 2.556)
				(xy 1.038 2.556)
			)
			(stroke
				(width 0.01)
				(type solid)
			)
			(fill solid)
			(layer "F.Cu")
		)
		(fp_poly
			(pts
				(xy -1.521 2.559) (xy -1.485 2.562) (xy -1.454 2.568) (xy -1.427 2.577) (xy -1.401 2.589) (xy -1.371 2.61)
				(xy -1.345 2.639) (xy -1.325 2.67) (xy -1.321 2.679) (xy -1.309 2.71) (xy -1.309 3.197) (xy -1.433 3.2)
				(xy -1.433 3.172) (xy -1.434 3.157) (xy -1.435 3.147) (xy -1.436 3.144) (xy -1.44 3.147) (xy -1.449 3.156)
				(xy -1.453 3.161) (xy -1.472 3.178) (xy -1.496 3.19) (xy -1.526 3.198) (xy -1.563 3.202) (xy -1.578 3.203)
				(xy -1.603 3.203) (xy -1.627 3.203) (xy -1.647 3.201) (xy -1.656 3.2) (xy -1.686 3.191) (xy -1.717 3.176)
				(xy -1.746 3.159) (xy -1.765 3.143) (xy -1.79 3.111) (xy -1.807 3.075) (xy -1.816 3.037) (xy -1.817 2.998)
				(xy -1.817 2.997) (xy -1.697 2.997) (xy -1.696 3.02) (xy -1.687 3.042) (xy -1.67 3.06) (xy -1.668 3.062)
				(xy -1.654 3.07) (xy -1.64 3.076) (xy -1.624 3.08) (xy -1.602 3.081) (xy -1.574 3.082) (xy -1.558 3.082)
				(xy -1.529 3.081) (xy -1.508 3.08) (xy -1.494 3.078) (xy -1.483 3.075) (xy -1.474 3.07) (xy -1.458 3.058)
				(xy -1.447 3.041) (xy -1.44 3.017) (xy -1.435 2.985) (xy -1.435 2.977) (xy -1.432 2.931) (xy -1.533 2.931)
				(xy -1.568 2.931) (xy -1.595 2.931) (xy -1.615 2.932) (xy -1.63 2.934) (xy -1.641 2.936) (xy -1.65 2.938)
				(xy -1.655 2.941) (xy -1.676 2.955) (xy -1.69 2.974) (xy -1.697 2.997) (xy -1.817 2.997) (xy -1.811 2.96)
				(xy -1.797 2.924) (xy -1.775 2.892) (xy -1.747 2.864) (xy -1.715 2.845) (xy -1.7 2.838) (xy -1.685 2.833)
				(xy -1.668 2.83) (xy -1.648 2.827) (xy -1.623 2.825) (xy -1.591 2.824) (xy -1.551 2.824) (xy -1.54 2.824)
				(xy -1.432 2.824) (xy -1.434 2.776) (xy -1.436 2.747) (xy -1.441 2.726) (xy -1.448 2.711) (xy -1.46 2.699)
				(xy -1.474 2.689) (xy -1.483 2.685) (xy -1.492 2.682) (xy -1.505 2.68) (xy -1.524 2.68) (xy -1.55 2.679)
				(xy -1.56 2.679) (xy -1.594 2.68) (xy -1.62 2.682) (xy -1.639 2.686) (xy -1.654 2.692) (xy -1.666 2.701)
				(xy -1.675 2.711) (xy -1.686 2.724) (xy -1.735 2.686) (xy -1.754 2.672) (xy -1.769 2.659) (xy -1.78 2.65)
				(xy -1.784 2.646) (xy -1.78 2.64) (xy -1.77 2.629) (xy -1.756 2.616) (xy -1.74 2.604) (xy -1.724 2.592)
				(xy -1.711 2.584) (xy -1.71 2.583) (xy -1.688 2.574) (xy -1.668 2.566) (xy -1.647 2.562) (xy -1.623 2.559)
				(xy -1.593 2.558) (xy -1.565 2.558) (xy -1.521 2.559)
			)
			(stroke
				(width 0.01)
				(type solid)
			)
			(fill solid)
			(layer "F.Cu")
		)
		(fp_poly
			(pts
				(xy 0.035 2.777) (xy 0.047 2.822) (xy 0.059 2.864) (xy 0.069 2.903) (xy 0.078 2.936) (xy 0.086 2.963)
				(xy 0.092 2.984) (xy 0.095 2.996) (xy 0.096 2.999) (xy 0.098 2.999) (xy 0.103 2.991) (xy 0.109 2.975)
				(xy 0.118 2.95) (xy 0.129 2.917) (xy 0.143 2.874) (xy 0.152 2.849) (xy 0.165 2.807) (xy 0.179 2.766)
				(xy 0.192 2.726) (xy 0.204 2.689) (xy 0.214 2.658) (xy 0.221 2.634) (xy 0.224 2.627) (xy 0.244 2.565)
				(xy 0.338 2.565) (xy 0.406 2.774) (xy 0.42 2.819) (xy 0.434 2.861) (xy 0.446 2.899) (xy 0.457 2.932)
				(xy 0.466 2.96) (xy 0.473 2.981) (xy 0.477 2.993) (xy 0.478 2.997) (xy 0.48 2.998) (xy 0.482 2.996)
				(xy 0.485 2.99) (xy 0.49 2.978) (xy 0.495 2.96) (xy 0.502 2.936) (xy 0.511 2.905) (xy 0.523 2.865)
				(xy 0.536 2.817) (xy 0.543 2.789) (xy 0.556 2.744) (xy 0.568 2.701) (xy 0.578 2.663) (xy 0.587 2.629)
				(xy 0.595 2.602) (xy 0.601 2.582) (xy 0.605 2.57) (xy 0.606 2.567) (xy 0.611 2.566) (xy 0.625 2.566)
				(xy 0.645 2.566) (xy 0.669 2.566) (xy 0.673 2.566) (xy 0.739 2.567) (xy 0.656 2.827) (xy 0.64 2.878)
				(xy 0.624 2.928) (xy 0.609 2.976) (xy 0.595 3.02) (xy 0.582 3.06) (xy 0.571 3.094) (xy 0.563 3.121)
				(xy 0.557 3.139) (xy 0.556 3.143) (xy 0.538 3.2) (xy 0.425 3.197) (xy 0.358 2.975) (xy 0.341 2.917)
				(xy 0.327 2.87) (xy 0.315 2.831) (xy 0.305 2.801) (xy 0.297 2.78) (xy 0.292 2.766) (xy 0.289 2.761)
				(xy 0.288 2.761) (xy 0.286 2.768) (xy 0.281 2.783) (xy 0.274 2.806) (xy 0.265 2.836) (xy 0.254 2.871)
				(xy 0.242 2.911) (xy 0.23 2.953) (xy 0.223 2.976) (xy 0.21 3.02) (xy 0.197 3.062) (xy 0.186 3.099)
				(xy 0.177 3.132) (xy 0.169 3.158) (xy 0.163 3.177) (xy 0.16 3.189) (xy 0.159 3.191) (xy 0.157 3.195)
				(xy 0.151 3.198) (xy 0.141 3.199) (xy 0.124 3.2) (xy 0.101 3.2) (xy 0.073 3.199) (xy 0.055 3.198)
				(xy 0.045 3.196) (xy 0.043 3.194) (xy 0.041 3.188) (xy 0.036 3.173) (xy 0.029 3.15) (xy 0.019 3.121)
				(xy 0.008 3.084) (xy -0.006 3.043) (xy -0.02 2.996) (xy -0.036 2.946) (xy -0.053 2.893) (xy -0.057 2.883)
				(xy -0.074 2.83) (xy -0.09 2.779) (xy -0.105 2.732) (xy -0.119 2.689) (xy -0.131 2.652) (xy -0.141 2.621)
				(xy -0.148 2.596) (xy -0.154 2.58) (xy -0.156 2.572) (xy -0.156 2.569) (xy -0.151 2.567) (xy -0.14 2.566)
				(xy -0.123 2.565) (xy -0.096 2.565) (xy -0.091 2.565) (xy -0.023 2.565) (xy 0.035 2.777)
			)
			(stroke
				(width 0.01)
				(type solid)
			)
			(fill solid)
			(layer "F.Cu")
		)
		(fp_poly
			(pts
				(xy -2.065 1.559) (xy -2.024 1.576) (xy -1.986 1.601) (xy -1.973 1.612) (xy -1.957 1.63) (xy -1.943 1.649)
				(xy -1.932 1.668) (xy -1.924 1.69) (xy -1.918 1.716) (xy -1.914 1.747) (xy -1.911 1.785) (xy -1.91 1.831)
				(xy -1.91 1.877) (xy -1.91 1.93) (xy -1.912 1.974) (xy -1.914 2.011) (xy -1.919 2.041) (xy -1.925 2.067)
				(xy -1.934 2.088) (xy -1.945 2.107) (xy -1.959 2.125) (xy -1.972 2.139) (xy -1.993 2.157) (xy -2.018 2.173)
				(xy -2.031 2.18) (xy -2.047 2.188) (xy -2.06 2.192) (xy -2.074 2.195) (xy -2.091 2.196) (xy -2.114 2.197)
				(xy -2.122 2.197) (xy -2.147 2.196) (xy -2.165 2.195) (xy -2.179 2.193) (xy -2.191 2.189) (xy -2.205 2.183)
				(xy -2.21 2.18) (xy -2.231 2.169) (xy -2.251 2.156) (xy -2.265 2.146) (xy -2.286 2.127) (xy -2.286 2.627)
				(xy -2.266 2.608) (xy -2.248 2.595) (xy -2.227 2.582) (xy -2.217 2.577) (xy -2.173 2.562) (xy -2.129 2.556)
				(xy -2.086 2.559) (xy -2.045 2.57) (xy -2.007 2.589) (xy -1.974 2.616) (xy -1.946 2.648) (xy -1.926 2.687)
				(xy -1.919 2.707) (xy -1.917 2.715) (xy -1.915 2.724) (xy -1.914 2.737) (xy -1.913 2.753) (xy -1.912 2.774)
				(xy -1.911 2.8) (xy -1.911 2.833) (xy -1.911 2.874) (xy -1.911 2.923) (xy -1.911 2.967) (xy -1.911 3.2)
				(xy -2.035 3.197) (xy -2.038 2.984) (xy -2.038 2.932) (xy -2.039 2.889) (xy -2.039 2.854) (xy -2.04 2.826)
				(xy -2.041 2.805) (xy -2.042 2.788) (xy -2.043 2.776) (xy -2.045 2.767) (xy -2.046 2.76) (xy -2.049 2.755)
				(xy -2.051 2.75) (xy -2.072 2.721) (xy -2.098 2.701) (xy -2.128 2.688) (xy -2.161 2.683) (xy -2.195 2.687)
				(xy -2.22 2.697) (xy -2.24 2.71) (xy -2.259 2.729) (xy -2.274 2.75) (xy -2.278 2.757) (xy -2.28 2.765)
				(xy -2.281 2.781) (xy -2.283 2.806) (xy -2.284 2.839) (xy -2.285 2.881) (xy -2.286 2.933) (xy -2.286 2.984)
				(xy -2.289 3.197) (xy -2.413 3.2) (xy -2.413 1.877) (xy -2.286 1.877) (xy -2.285 1.926) (xy -2.281 1.966)
				(xy -2.274 1.998) (xy -2.262 2.024) (xy -2.247 2.043) (xy -2.228 2.058) (xy -2.215 2.064) (xy -2.194 2.07)
				(xy -2.168 2.072) (xy -2.141 2.071) (xy -2.117 2.066) (xy -2.106 2.063) (xy -2.079 2.044) (xy -2.058 2.019)
				(xy -2.05 2.001) (xy -2.045 1.984) (xy -2.042 1.959) (xy -2.04 1.929) (xy -2.038 1.895) (xy -2.038 1.861)
				(xy -2.039 1.829) (xy -2.041 1.8) (xy -2.044 1.777) (xy -2.045 1.772) (xy -2.057 1.738) (xy -2.073 1.712)
				(xy -2.094 1.695) (xy -2.122 1.684) (xy -2.156 1.681) (xy -2.159 1.681) (xy -2.192 1.683) (xy -2.22 1.691)
				(xy -2.243 1.705) (xy -2.26 1.725) (xy -2.273 1.753) (xy -2.281 1.788) (xy -2.285 1.832) (xy -2.286 1.877)
				(xy -2.413 1.877) (xy -2.413 1.559) (xy -2.286 1.559) (xy -2.286 1.62) (xy -2.26 1.6) (xy -2.225 1.577)
				(xy -2.19 1.563) (xy -2.154 1.554) (xy -2.109 1.552) (xy -2.065 1.559)
			)
			(stroke
				(width 0.01)
				(type solid)
			)
			(fill solid)
			(layer "F.Cu")
		)
		(fp_poly
			(pts
				(xy 0.063 -3.201) (xy 0.118 -3.201) (xy 0.164 -3.201) (xy 0.202 -3.2) (xy 0.233 -3.2) (xy 0.258 -3.2)
				(xy 0.277 -3.199) (xy 0.292 -3.198) (xy 0.302 -3.197) (xy 0.309 -3.196) (xy 0.314 -3.195) (xy 0.317 -3.193)
				(xy 0.319 -3.192) (xy 0.321 -3.189) (xy 0.324 -3.183) (xy 0.327 -3.174) (xy 0.33 -3.161) (xy 0.334 -3.144)
				(xy 0.339 -3.12) (xy 0.345 -3.091) (xy 0.352 -3.054) (xy 0.361 -3.01) (xy 0.371 -2.958) (xy 0.382 -2.897)
				(xy 0.385 -2.878) (xy 0.395 -2.824) (xy 0.405 -2.772) (xy 0.414 -2.724) (xy 0.423 -2.68) (xy 0.43 -2.642)
				(xy 0.437 -2.61) (xy 0.442 -2.586) (xy 0.446 -2.569) (xy 0.448 -2.562) (xy 0.456 -2.55) (xy 0.464 -2.544)
				(xy 0.476 -2.539) (xy 0.495 -2.53) (xy 0.521 -2.519) (xy 0.552 -2.506) (xy 0.587 -2.492) (xy 0.624 -2.477)
				(xy 0.664 -2.461) (xy 0.704 -2.445) (xy 0.743 -2.43) (xy 0.78 -2.415) (xy 0.814 -2.402) (xy 0.843 -2.391)
				(xy 0.868 -2.382) (xy 0.885 -2.376) (xy 0.895 -2.373) (xy 0.896 -2.373) (xy 0.911 -2.376) (xy 0.931 -2.386)
				(xy 0.948 -2.397) (xy 0.962 -2.406) (xy 0.983 -2.421) (xy 1.011 -2.44) (xy 1.043 -2.462) (xy 1.079 -2.487)
				(xy 1.118 -2.513) (xy 1.158 -2.541) (xy 1.198 -2.568) (xy 1.238 -2.595) (xy 1.275 -2.621) (xy 1.309 -2.644)
				(xy 1.338 -2.665) (xy 1.362 -2.681) (xy 1.377 -2.691) (xy 1.398 -2.705) (xy 1.418 -2.717) (xy 1.433 -2.725)
				(xy 1.442 -2.728) (xy 1.443 -2.728) (xy 1.448 -2.726) (xy 1.456 -2.72) (xy 1.468 -2.71) (xy 1.486 -2.694)
				(xy 1.508 -2.673) (xy 1.535 -2.647) (xy 1.568 -2.614) (xy 1.608 -2.575) (xy 1.654 -2.53) (xy 1.675 -2.509)
				(xy 1.721 -2.462) (xy 1.761 -2.422) (xy 1.794 -2.388) (xy 1.822 -2.36) (xy 1.844 -2.337) (xy 1.862 -2.318)
				(xy 1.875 -2.304) (xy 1.884 -2.293) (xy 1.89 -2.284) (xy 1.893 -2.279) (xy 1.894 -2.275) (xy 1.892 -2.269)
				(xy 1.886 -2.257) (xy 1.875 -2.239) (xy 1.86 -2.215) (xy 1.839 -2.183) (xy 1.814 -2.145) (xy 1.783 -2.1)
				(xy 1.747 -2.046) (xy 1.721 -2.009) (xy 1.69 -1.964) (xy 1.661 -1.921) (xy 1.634 -1.88) (xy 1.609 -1.844)
				(xy 1.588 -1.811) (xy 1.57 -1.785) (xy 1.557 -1.764) (xy 1.549 -1.75) (xy 1.546 -1.743) (xy 1.547 -1.735)
				(xy 1.552 -1.719) (xy 1.56 -1.696) (xy 1.571 -1.667) (xy 1.585 -1.634) (xy 1.6 -1.597) (xy 1.616 -1.557)
				(xy 1.633 -1.516) (xy 1.651 -1.476) (xy 1.668 -1.436) (xy 1.685 -1.398) (xy 1.701 -1.363) (xy 1.715 -1.333)
				(xy 1.727 -1.309) (xy 1.736 -1.291) (xy 1.742 -1.281) (xy 1.744 -1.279) (xy 1.751 -1.277) (xy 1.767 -1.273)
				(xy 1.791 -1.268) (xy 1.822 -1.261) (xy 1.86 -1.254) (xy 1.903 -1.245) (xy 1.951 -1.236) (xy 2.002 -1.226)
				(xy 2.049 -1.217) (xy 2.103 -1.207) (xy 2.154 -1.198) (xy 2.201 -1.188) (xy 2.244 -1.18) (xy 2.281 -1.173)
				(xy 2.311 -1.166) (xy 2.335 -1.161) (xy 2.35 -1.157) (xy 2.355 -1.156) (xy 2.367 -1.148) (xy 2.367 -0.834)
				(xy 2.367 -0.768) (xy 2.367 -0.712) (xy 2.367 -0.664) (xy 2.366 -0.625) (xy 2.366 -0.592) (xy 2.365 -0.566)
				(xy 2.364 -0.546) (xy 2.363 -0.531) (xy 2.361 -0.52) (xy 2.358 -0.512) (xy 2.355 -0.507) (xy 2.352 -0.504)
				(xy 2.348 -0.503) (xy 2.343 -0.501) (xy 2.34 -0.501) (xy 2.333 -0.499) (xy 2.317 -0.496) (xy 2.293 -0.492)
				(xy 2.261 -0.486) (xy 2.224 -0.479) (xy 2.181 -0.471) (xy 2.134 -0.462) (xy 2.084 -0.453) (xy 2.054 -0.448)
				(xy 2.002 -0.438) (xy 1.953 -0.429) (xy 1.907 -0.42) (xy 1.866 -0.412) (xy 1.831 -0.404) (xy 1.802 -0.398)
				(xy 1.78 -0.394) (xy 1.767 -0.391) (xy 1.764 -0.39) (xy 1.76 -0.387) (xy 1.757 -0.384) (xy 1.753 -0.379)
				(xy 1.748 -0.371) (xy 1.742 -0.36) (xy 1.735 -0.344) (xy 1.726 -0.324) (xy 1.715 -0.297) (xy 1.701 -0.264)
				(xy 1.685 -0.223) (xy 1.665 -0.174) (xy 1.653 -0.145) (xy 1.63 -0.086) (xy 1.61 -0.037) (xy 1.594 0.005)
				(xy 1.582 0.038) (xy 1.572 0.064) (xy 1.566 0.084) (xy 1.562 0.097) (xy 1.561 0.104) (xy 1.562 0.105)
				(xy 1.565 0.111) (xy 1.574 0.125) (xy 1.587 0.146) (xy 1.604 0.173) (xy 1.626 0.205) (xy 1.65 0.241)
				(xy 1.677 0.281) (xy 1.706 0.324) (xy 1.729 0.358) (xy 1.768 0.413) (xy 1.8 0.461) (xy 1.827 0.502)
				(xy 1.85 0.535) (xy 1.867 0.562) (xy 1.88 0.583) (xy 1.889 0.598) (xy 1.893 0.608) (xy 1.894 0.612)
				(xy 1.893 0.616) (xy 1.89 0.622) (xy 1.885 0.63) (xy 1.876 0.64) (xy 1.863 0.655) (xy 1.846 0.673)
				(xy 1.825 0.695) (xy 1.798 0.723) (xy 1.765 0.756) (xy 1.727 0.795) (xy 1.682 0.839) (xy 1.635 0.886)
				(xy 1.595 0.926) (xy 1.561 0.96) (xy 1.532 0.989) (xy 1.508 1.012) (xy 1.488 1.03) (xy 1.473 1.044)
				(xy 1.461 1.054) (xy 1.452 1.061) (xy 1.445 1.065) (xy 1.44 1.066) (xy 1.438 1.066) (xy 1.433 1.064)
				(xy 1.421 1.055) (xy 1.401 1.043) (xy 1.376 1.026) (xy 1.345 1.005) (xy 1.31 0.981) (xy 1.27 0.954)
				(xy 1.228 0.925) (xy 1.193 0.901) (xy 1.138 0.864) (xy 1.089 0.83) (xy 1.046 0.802) (xy 1.01 0.778)
				(xy 0.981 0.759) (xy 0.96 0.746) (xy 0.946 0.738) (xy 0.94 0.736) (xy 0.932 0.738) (xy 0.917 0.745)
				(xy 0.895 0.755) (xy 0.869 0.768) (xy 0.84 0.783) (xy 0.816 0.795) (xy 0.781 0.814) (xy 0.753 0.828)
				(xy 0.732 0.838) (xy 0.717 0.845) (xy 0.707 0.849) (xy 0.699 0.85) (xy 0.694 0.849) (xy 0.691 0.847)
				(xy 0.687 0.84) (xy 0.682 0.829) (xy 0.674 0.814) (xy 0.665 0.793) (xy 0.653 0.767) (xy 0.639 0.735)
				(xy 0.623 0.696) (xy 0.604 0.651) (xy 0.582 0.598) (xy 0.556 0.538) (xy 0.528 0.469) (xy 0.496 0.391)
				(xy 0.47 0.329) (xy 0.436 0.247) (xy 0.406 0.173) (xy 0.379 0.108) (xy 0.355 0.05) (xy 0.335 0)
				(xy 0.317 -0.043) (xy 0.303 -0.079) (xy 0.291 -0.11) (xy 0.281 -0.135) (xy 0.273 -0.155) (xy 0.268 -0.171)
				(xy 0.264 -0.183) (xy 0.262 -0.191) (xy 0.262 -0.196) (xy 0.262 -0.198) (xy 0.269 -0.207) (xy 0.283 -0.219)
				(xy 0.302 -0.233) (xy 0.303 -0.234) (xy 0.354 -0.268) (xy 0.398 -0.3) (xy 0.435 -0.331) (xy 0.469 -0.363)
				(xy 0.5 -0.397) (xy 0.507 -0.405) (xy 0.556 -0.472) (xy 0.596 -0.543) (xy 0.627 -0.619) (xy 0.643 -0.672)
				(xy 0.651 -0.718) (xy 0.657 -0.77) (xy 0.66 -0.824) (xy 0.659 -0.878) (xy 0.654 -0.927) (xy 0.652 -0.936)
				(xy 0.634 -1.015) (xy 0.607 -1.09) (xy 0.571 -1.161) (xy 0.528 -1.227) (xy 0.477 -1.287) (xy 0.419 -1.341)
				(xy 0.355 -1.387) (xy 0.285 -1.426) (xy 0.21 -1.456) (xy 0.205 -1.458) (xy 0.131 -1.477) (xy 0.054 -1.487)
				(xy -0.025 -1.489) (xy -0.103 -1.482) (xy -0.178 -1.466) (xy -0.206 -1.458) (xy -0.281 -1.428) (xy -0.351 -1.39)
				(xy -0.416 -1.344) (xy -0.474 -1.29) (xy -0.526 -1.23) (xy -0.571 -1.164) (xy -0.607 -1.093) (xy -0.63 -1.034)
				(xy -0.649 -0.96) (xy -0.659 -0.883) (xy -0.661 -0.804) (xy -0.654 -0.726) (xy -0.638 -0.651) (xy -0.63 -0.623)
				(xy -0.618 -0.591) (xy -0.602 -0.554) (xy -0.584 -0.518) (xy -0.566 -0.485) (xy -0.553 -0.463) (xy -0.509 -0.407)
				(xy -0.457 -0.352) (xy -0.397 -0.299) (xy -0.33 -0.25) (xy -0.289 -0.224) (xy -0.273 -0.212) (xy -0.263 -0.2)
				(xy -0.262 -0.197) (xy -0.263 -0.19) (xy -0.268 -0.175) (xy -0.277 -0.151) (xy -0.288 -0.121) (xy -0.302 -0.084)
				(xy -0.319 -0.042) (xy -0.338 0.005) (xy -0.358 0.056) (xy -0.381 0.111) (xy -0.404 0.168) (xy -0.428 0.228)
				(xy -0.453 0.288) (xy -0.478 0.349) (xy -0.504 0.41) (xy -0.529 0.47) (xy -0.553 0.527) (xy -0.576 0.583)
				(xy -0.598 0.635) (xy -0.619 0.683) (xy -0.638 0.727) (xy -0.655 0.765) (xy -0.669 0.797) (xy -0.68 0.822)
				(xy -0.689 0.839) (xy -0.694 0.848) (xy -0.695 0.849) (xy -0.699 0.85) (xy -0.706 0.849) (xy -0.717 0.845)
				(xy -0.732 0.839) (xy -0.752 0.829) (xy -0.779 0.815) (xy -0.814 0.797) (xy -0.817 0.795) (xy -0.848 0.779)
				(xy -0.877 0.764) (xy -0.902 0.752) (xy -0.922 0.743) (xy -0.936 0.737) (xy -0.941 0.736) (xy -0.949 0.739)
				(xy -0.964 0.748) (xy -0.987 0.761) (xy -1.015 0.78) (xy -1.05 0.803) (xy -1.072 0.818) (xy -1.138 0.863)
				(xy -1.195 0.903) (xy -1.245 0.937) (xy -1.289 0.966) (xy -1.325 0.991) (xy -1.356 1.012) (xy -1.381 1.029)
				(xy -1.401 1.042) (xy -1.416 1.052) (xy -1.427 1.059) (xy -1.435 1.064) (xy -1.439 1.066) (xy -1.44 1.066)
				(xy -1.449 1.064) (xy -1.453 1.061) (xy -1.458 1.057) (xy -1.47 1.046) (xy -1.487 1.029) (xy -1.509 1.007)
				(xy -1.537 0.98) (xy -1.568 0.95) (xy -1.602 0.915) (xy -1.639 0.879) (xy -1.678 0.84) (xy -1.678 0.839)
				(xy -1.726 0.792) (xy -1.767 0.751) (xy -1.801 0.716) (xy -1.829 0.687) (xy -1.852 0.663) (xy -1.869 0.644)
				(xy -1.882 0.63) (xy -1.89 0.62) (xy -1.894 0.613) (xy -1.895 0.61) (xy -1.892 0.603) (xy -1.884 0.588)
				(xy -1.87 0.565) (xy -1.85 0.536) (xy -1.826 0.499) (xy -1.797 0.455) (xy -1.763 0.405) (xy -1.73 0.358)
				(xy -1.7 0.313) (xy -1.671 0.271) (xy -1.645 0.232) (xy -1.621 0.197) (xy -1.601 0.166) (xy -1.584 0.141)
				(xy -1.572 0.121) (xy -1.565 0.109) (xy -1.563 0.105) (xy -1.563 0.099) (xy -1.566 0.087) (xy -1.572 0.07)
				(xy -1.58 0.045) (xy -1.592 0.013) (xy -1.607 -0.026) (xy -1.626 -0.074) (xy -1.648 -0.13) (xy -1.654 -0.145)
				(xy -1.676 -0.199) (xy -1.695 -0.245) (xy -1.71 -0.282) (xy -1.723 -0.313) (xy -1.733 -0.337) (xy -1.741 -0.356)
				(xy -1.748 -0.369) (xy -1.753 -0.379) (xy -1.758 -0.385) (xy -1.761 -0.388) (xy -1.763 -0.389) (xy -1.767 -0.39)
				(xy -1.774 -0.392) (xy -1.784 -0.395) (xy -1.799 -0.398) (xy -1.818 -0.402) (xy -1.843 -0.407) (xy -1.873 -0.413)
				(xy -1.91 -0.42) (xy -1.954 -0.429) (xy -2.005 -0.438) (xy -2.065 -0.449) (xy -2.133 -0.462) (xy -2.211 -0.477)
				(xy -2.22 -0.478) (xy -2.26 -0.486) (xy -2.29 -0.491) (xy -2.313 -0.496) (xy -2.33 -0.499) (xy -2.341 -0.502)
				(xy -2.349 -0.504) (xy -2.353 -0.506) (xy -2.356 -0.508) (xy -2.359 -0.51) (xy -2.36 -0.511) (xy -2.361 -0.514)
				(xy -2.363 -0.518) (xy -2.364 -0.526) (xy -2.365 -0.536) (xy -2.366 -0.551) (xy -2.366 -0.571) (xy -2.367 -0.597)
				(xy -2.367 -0.629) (xy -2.368 -0.668) (xy -2.368 -0.715) (xy -2.368 -0.771) (xy -2.368 -0.834) (xy -2.368 -1.148)
				(xy -2.356 -1.155) (xy -2.349 -1.158) (xy -2.333 -1.162) (xy -2.309 -1.167) (xy -2.278 -1.173) (xy -2.24 -1.181)
				(xy -2.197 -1.189) (xy -2.149 -1.198) (xy -2.098 -1.208) (xy -2.051 -1.217) (xy -1.996 -1.227) (xy -1.945 -1.237)
				(xy -1.897 -1.246) (xy -1.854 -1.254) (xy -1.817 -1.262) (xy -1.787 -1.268) (xy -1.764 -1.273) (xy -1.75 -1.277)
				(xy -1.745 -1.279) (xy -1.741 -1.285) (xy -1.733 -1.3) (xy -1.722 -1.322) (xy -1.709 -1.35) (xy -1.694 -1.382)
				(xy -1.677 -1.419) (xy -1.66 -1.458) (xy -1.642 -1.498) (xy -1.625 -1.539) (xy -1.608 -1.58) (xy -1.592 -1.618)
				(xy -1.578 -1.653) (xy -1.565 -1.684) (xy -1.556 -1.709) (xy -1.549 -1.729) (xy -1.546 -1.74) (xy -1.546 -1.742)
				(xy -1.549 -1.749) (xy -1.558 -1.763) (xy -1.571 -1.784) (xy -1.588 -1.811) (xy -1.61 -1.843) (xy -1.634 -1.88)
				(xy -1.661 -1.92) (xy -1.691 -1.963) (xy -1.722 -2.008) (xy -1.762 -2.067) (xy -1.796 -2.117) (xy -1.825 -2.16)
				(xy -1.848 -2.196) (xy -1.867 -2.225) (xy -1.881 -2.247) (xy -1.89 -2.262) (xy -1.895 -2.272) (xy -1.895 -2.275)
				(xy -1.894 -2.279) (xy -1.891 -2.285) (xy -1.884 -2.293) (xy -1.875 -2.305) (xy -1.861 -2.32) (xy -1.843 -2.339)
				(xy -1.82 -2.363) (xy -1.792 -2.392) (xy -1.758 -2.426) (xy -1.718 -2.466) (xy -1.676 -2.509) (xy -1.627 -2.557)
				(xy -1.585 -2.599) (xy -1.549 -2.634) (xy -1.52 -2.663) (xy -1.495 -2.686) (xy -1.476 -2.704) (xy -1.462 -2.716)
				(xy -1.452 -2.724) (xy -1.446 -2.728) (xy -1.444 -2.728) (xy -1.437 -2.726) (xy -1.423 -2.717) (xy -1.401 -2.703)
				(xy -1.372 -2.685) (xy -1.337 -2.661) (xy -1.295 -2.634) (xy -1.248 -2.602) (xy -1.196 -2.566) (xy -1.173 -2.551)
				(xy -1.118 -2.513) (xy -1.071 -2.481) (xy -1.031 -2.454) (xy -0.998 -2.432) (xy -0.97 -2.413) (xy -0.948 -2.399)
				(xy -0.931 -2.389) (xy -0.917 -2.381) (xy -0.907 -2.376) (xy -0.901 -2.373) (xy -0.897 -2.373) (xy -0.888 -2.375)
				(xy -0.87 -2.38) (xy -0.845 -2.39) (xy -0.813 -2.402) (xy -0.774 -2.417) (xy -0.73 -2.434) (xy -0.681 -2.454)
				(xy -0.629 -2.475) (xy -0.586 -2.493) (xy -0.55 -2.508) (xy -0.522 -2.52) (xy -0.499 -2.529) (xy -0.482 -2.537)
				(xy -0.47 -2.543) (xy -0.461 -2.548) (xy -0.455 -2.551) (xy -0.452 -2.554) (xy -0.449 -2.557) (xy -0.448 -2.56)
				(xy -0.447 -2.566) (xy -0.443 -2.582) (xy -0.438 -2.605) (xy -0.432 -2.637) (xy -0.425 -2.674) (xy -0.417 -2.717)
				(xy -0.407 -2.765) (xy -0.398 -2.817) (xy -0.388 -2.871) (xy -0.387 -2.876) (xy -0.375 -2.94) (xy -0.364 -2.995)
				(xy -0.356 -3.042) (xy -0.348 -3.081) (xy -0.342 -3.112) (xy -0.337 -3.137) (xy -0.332 -3.157) (xy -0.328 -3.171)
				(xy -0.325 -3.181) (xy -0.323 -3.188) (xy -0.32 -3.191) (xy -0.32 -3.192) (xy -0.317 -3.194) (xy -0.313 -3.195)
				(xy -0.307 -3.197) (xy -0.298 -3.198) (xy -0.286 -3.199) (xy -0.269 -3.199) (xy -0.247 -3.2) (xy -0.219 -3.2)
				(xy -0.184 -3.201) (xy -0.142 -3.201) (xy -0.092 -3.201) (xy -0.033 -3.201) (xy -0.001 -3.201) (xy 0.063 -3.201)
			)
			(stroke
				(width 0.01)
				(type solid)
			)
			(fill solid)
			(layer "F.Cu")
		)
		(fp_poly
			(pts
				(xy -0.843 2.558) (xy -0.815 2.564) (xy -0.794 2.572) (xy -0.773 2.581) (xy -0.759 2.589) (xy -0.738 2.603)
				(xy -0.783 2.658) (xy -0.8 2.677) (xy -0.814 2.694) (xy -0.825 2.706) (xy -0.831 2.712) (xy -0.832 2.712)
				(xy -0.837 2.71) (xy -0.847 2.703) (xy -0.849 2.702) (xy -0.874 2.69) (xy -0.904 2.684) (xy -0.935 2.685)
				(xy -0.942 2.686) (xy -0.975 2.698) (xy -1.001 2.717) (xy -1.02 2.741) (xy -1.034 2.766) (xy -1.039 3.197)
				(xy -1.164 3.2) (xy -1.164 2.565) (xy -1.037 2.565) (xy -1.037 2.626) (xy -1.009 2.604) (xy -0.972 2.579)
				(xy -0.931 2.563) (xy -0.887 2.556) (xy -0.843 2.558)
			)
			(stroke
				(width 0.01)
				(type solid)
			)
			(fill solid)
			(layer "F.Mask")
		)
		(fp_poly
			(pts
				(xy 1.889 1.554) (xy 1.907 1.559) (xy 1.927 1.566) (xy 1.948 1.574) (xy 1.966 1.583) (xy 1.979 1.592)
				(xy 1.984 1.597) (xy 1.982 1.604) (xy 1.974 1.616) (xy 1.962 1.633) (xy 1.946 1.652) (xy 1.945 1.654)
				(xy 1.929 1.673) (xy 1.915 1.689) (xy 1.906 1.7) (xy 1.901 1.706) (xy 1.896 1.705) (xy 1.885 1.7)
				(xy 1.873 1.695) (xy 1.84 1.683) (xy 1.808 1.68) (xy 1.776 1.685) (xy 1.747 1.698) (xy 1.723 1.717)
				(xy 1.704 1.742) (xy 1.696 1.763) (xy 1.695 1.772) (xy 1.694 1.79) (xy 1.693 1.817) (xy 1.692 1.85)
				(xy 1.692 1.89) (xy 1.691 1.934) (xy 1.691 1.983) (xy 1.691 2.194) (xy 1.559 2.194) (xy 1.559 1.559)
				(xy 1.691 1.559) (xy 1.691 1.626) (xy 1.71 1.607) (xy 1.739 1.585) (xy 1.775 1.568) (xy 1.814 1.556)
				(xy 1.855 1.552) (xy 1.889 1.554)
			)
			(stroke
				(width 0.01)
				(type solid)
			)
			(fill solid)
			(layer "F.Mask")
		)
		(fp_poly
			(pts
				(xy -0.837 1.56) (xy -0.797 1.576) (xy -0.761 1.6) (xy -0.73 1.63) (xy -0.706 1.667) (xy -0.69 1.709)
				(xy -0.687 1.721) (xy -0.685 1.734) (xy -0.684 1.757) (xy -0.683 1.79) (xy -0.682 1.833) (xy -0.681 1.884)
				(xy -0.681 1.945) (xy -0.681 1.971) (xy -0.681 2.194) (xy -0.808 2.194) (xy -0.809 1.984) (xy -0.811 1.774)
				(xy -0.826 1.744) (xy -0.845 1.716) (xy -0.868 1.697) (xy -0.897 1.686) (xy -0.925 1.682) (xy -0.947 1.682)
				(xy -0.967 1.684) (xy -0.979 1.686) (xy -1.001 1.698) (xy -1.023 1.716) (xy -1.041 1.738) (xy -1.049 1.752)
				(xy -1.052 1.758) (xy -1.054 1.765) (xy -1.056 1.773) (xy -1.057 1.783) (xy -1.058 1.797) (xy -1.059 1.815)
				(xy -1.06 1.839) (xy -1.06 1.869) (xy -1.061 1.907) (xy -1.061 1.953) (xy -1.061 1.985) (xy -1.063 2.194)
				(xy -1.189 2.194) (xy -1.189 1.559) (xy -1.062 1.559) (xy -1.062 1.625) (xy -1.033 1.602) (xy -1.001 1.579)
				(xy -0.969 1.564) (xy -0.934 1.555) (xy -0.927 1.554) (xy -0.881 1.553) (xy -0.837 1.56)
			)
			(stroke
				(width 0.01)
				(type solid)
			)
			(fill solid)
			(layer "F.Mask")
		)
		(fp_poly
			(pts
				(xy 1.042 1.769) (xy 1.043 1.979) (xy 1.059 2.009) (xy 1.077 2.036) (xy 1.1 2.056) (xy 1.129 2.067)
				(xy 1.159 2.071) (xy 1.193 2.07) (xy 1.221 2.063) (xy 1.245 2.047) (xy 1.258 2.034) (xy 1.266 2.025)
				(xy 1.273 2.016) (xy 1.278 2.008) (xy 1.282 1.997) (xy 1.286 1.985) (xy 1.288 1.969) (xy 1.29 1.948)
				(xy 1.291 1.922) (xy 1.292 1.89) (xy 1.293 1.85) (xy 1.293 1.801) (xy 1.294 1.766) (xy 1.295 1.559)
				(xy 1.422 1.559) (xy 1.422 2.194) (xy 1.295 2.194) (xy 1.295 2.161) (xy 1.295 2.144) (xy 1.293 2.132)
				(xy 1.292 2.128) (xy 1.287 2.131) (xy 1.278 2.14) (xy 1.271 2.147) (xy 1.256 2.159) (xy 1.236 2.171)
				(xy 1.219 2.181) (xy 1.202 2.188) (xy 1.186 2.193) (xy 1.17 2.196) (xy 1.148 2.197) (xy 1.135 2.198)
				(xy 1.107 2.198) (xy 1.087 2.197) (xy 1.07 2.194) (xy 1.059 2.19) (xy 1.036 2.181) (xy 1.019 2.172)
				(xy 1.003 2.161) (xy 0.985 2.146) (xy 0.981 2.141) (xy 0.952 2.107) (xy 0.931 2.068) (xy 0.92 2.033)
				(xy 0.918 2.019) (xy 0.917 1.996) (xy 0.916 1.963) (xy 0.915 1.92) (xy 0.914 1.869) (xy 0.914 1.808)
				(xy 0.914 1.782) (xy 0.914 1.559) (xy 1.04 1.559) (xy 1.042 1.769)
			)
			(stroke
				(width 0.01)
				(type solid)
			)
			(fill solid)
			(layer "F.Mask")
		)
		(fp_poly
			(pts
				(xy 1.753 2.563) (xy 1.768 2.568) (xy 1.787 2.577) (xy 1.804 2.586) (xy 1.818 2.595) (xy 1.826 2.602)
				(xy 1.827 2.606) (xy 1.824 2.611) (xy 1.815 2.621) (xy 1.803 2.636) (xy 1.789 2.654) (xy 1.775 2.671)
				(xy 1.761 2.688) (xy 1.749 2.701) (xy 1.742 2.71) (xy 1.739 2.712) (xy 1.735 2.71) (xy 1.724 2.704)
				(xy 1.713 2.698) (xy 1.697 2.69) (xy 1.682 2.686) (xy 1.664 2.685) (xy 1.653 2.685) (xy 1.618 2.688)
				(xy 1.59 2.699) (xy 1.566 2.718) (xy 1.561 2.723) (xy 1.554 2.732) (xy 1.548 2.74) (xy 1.544 2.748)
				(xy 1.54 2.758) (xy 1.537 2.769) (xy 1.534 2.785) (xy 1.533 2.804) (xy 1.532 2.829) (xy 1.531 2.861)
				(xy 1.53 2.899) (xy 1.53 2.947) (xy 1.53 2.988) (xy 1.528 3.2) (xy 1.468 3.2) (xy 1.444 3.2) (xy 1.425 3.199)
				(xy 1.411 3.198) (xy 1.405 3.197) (xy 1.404 3.191) (xy 1.404 3.176) (xy 1.403 3.153) (xy 1.403 3.122)
				(xy 1.402 3.085) (xy 1.402 3.042) (xy 1.402 2.993) (xy 1.402 2.941) (xy 1.402 2.886) (xy 1.402 2.565)
				(xy 1.529 2.565) (xy 1.529 2.595) (xy 1.529 2.611) (xy 1.53 2.623) (xy 1.532 2.626) (xy 1.537 2.623)
				(xy 1.547 2.615) (xy 1.554 2.608) (xy 1.588 2.584) (xy 1.627 2.567) (xy 1.669 2.558) (xy 1.712 2.556)
				(xy 1.753 2.563)
			)
			(stroke
				(width 0.01)
				(type solid)
			)
			(fill solid)
			(layer "F.Mask")
		)
		(fp_poly
			(pts
				(xy 2.316 1.557) (xy 2.365 1.57) (xy 2.41 1.593) (xy 2.453 1.625) (xy 2.46 1.631) (xy 2.491 1.661)
				(xy 2.466 1.684) (xy 2.448 1.699) (xy 2.43 1.715) (xy 2.419 1.725) (xy 2.397 1.743) (xy 2.376 1.724)
				(xy 2.345 1.701) (xy 2.312 1.687) (xy 2.274 1.681) (xy 2.265 1.681) (xy 2.226 1.684) (xy 2.195 1.693)
				(xy 2.167 1.708) (xy 2.159 1.715) (xy 2.136 1.741) (xy 2.118 1.776) (xy 2.107 1.817) (xy 2.103 1.866)
				(xy 2.103 1.876) (xy 2.106 1.926) (xy 2.116 1.97) (xy 2.132 2.006) (xy 2.155 2.034) (xy 2.184 2.055)
				(xy 2.219 2.067) (xy 2.259 2.072) (xy 2.274 2.071) (xy 2.309 2.066) (xy 2.339 2.056) (xy 2.366 2.038)
				(xy 2.377 2.028) (xy 2.386 2.02) (xy 2.393 2.016) (xy 2.4 2.015) (xy 2.409 2.018) (xy 2.42 2.027)
				(xy 2.436 2.041) (xy 2.456 2.059) (xy 2.491 2.092) (xy 2.476 2.108) (xy 2.449 2.132) (xy 2.416 2.155)
				(xy 2.38 2.174) (xy 2.35 2.186) (xy 2.327 2.193) (xy 2.306 2.197) (xy 2.283 2.199) (xy 2.259 2.199)
				(xy 2.233 2.198) (xy 2.209 2.196) (xy 2.189 2.193) (xy 2.182 2.191) (xy 2.133 2.173) (xy 2.089 2.146)
				(xy 2.053 2.112) (xy 2.023 2.071) (xy 2.012 2.051) (xy 2 2.023) (xy 1.991 1.999) (xy 1.984 1.975)
				(xy 1.981 1.948) (xy 1.979 1.917) (xy 1.978 1.879) (xy 1.978 1.877) (xy 1.979 1.838) (xy 1.98 1.806)
				(xy 1.984 1.78) (xy 1.99 1.756) (xy 1.999 1.731) (xy 2.011 1.704) (xy 2.012 1.701) (xy 2.039 1.657)
				(xy 2.072 1.62) (xy 2.111 1.591) (xy 2.156 1.57) (xy 2.207 1.557) (xy 2.263 1.552) (xy 2.316 1.557)
			)
			(stroke
				(width 0.01)
				(type solid)
			)
			(fill solid)
			(layer "F.Mask")
		)
		(fp_poly
			(pts
				(xy -1.494 1.56) (xy -1.447 1.576) (xy -1.405 1.6) (xy -1.368 1.633) (xy -1.341 1.668) (xy -1.326 1.692)
				(xy -1.316 1.716) (xy -1.308 1.743) (xy -1.302 1.774) (xy -1.299 1.811) (xy -1.297 1.845) (xy -1.294 1.925)
				(xy -1.692 1.925) (xy -1.692 1.942) (xy -1.687 1.977) (xy -1.673 2.011) (xy -1.65 2.039) (xy -1.626 2.059)
				(xy -1.601 2.071) (xy -1.572 2.078) (xy -1.537 2.079) (xy -1.497 2.074) (xy -1.458 2.06) (xy -1.422 2.036)
				(xy -1.421 2.036) (xy -1.402 2.021) (xy -1.359 2.057) (xy -1.342 2.072) (xy -1.327 2.085) (xy -1.317 2.094)
				(xy -1.314 2.098) (xy -1.316 2.103) (xy -1.324 2.113) (xy -1.338 2.126) (xy -1.354 2.139) (xy -1.372 2.152)
				(xy -1.389 2.163) (xy -1.399 2.168) (xy -1.421 2.178) (xy -1.445 2.187) (xy -1.461 2.191) (xy -1.488 2.196)
				(xy -1.522 2.199) (xy -1.557 2.199) (xy -1.591 2.196) (xy -1.62 2.192) (xy -1.629 2.19) (xy -1.677 2.171)
				(xy -1.718 2.146) (xy -1.752 2.114) (xy -1.779 2.074) (xy -1.8 2.026) (xy -1.802 2.02) (xy -1.81 1.989)
				(xy -1.815 1.951) (xy -1.818 1.908) (xy -1.819 1.865) (xy -1.818 1.823) (xy -1.816 1.804) (xy -1.692 1.804)
				(xy -1.692 1.818) (xy -1.428 1.818) (xy -1.428 1.801) (xy -1.432 1.775) (xy -1.442 1.748) (xy -1.457 1.722)
				(xy -1.469 1.707) (xy -1.495 1.688) (xy -1.526 1.676) (xy -1.56 1.672) (xy -1.593 1.676) (xy -1.619 1.685)
				(xy -1.646 1.704) (xy -1.668 1.73) (xy -1.683 1.76) (xy -1.691 1.792) (xy -1.692 1.804) (xy -1.816 1.804)
				(xy -1.814 1.786) (xy -1.812 1.777) (xy -1.797 1.724) (xy -1.775 1.676) (xy -1.747 1.636) (xy -1.713 1.603)
				(xy -1.673 1.578) (xy -1.629 1.561) (xy -1.597 1.554) (xy -1.544 1.552) (xy -1.494 1.56)
			)
			(stroke
				(width 0.01)
				(type solid)
			)
			(fill solid)
			(layer "F.Mask")
		)
		(fp_poly
			(pts
				(xy 2.835 1.557) (xy 2.883 1.57) (xy 2.926 1.592) (xy 2.964 1.621) (xy 2.996 1.657) (xy 3.021 1.699)
				(xy 3.038 1.747) (xy 3.04 1.757) (xy 3.043 1.776) (xy 3.045 1.802) (xy 3.047 1.832) (xy 3.047 1.858)
				(xy 3.047 1.925) (xy 2.65 1.925) (xy 2.653 1.951) (xy 2.663 1.991) (xy 2.68 2.024) (xy 2.703 2.049)
				(xy 2.733 2.067) (xy 2.77 2.077) (xy 2.801 2.079) (xy 2.845 2.075) (xy 2.883 2.063) (xy 2.916 2.042)
				(xy 2.92 2.039) (xy 2.929 2.031) (xy 2.935 2.026) (xy 2.941 2.025) (xy 2.949 2.027) (xy 2.959 2.034)
				(xy 2.974 2.047) (xy 2.994 2.064) (xy 3.01 2.078) (xy 3.023 2.088) (xy 3.03 2.095) (xy 3.032 2.096)
				(xy 3.03 2.1) (xy 3.022 2.11) (xy 3.01 2.122) (xy 3.009 2.123) (xy 2.98 2.147) (xy 2.945 2.169)
				(xy 2.906 2.185) (xy 2.887 2.191) (xy 2.861 2.196) (xy 2.828 2.198) (xy 2.793 2.198) (xy 2.759 2.197)
				(xy 2.729 2.193) (xy 2.721 2.191) (xy 2.675 2.175) (xy 2.634 2.15) (xy 2.599 2.118) (xy 2.569 2.077)
				(xy 2.547 2.029) (xy 2.536 1.996) (xy 2.532 1.973) (xy 2.529 1.942) (xy 2.527 1.906) (xy 2.527 1.869)
				(xy 2.528 1.832) (xy 2.529 1.818) (xy 2.65 1.818) (xy 2.922 1.818) (xy 2.918 1.799) (xy 2.908 1.758)
				(xy 2.891 1.725) (xy 2.869 1.7) (xy 2.84 1.683) (xy 2.826 1.678) (xy 2.788 1.672) (xy 2.753 1.675)
				(xy 2.722 1.687) (xy 2.695 1.706) (xy 2.674 1.734) (xy 2.659 1.768) (xy 2.654 1.794) (xy 2.65 1.818)
				(xy 2.529 1.818) (xy 2.53 1.798) (xy 2.534 1.769) (xy 2.536 1.76) (xy 2.554 1.707) (xy 2.578 1.662)
				(xy 2.609 1.624) (xy 2.645 1.593) (xy 2.687 1.571) (xy 2.734 1.557) (xy 2.783 1.553) (xy 2.835 1.557)
			)
			(stroke
				(width 0.01)
				(type solid)
			)
			(fill solid)
			(layer "F.Mask")
		)
		(fp_poly
			(pts
				(xy -2.733 1.557) (xy -2.685 1.57) (xy -2.642 1.592) (xy -2.604 1.622) (xy -2.581 1.649) (xy -2.562 1.676)
				(xy -2.548 1.706) (xy -2.537 1.739) (xy -2.53 1.777) (xy -2.527 1.821) (xy -2.526 1.873) (xy -2.527 1.907)
				(xy -2.529 1.956) (xy -2.534 1.997) (xy -2.542 2.031) (xy -2.553 2.06) (xy -2.567 2.086) (xy -2.587 2.111)
				(xy -2.603 2.129) (xy -2.637 2.158) (xy -2.673 2.178) (xy -2.714 2.192) (xy -2.76 2.198) (xy -2.789 2.199)
				(xy -2.813 2.198) (xy -2.835 2.196) (xy -2.852 2.194) (xy -2.857 2.194) (xy -2.898 2.179) (xy -2.937 2.155)
				(xy -2.97 2.126) (xy -2.993 2.101) (xy -3.011 2.077) (xy -3.024 2.051) (xy -3.034 2.022) (xy -3.041 1.988)
				(xy -3.045 1.947) (xy -3.047 1.91) (xy -3.047 1.882) (xy -2.919 1.882) (xy -2.919 1.968) (xy -2.903 2.001)
				(xy -2.885 2.031) (xy -2.863 2.051) (xy -2.837 2.064) (xy -2.804 2.07) (xy -2.779 2.07) (xy -2.755 2.069)
				(xy -2.737 2.065) (xy -2.722 2.058) (xy -2.717 2.055) (xy -2.697 2.041) (xy -2.681 2.025) (xy -2.67 2.004)
				(xy -2.662 1.978) (xy -2.657 1.945) (xy -2.654 1.903) (xy -2.654 1.899) (xy -2.653 1.848) (xy -2.656 1.806)
				(xy -2.662 1.772) (xy -2.673 1.744) (xy -2.687 1.722) (xy -2.707 1.705) (xy -2.723 1.695) (xy -2.755 1.684)
				(xy -2.788 1.68) (xy -2.821 1.684) (xy -2.851 1.695) (xy -2.877 1.713) (xy -2.892 1.729) (xy -2.901 1.745)
				(xy -2.908 1.76) (xy -2.913 1.778) (xy -2.916 1.8) (xy -2.918 1.828) (xy -2.919 1.864) (xy -2.919 1.882)
				(xy -3.047 1.882) (xy -3.048 1.844) (xy -3.043 1.786) (xy -3.034 1.736) (xy -3.021 1.695) (xy -3.004 1.664)
				(xy -2.972 1.624) (xy -2.935 1.594) (xy -2.893 1.571) (xy -2.846 1.558) (xy -2.794 1.553) (xy -2.787 1.553)
				(xy -2.733 1.557)
			)
			(stroke
				(width 0.01)
				(type solid)
			)
			(fill solid)
			(layer "F.Mask")
		)
		(fp_poly
			(pts
				(xy 2.148 2.561) (xy 2.193 2.574) (xy 2.235 2.595) (xy 2.273 2.623) (xy 2.304 2.657) (xy 2.326 2.691)
				(xy 2.338 2.718) (xy 2.346 2.745) (xy 2.352 2.774) (xy 2.355 2.808) (xy 2.357 2.85) (xy 2.357 2.858)
				(xy 2.357 2.931) (xy 1.96 2.931) (xy 1.963 2.955) (xy 1.973 2.993) (xy 1.991 3.026) (xy 2.015 3.053)
				(xy 2.039 3.069) (xy 2.057 3.076) (xy 2.08 3.08) (xy 2.103 3.082) (xy 2.144 3.081) (xy 2.18 3.071)
				(xy 2.214 3.054) (xy 2.227 3.045) (xy 2.24 3.035) (xy 2.25 3.029) (xy 2.253 3.027) (xy 2.258 3.03)
				(xy 2.269 3.039) (xy 2.284 3.05) (xy 2.3 3.064) (xy 2.315 3.078) (xy 2.329 3.09) (xy 2.338 3.099)
				(xy 2.341 3.103) (xy 2.337 3.11) (xy 2.327 3.121) (xy 2.312 3.134) (xy 2.294 3.148) (xy 2.276 3.161)
				(xy 2.259 3.171) (xy 2.252 3.175) (xy 2.204 3.192) (xy 2.152 3.202) (xy 2.098 3.204) (xy 2.046 3.198)
				(xy 2.032 3.195) (xy 1.984 3.178) (xy 1.943 3.154) (xy 1.909 3.123) (xy 1.881 3.084) (xy 1.859 3.037)
				(xy 1.847 3.003) (xy 1.841 2.972) (xy 1.838 2.934) (xy 1.836 2.893) (xy 1.837 2.851) (xy 1.839 2.824)
				(xy 1.96 2.824) (xy 2.23 2.824) (xy 2.23 2.813) (xy 2.225 2.783) (xy 2.214 2.753) (xy 2.196 2.725)
				(xy 2.175 2.702) (xy 2.151 2.686) (xy 2.128 2.68) (xy 2.101 2.677) (xy 2.072 2.678) (xy 2.051 2.683)
				(xy 2.023 2.696) (xy 2 2.717) (xy 1.981 2.746) (xy 1.968 2.779) (xy 1.963 2.8) (xy 1.96 2.824) (xy 1.839 2.824)
				(xy 1.839 2.811) (xy 1.844 2.776) (xy 1.848 2.76) (xy 1.866 2.708) (xy 1.889 2.663) (xy 1.919 2.627)
				(xy 1.954 2.598) (xy 1.996 2.575) (xy 2.007 2.571) (xy 2.054 2.559) (xy 2.101 2.556) (xy 2.148 2.561)
			)
			(stroke
				(width 0.01)
				(type solid)
			)
			(fill solid)
			(layer "F.Mask")
		)
		(fp_poly
			(pts
				(xy -0.229 3.2) (xy -0.354 3.197) (xy -0.355 3.165) (xy -0.357 3.133) (xy -0.374 3.148) (xy -0.411 3.175)
				(xy -0.453 3.193) (xy -0.497 3.203) (xy -0.542 3.204) (xy -0.585 3.195) (xy -0.586 3.195) (xy -0.621 3.181)
				(xy -0.651 3.16) (xy -0.673 3.141) (xy -0.689 3.123) (xy -0.702 3.106) (xy -0.712 3.086) (xy -0.72 3.064)
				(xy -0.726 3.038) (xy -0.73 3.007) (xy -0.732 2.968) (xy -0.733 2.922) (xy -0.733 2.88) (xy -0.602 2.88)
				(xy -0.602 2.915) (xy -0.602 2.942) (xy -0.601 2.962) (xy -0.6 2.977) (xy -0.598 2.988) (xy -0.596 2.998)
				(xy -0.592 3.007) (xy -0.591 3.01) (xy -0.574 3.039) (xy -0.552 3.059) (xy -0.525 3.071) (xy -0.492 3.076)
				(xy -0.472 3.076) (xy -0.442 3.072) (xy -0.418 3.063) (xy -0.398 3.048) (xy -0.382 3.029) (xy -0.371 3.004)
				(xy -0.363 2.972) (xy -0.358 2.933) (xy -0.356 2.885) (xy -0.356 2.88) (xy -0.358 2.828) (xy -0.363 2.785)
				(xy -0.373 2.75) (xy -0.387 2.724) (xy -0.406 2.704) (xy -0.43 2.692) (xy -0.46 2.686) (xy -0.483 2.685)
				(xy -0.517 2.687) (xy -0.544 2.696) (xy -0.565 2.711) (xy -0.583 2.734) (xy -0.591 2.751) (xy -0.595 2.76)
				(xy -0.598 2.769) (xy -0.6 2.779) (xy -0.601 2.793) (xy -0.602 2.811) (xy -0.602 2.836) (xy -0.602 2.869)
				(xy -0.602 2.88) (xy -0.733 2.88) (xy -0.733 2.827) (xy -0.732 2.783) (xy -0.729 2.746) (xy -0.725 2.716)
				(xy -0.719 2.691) (xy -0.71 2.67) (xy -0.699 2.651) (xy -0.685 2.633) (xy -0.668 2.616) (xy -0.668 2.615)
				(xy -0.632 2.587) (xy -0.592 2.567) (xy -0.55 2.557) (xy -0.506 2.556) (xy -0.463 2.564) (xy -0.421 2.582)
				(xy -0.411 2.587) (xy -0.394 2.598) (xy -0.377 2.61) (xy -0.373 2.614) (xy -0.356 2.627) (xy -0.356 2.306)
				(xy -0.229 2.306) (xy -0.229 3.2)
			)
			(stroke
				(width 0.01)
				(type solid)
			)
			(fill solid)
			(layer "F.Mask")
		)
		(fp_poly
			(pts
				(xy 0.605 1.558) (xy 0.651 1.574) (xy 0.694 1.598) (xy 0.728 1.627) (xy 0.75 1.652) (xy 0.768 1.678)
				(xy 0.781 1.707) (xy 0.791 1.739) (xy 0.797 1.777) (xy 0.801 1.822) (xy 0.802 1.876) (xy 0.802 1.877)
				(xy 0.801 1.929) (xy 0.798 1.973) (xy 0.792 2.009) (xy 0.784 2.04) (xy 0.774 2.062) (xy 0.748 2.103)
				(xy 0.715 2.139) (xy 0.675 2.167) (xy 0.632 2.187) (xy 0.626 2.189) (xy 0.599 2.195) (xy 0.567 2.198)
				(xy 0.532 2.199) (xy 0.499 2.197) (xy 0.471 2.193) (xy 0.466 2.192) (xy 0.428 2.177) (xy 0.391 2.155)
				(xy 0.359 2.129) (xy 0.354 2.123) (xy 0.332 2.098) (xy 0.316 2.073) (xy 0.303 2.047) (xy 0.294 2.017)
				(xy 0.287 1.983) (xy 0.284 1.943) (xy 0.282 1.894) (xy 0.282 1.877) (xy 0.409 1.877) (xy 0.41 1.918)
				(xy 0.412 1.95) (xy 0.416 1.976) (xy 0.423 1.997) (xy 0.432 2.015) (xy 0.445 2.03) (xy 0.451 2.037)
				(xy 0.471 2.054) (xy 0.491 2.064) (xy 0.514 2.07) (xy 0.543 2.072) (xy 0.569 2.07) (xy 0.59 2.065)
				(xy 0.601 2.06) (xy 0.625 2.047) (xy 0.642 2.031) (xy 0.656 2.009) (xy 0.661 1.998) (xy 0.665 1.989)
				(xy 0.668 1.98) (xy 0.67 1.969) (xy 0.671 1.954) (xy 0.672 1.935) (xy 0.673 1.909) (xy 0.673 1.877)
				(xy 0.673 1.842) (xy 0.672 1.817) (xy 0.671 1.798) (xy 0.67 1.784) (xy 0.668 1.773) (xy 0.665 1.764)
				(xy 0.661 1.755) (xy 0.647 1.73) (xy 0.632 1.712) (xy 0.612 1.698) (xy 0.601 1.693) (xy 0.569 1.683)
				(xy 0.535 1.681) (xy 0.501 1.686) (xy 0.471 1.7) (xy 0.447 1.719) (xy 0.434 1.736) (xy 0.424 1.753)
				(xy 0.417 1.774) (xy 0.412 1.8) (xy 0.41 1.833) (xy 0.409 1.873) (xy 0.409 1.877) (xy 0.282 1.877)
				(xy 0.283 1.824) (xy 0.286 1.78) (xy 0.292 1.742) (xy 0.301 1.711) (xy 0.313 1.683) (xy 0.33 1.657)
				(xy 0.35 1.633) (xy 0.351 1.632) (xy 0.385 1.601) (xy 0.42 1.578) (xy 0.46 1.563) (xy 0.505 1.554)
				(xy 0.555 1.551) (xy 0.605 1.558)
			)
			(stroke
				(width 0.01)
				(type solid)
			)
			(fill solid)
			(layer "F.Mask")
		)
		(fp_poly
			(pts
				(xy 0.004 1.556) (xy 0.054 1.566) (xy 0.102 1.582) (xy 0.146 1.605) (xy 0.154 1.61) (xy 0.193 1.636)
				(xy 0.178 1.655) (xy 0.166 1.668) (xy 0.152 1.686) (xy 0.138 1.7) (xy 0.114 1.727) (xy 0.07 1.705)
				(xy 0.032 1.688) (xy -0.007 1.677) (xy -0.044 1.672) (xy -0.079 1.672) (xy -0.11 1.678) (xy -0.136 1.69)
				(xy -0.154 1.707) (xy -0.162 1.724) (xy -0.164 1.745) (xy -0.164 1.761) (xy -0.159 1.772) (xy -0.15 1.782)
				(xy -0.149 1.783) (xy -0.139 1.791) (xy -0.128 1.797) (xy -0.114 1.802) (xy -0.095 1.805) (xy -0.07 1.808)
				(xy -0.037 1.811) (xy -0.02 1.813) (xy 0.027 1.817) (xy 0.065 1.823) (xy 0.096 1.832) (xy 0.122 1.842)
				(xy 0.14 1.854) (xy 0.166 1.879) (xy 0.186 1.91) (xy 0.2 1.947) (xy 0.206 1.987) (xy 0.206 2.018)
				(xy 0.198 2.06) (xy 0.181 2.097) (xy 0.155 2.129) (xy 0.122 2.156) (xy 0.08 2.177) (xy 0.042 2.189)
				(xy 0.005 2.196) (xy -0.038 2.199) (xy -0.083 2.198) (xy -0.125 2.194) (xy -0.153 2.189) (xy -0.177 2.181)
				(xy -0.204 2.171) (xy -0.229 2.16) (xy -0.232 2.159) (xy -0.251 2.148) (xy -0.272 2.136) (xy -0.292 2.122)
				(xy -0.309 2.109) (xy -0.323 2.098) (xy -0.33 2.09) (xy -0.331 2.088) (xy -0.327 2.084) (xy -0.318 2.073)
				(xy -0.304 2.059) (xy -0.288 2.043) (xy -0.246 2) (xy -0.221 2.021) (xy -0.184 2.047) (xy -0.145 2.065)
				(xy -0.102 2.075) (xy -0.053 2.079) (xy -0.049 2.079) (xy -0.023 2.079) (xy -0.004 2.078) (xy 0.011 2.074)
				(xy 0.025 2.069) (xy 0.029 2.068) (xy 0.054 2.052) (xy 0.071 2.033) (xy 0.079 2.01) (xy 0.078 1.986)
				(xy 0.074 1.975) (xy 0.068 1.964) (xy 0.06 1.956) (xy 0.048 1.949) (xy 0.031 1.944) (xy 0.007 1.939)
				(xy -0.024 1.935) (xy -0.052 1.932) (xy -0.089 1.929) (xy -0.119 1.925) (xy -0.142 1.921) (xy -0.16 1.917)
				(xy -0.176 1.912) (xy -0.192 1.906) (xy -0.201 1.901) (xy -0.235 1.879) (xy -0.262 1.85) (xy -0.28 1.816)
				(xy -0.29 1.776) (xy -0.292 1.75) (xy -0.291 1.727) (xy -0.289 1.705) (xy -0.286 1.689) (xy -0.286 1.688)
				(xy -0.273 1.659) (xy -0.253 1.63) (xy -0.229 1.604) (xy -0.221 1.599) (xy -0.185 1.577) (xy -0.143 1.562)
				(xy -0.096 1.554) (xy -0.047 1.552) (xy 0.004 1.556)
			)
			(stroke
				(width 0.01)
				(type solid)
			)
			(fill solid)
			(layer "F.Mask")
		)
		(fp_poly
			(pts
				(xy 1.038 2.556) (xy 1.091 2.563) (xy 1.137 2.576) (xy 1.177 2.595) (xy 1.209 2.62) (xy 1.234 2.65)
				(xy 1.242 2.665) (xy 1.247 2.677) (xy 1.251 2.691) (xy 1.255 2.708) (xy 1.258 2.727) (xy 1.26 2.751)
				(xy 1.262 2.78) (xy 1.263 2.815) (xy 1.263 2.858) (xy 1.264 2.908) (xy 1.263 2.967) (xy 1.263 2.989)
				(xy 1.262 3.197) (xy 1.135 3.197) (xy 1.133 3.171) (xy 1.132 3.144) (xy 1.119 3.159) (xy 1.096 3.179)
				(xy 1.065 3.193) (xy 1.026 3.202) (xy 0.98 3.204) (xy 0.976 3.204) (xy 0.955 3.204) (xy 0.937 3.203)
				(xy 0.925 3.202) (xy 0.924 3.201) (xy 0.879 3.189) (xy 0.839 3.17) (xy 0.806 3.144) (xy 0.781 3.113)
				(xy 0.763 3.077) (xy 0.753 3.037) (xy 0.753 3.005) (xy 0.873 3.005) (xy 0.874 3.023) (xy 0.878 3.035)
				(xy 0.887 3.047) (xy 0.89 3.05) (xy 0.903 3.063) (xy 0.917 3.072) (xy 0.935 3.078) (xy 0.957 3.081)
				(xy 0.986 3.082) (xy 1.013 3.082) (xy 1.043 3.081) (xy 1.065 3.079) (xy 1.08 3.077) (xy 1.091 3.073)
				(xy 1.096 3.071) (xy 1.112 3.058) (xy 1.123 3.039) (xy 1.13 3.012) (xy 1.132 2.977) (xy 1.132 2.975)
				(xy 1.132 2.931) (xy 1.035 2.931) (xy 0.999 2.931) (xy 0.973 2.931) (xy 0.953 2.932) (xy 0.939 2.934)
				(xy 0.928 2.936) (xy 0.919 2.939) (xy 0.916 2.94) (xy 0.893 2.954) (xy 0.88 2.971) (xy 0.874 2.994)
				(xy 0.873 3.005) (xy 0.753 3.005) (xy 0.753 2.994) (xy 0.761 2.951) (xy 0.768 2.931) (xy 0.776 2.915)
				(xy 0.786 2.901) (xy 0.802 2.884) (xy 0.804 2.882) (xy 0.82 2.867) (xy 0.835 2.854) (xy 0.85 2.845)
				(xy 0.867 2.838) (xy 0.887 2.833) (xy 0.912 2.829) (xy 0.943 2.827) (xy 0.982 2.826) (xy 1.015 2.825)
				(xy 1.133 2.823) (xy 1.132 2.771) (xy 1.131 2.746) (xy 1.129 2.73) (xy 1.127 2.719) (xy 1.123 2.711)
				(xy 1.117 2.705) (xy 1.098 2.691) (xy 1.07 2.682) (xy 1.032 2.677) (xy 1.006 2.677) (xy 0.972 2.678)
				(xy 0.945 2.682) (xy 0.924 2.688) (xy 0.907 2.699) (xy 0.9 2.706) (xy 0.882 2.723) (xy 0.834 2.686)
				(xy 0.816 2.672) (xy 0.801 2.66) (xy 0.79 2.652) (xy 0.787 2.648) (xy 0.791 2.639) (xy 0.801 2.626)
				(xy 0.816 2.612) (xy 0.832 2.6) (xy 0.864 2.581) (xy 0.902 2.568) (xy 0.946 2.559) (xy 0.98 2.556)
				(xy 1.038 2.556)
			)
			(stroke
				(width 0.01)
				(type solid)
			)
			(fill solid)
			(layer "F.Mask")
		)
		(fp_poly
			(pts
				(xy -1.521 2.559) (xy -1.485 2.562) (xy -1.454 2.568) (xy -1.427 2.577) (xy -1.401 2.589) (xy -1.371 2.61)
				(xy -1.345 2.639) (xy -1.325 2.67) (xy -1.321 2.679) (xy -1.309 2.71) (xy -1.309 3.197) (xy -1.433 3.2)
				(xy -1.433 3.172) (xy -1.434 3.157) (xy -1.435 3.147) (xy -1.436 3.144) (xy -1.44 3.147) (xy -1.449 3.156)
				(xy -1.453 3.161) (xy -1.472 3.178) (xy -1.496 3.19) (xy -1.526 3.198) (xy -1.563 3.202) (xy -1.578 3.203)
				(xy -1.603 3.203) (xy -1.627 3.203) (xy -1.647 3.201) (xy -1.656 3.2) (xy -1.686 3.191) (xy -1.717 3.176)
				(xy -1.746 3.159) (xy -1.765 3.143) (xy -1.79 3.111) (xy -1.807 3.075) (xy -1.816 3.037) (xy -1.817 2.998)
				(xy -1.817 2.997) (xy -1.697 2.997) (xy -1.696 3.02) (xy -1.687 3.042) (xy -1.67 3.06) (xy -1.668 3.062)
				(xy -1.654 3.07) (xy -1.64 3.076) (xy -1.624 3.08) (xy -1.602 3.081) (xy -1.574 3.082) (xy -1.558 3.082)
				(xy -1.529 3.081) (xy -1.508 3.08) (xy -1.494 3.078) (xy -1.483 3.075) (xy -1.474 3.07) (xy -1.458 3.058)
				(xy -1.447 3.041) (xy -1.44 3.017) (xy -1.435 2.985) (xy -1.435 2.977) (xy -1.432 2.931) (xy -1.533 2.931)
				(xy -1.568 2.931) (xy -1.595 2.931) (xy -1.615 2.932) (xy -1.63 2.934) (xy -1.641 2.936) (xy -1.65 2.938)
				(xy -1.655 2.941) (xy -1.676 2.955) (xy -1.69 2.974) (xy -1.697 2.997) (xy -1.817 2.997) (xy -1.811 2.96)
				(xy -1.797 2.924) (xy -1.775 2.892) (xy -1.747 2.864) (xy -1.715 2.845) (xy -1.7 2.838) (xy -1.685 2.833)
				(xy -1.668 2.83) (xy -1.648 2.827) (xy -1.623 2.825) (xy -1.591 2.824) (xy -1.551 2.824) (xy -1.54 2.824)
				(xy -1.432 2.824) (xy -1.434 2.776) (xy -1.436 2.747) (xy -1.441 2.726) (xy -1.448 2.711) (xy -1.46 2.699)
				(xy -1.474 2.689) (xy -1.483 2.685) (xy -1.492 2.682) (xy -1.505 2.68) (xy -1.524 2.68) (xy -1.55 2.679)
				(xy -1.56 2.679) (xy -1.594 2.68) (xy -1.62 2.682) (xy -1.639 2.686) (xy -1.654 2.692) (xy -1.666 2.701)
				(xy -1.675 2.711) (xy -1.686 2.724) (xy -1.735 2.686) (xy -1.754 2.672) (xy -1.769 2.659) (xy -1.78 2.65)
				(xy -1.784 2.646) (xy -1.78 2.64) (xy -1.77 2.629) (xy -1.756 2.616) (xy -1.74 2.604) (xy -1.724 2.592)
				(xy -1.711 2.584) (xy -1.71 2.583) (xy -1.688 2.574) (xy -1.668 2.566) (xy -1.647 2.562) (xy -1.623 2.559)
				(xy -1.593 2.558) (xy -1.565 2.558) (xy -1.521 2.559)
			)
			(stroke
				(width 0.01)
				(type solid)
			)
			(fill solid)
			(layer "F.Mask")
		)
		(fp_poly
			(pts
				(xy 0.035 2.777) (xy 0.047 2.822) (xy 0.059 2.864) (xy 0.069 2.903) (xy 0.078 2.936) (xy 0.086 2.963)
				(xy 0.092 2.984) (xy 0.095 2.996) (xy 0.096 2.999) (xy 0.098 2.999) (xy 0.103 2.991) (xy 0.109 2.975)
				(xy 0.118 2.95) (xy 0.129 2.917) (xy 0.143 2.874) (xy 0.152 2.849) (xy 0.165 2.807) (xy 0.179 2.766)
				(xy 0.192 2.726) (xy 0.204 2.689) (xy 0.214 2.658) (xy 0.221 2.634) (xy 0.224 2.627) (xy 0.244 2.565)
				(xy 0.338 2.565) (xy 0.406 2.774) (xy 0.42 2.819) (xy 0.434 2.861) (xy 0.446 2.899) (xy 0.457 2.932)
				(xy 0.466 2.96) (xy 0.473 2.981) (xy 0.477 2.993) (xy 0.478 2.997) (xy 0.48 2.998) (xy 0.482 2.996)
				(xy 0.485 2.99) (xy 0.49 2.978) (xy 0.495 2.96) (xy 0.502 2.936) (xy 0.511 2.905) (xy 0.523 2.865)
				(xy 0.536 2.817) (xy 0.543 2.789) (xy 0.556 2.744) (xy 0.568 2.701) (xy 0.578 2.663) (xy 0.587 2.629)
				(xy 0.595 2.602) (xy 0.601 2.582) (xy 0.605 2.57) (xy 0.606 2.567) (xy 0.611 2.566) (xy 0.625 2.566)
				(xy 0.645 2.566) (xy 0.669 2.566) (xy 0.673 2.566) (xy 0.739 2.567) (xy 0.656 2.827) (xy 0.64 2.878)
				(xy 0.624 2.928) (xy 0.609 2.976) (xy 0.595 3.02) (xy 0.582 3.06) (xy 0.571 3.094) (xy 0.563 3.121)
				(xy 0.557 3.139) (xy 0.556 3.143) (xy 0.538 3.2) (xy 0.425 3.197) (xy 0.358 2.975) (xy 0.341 2.917)
				(xy 0.327 2.87) (xy 0.315 2.831) (xy 0.305 2.801) (xy 0.297 2.78) (xy 0.292 2.766) (xy 0.289 2.761)
				(xy 0.288 2.761) (xy 0.286 2.768) (xy 0.281 2.783) (xy 0.274 2.806) (xy 0.265 2.836) (xy 0.254 2.871)
				(xy 0.242 2.911) (xy 0.23 2.953) (xy 0.223 2.976) (xy 0.21 3.02) (xy 0.197 3.062) (xy 0.186 3.099)
				(xy 0.177 3.132) (xy 0.169 3.158) (xy 0.163 3.177) (xy 0.16 3.189) (xy 0.159 3.191) (xy 0.157 3.195)
				(xy 0.151 3.198) (xy 0.141 3.199) (xy 0.124 3.2) (xy 0.101 3.2) (xy 0.073 3.199) (xy 0.055 3.198)
				(xy 0.045 3.196) (xy 0.043 3.194) (xy 0.041 3.188) (xy 0.036 3.173) (xy 0.029 3.15) (xy 0.019 3.121)
				(xy 0.008 3.084) (xy -0.006 3.043) (xy -0.02 2.996) (xy -0.036 2.946) (xy -0.053 2.893) (xy -0.057 2.883)
				(xy -0.074 2.83) (xy -0.09 2.779) (xy -0.105 2.732) (xy -0.119 2.689) (xy -0.131 2.652) (xy -0.141 2.621)
				(xy -0.148 2.596) (xy -0.154 2.58) (xy -0.156 2.572) (xy -0.156 2.569) (xy -0.151 2.567) (xy -0.14 2.566)
				(xy -0.123 2.565) (xy -0.096 2.565) (xy -0.091 2.565) (xy -0.023 2.565) (xy 0.035 2.777)
			)
			(stroke
				(width 0.01)
				(type solid)
			)
			(fill solid)
			(layer "F.Mask")
		)
		(fp_poly
			(pts
				(xy -2.065 1.559) (xy -2.024 1.576) (xy -1.986 1.601) (xy -1.973 1.612) (xy -1.957 1.63) (xy -1.943 1.649)
				(xy -1.932 1.668) (xy -1.924 1.69) (xy -1.918 1.716) (xy -1.914 1.747) (xy -1.911 1.785) (xy -1.91 1.831)
				(xy -1.91 1.877) (xy -1.91 1.93) (xy -1.912 1.974) (xy -1.914 2.011) (xy -1.919 2.041) (xy -1.925 2.067)
				(xy -1.934 2.088) (xy -1.945 2.107) (xy -1.959 2.125) (xy -1.972 2.139) (xy -1.993 2.157) (xy -2.018 2.173)
				(xy -2.031 2.18) (xy -2.047 2.188) (xy -2.06 2.192) (xy -2.074 2.195) (xy -2.091 2.196) (xy -2.114 2.197)
				(xy -2.122 2.197) (xy -2.147 2.196) (xy -2.165 2.195) (xy -2.179 2.193) (xy -2.191 2.189) (xy -2.205 2.183)
				(xy -2.21 2.18) (xy -2.231 2.169) (xy -2.251 2.156) (xy -2.265 2.146) (xy -2.286 2.127) (xy -2.286 2.627)
				(xy -2.266 2.608) (xy -2.248 2.595) (xy -2.227 2.582) (xy -2.217 2.577) (xy -2.173 2.562) (xy -2.129 2.556)
				(xy -2.086 2.559) (xy -2.045 2.57) (xy -2.007 2.589) (xy -1.974 2.616) (xy -1.946 2.648) (xy -1.926 2.687)
				(xy -1.919 2.707) (xy -1.917 2.715) (xy -1.915 2.724) (xy -1.914 2.737) (xy -1.913 2.753) (xy -1.912 2.774)
				(xy -1.911 2.8) (xy -1.911 2.833) (xy -1.911 2.874) (xy -1.911 2.923) (xy -1.911 2.967) (xy -1.911 3.2)
				(xy -2.035 3.197) (xy -2.038 2.984) (xy -2.038 2.932) (xy -2.039 2.889) (xy -2.039 2.854) (xy -2.04 2.826)
				(xy -2.041 2.805) (xy -2.042 2.788) (xy -2.043 2.776) (xy -2.045 2.767) (xy -2.046 2.76) (xy -2.049 2.755)
				(xy -2.051 2.75) (xy -2.072 2.721) (xy -2.098 2.701) (xy -2.128 2.688) (xy -2.161 2.683) (xy -2.195 2.687)
				(xy -2.22 2.697) (xy -2.24 2.71) (xy -2.259 2.729) (xy -2.274 2.75) (xy -2.278 2.757) (xy -2.28 2.765)
				(xy -2.281 2.781) (xy -2.283 2.806) (xy -2.284 2.839) (xy -2.285 2.881) (xy -2.286 2.933) (xy -2.286 2.984)
				(xy -2.289 3.197) (xy -2.413 3.2) (xy -2.413 1.877) (xy -2.286 1.877) (xy -2.285 1.926) (xy -2.281 1.966)
				(xy -2.274 1.998) (xy -2.262 2.024) (xy -2.247 2.043) (xy -2.228 2.058) (xy -2.215 2.064) (xy -2.194 2.07)
				(xy -2.168 2.072) (xy -2.141 2.071) (xy -2.117 2.066) (xy -2.106 2.063) (xy -2.079 2.044) (xy -2.058 2.019)
				(xy -2.05 2.001) (xy -2.045 1.984) (xy -2.042 1.959) (xy -2.04 1.929) (xy -2.038 1.895) (xy -2.038 1.861)
				(xy -2.039 1.829) (xy -2.041 1.8) (xy -2.044 1.777) (xy -2.045 1.772) (xy -2.057 1.738) (xy -2.073 1.712)
				(xy -2.094 1.695) (xy -2.122 1.684) (xy -2.156 1.681) (xy -2.159 1.681) (xy -2.192 1.683) (xy -2.22 1.691)
				(xy -2.243 1.705) (xy -2.26 1.725) (xy -2.273 1.753) (xy -2.281 1.788) (xy -2.285 1.832) (xy -2.286 1.877)
				(xy -2.413 1.877) (xy -2.413 1.559) (xy -2.286 1.559) (xy -2.286 1.62) (xy -2.26 1.6) (xy -2.225 1.577)
				(xy -2.19 1.563) (xy -2.154 1.554) (xy -2.109 1.552) (xy -2.065 1.559)
			)
			(stroke
				(width 0.01)
				(type solid)
			)
			(fill solid)
			(layer "F.Mask")
		)
		(fp_poly
			(pts
				(xy 0.063 -3.201) (xy 0.118 -3.201) (xy 0.164 -3.201) (xy 0.202 -3.2) (xy 0.233 -3.2) (xy 0.258 -3.2)
				(xy 0.277 -3.199) (xy 0.292 -3.198) (xy 0.302 -3.197) (xy 0.309 -3.196) (xy 0.314 -3.195) (xy 0.317 -3.193)
				(xy 0.319 -3.192) (xy 0.321 -3.189) (xy 0.324 -3.183) (xy 0.327 -3.174) (xy 0.33 -3.161) (xy 0.334 -3.144)
				(xy 0.339 -3.12) (xy 0.345 -3.091) (xy 0.352 -3.054) (xy 0.361 -3.01) (xy 0.371 -2.958) (xy 0.382 -2.897)
				(xy 0.385 -2.878) (xy 0.395 -2.824) (xy 0.405 -2.772) (xy 0.414 -2.724) (xy 0.423 -2.68) (xy 0.43 -2.642)
				(xy 0.437 -2.61) (xy 0.442 -2.586) (xy 0.446 -2.569) (xy 0.448 -2.562) (xy 0.456 -2.55) (xy 0.464 -2.544)
				(xy 0.476 -2.539) (xy 0.495 -2.53) (xy 0.521 -2.519) (xy 0.552 -2.506) (xy 0.587 -2.492) (xy 0.624 -2.477)
				(xy 0.664 -2.461) (xy 0.704 -2.445) (xy 0.743 -2.43) (xy 0.78 -2.415) (xy 0.814 -2.402) (xy 0.843 -2.391)
				(xy 0.868 -2.382) (xy 0.885 -2.376) (xy 0.895 -2.373) (xy 0.896 -2.373) (xy 0.911 -2.376) (xy 0.931 -2.386)
				(xy 0.948 -2.397) (xy 0.962 -2.406) (xy 0.983 -2.421) (xy 1.011 -2.44) (xy 1.043 -2.462) (xy 1.079 -2.487)
				(xy 1.118 -2.513) (xy 1.158 -2.541) (xy 1.198 -2.568) (xy 1.238 -2.595) (xy 1.275 -2.621) (xy 1.309 -2.644)
				(xy 1.338 -2.665) (xy 1.362 -2.681) (xy 1.377 -2.691) (xy 1.398 -2.705) (xy 1.418 -2.717) (xy 1.433 -2.725)
				(xy 1.442 -2.728) (xy 1.443 -2.728) (xy 1.448 -2.726) (xy 1.456 -2.72) (xy 1.468 -2.71) (xy 1.486 -2.694)
				(xy 1.508 -2.673) (xy 1.535 -2.647) (xy 1.568 -2.614) (xy 1.608 -2.575) (xy 1.654 -2.53) (xy 1.675 -2.509)
				(xy 1.721 -2.462) (xy 1.761 -2.422) (xy 1.794 -2.388) (xy 1.822 -2.36) (xy 1.844 -2.337) (xy 1.862 -2.318)
				(xy 1.875 -2.304) (xy 1.884 -2.293) (xy 1.89 -2.284) (xy 1.893 -2.279) (xy 1.894 -2.275) (xy 1.892 -2.269)
				(xy 1.886 -2.257) (xy 1.875 -2.239) (xy 1.86 -2.215) (xy 1.839 -2.183) (xy 1.814 -2.145) (xy 1.783 -2.1)
				(xy 1.747 -2.046) (xy 1.721 -2.009) (xy 1.69 -1.964) (xy 1.661 -1.921) (xy 1.634 -1.88) (xy 1.609 -1.844)
				(xy 1.588 -1.811) (xy 1.57 -1.785) (xy 1.557 -1.764) (xy 1.549 -1.75) (xy 1.546 -1.743) (xy 1.547 -1.735)
				(xy 1.552 -1.719) (xy 1.56 -1.696) (xy 1.571 -1.667) (xy 1.585 -1.634) (xy 1.6 -1.597) (xy 1.616 -1.557)
				(xy 1.633 -1.516) (xy 1.651 -1.476) (xy 1.668 -1.436) (xy 1.685 -1.398) (xy 1.701 -1.363) (xy 1.715 -1.333)
				(xy 1.727 -1.309) (xy 1.736 -1.291) (xy 1.742 -1.281) (xy 1.744 -1.279) (xy 1.751 -1.277) (xy 1.767 -1.273)
				(xy 1.791 -1.268) (xy 1.822 -1.261) (xy 1.86 -1.254) (xy 1.903 -1.245) (xy 1.951 -1.236) (xy 2.002 -1.226)
				(xy 2.049 -1.217) (xy 2.103 -1.207) (xy 2.154 -1.198) (xy 2.201 -1.188) (xy 2.244 -1.18) (xy 2.281 -1.173)
				(xy 2.311 -1.166) (xy 2.335 -1.161) (xy 2.35 -1.157) (xy 2.355 -1.156) (xy 2.367 -1.148) (xy 2.367 -0.834)
				(xy 2.367 -0.768) (xy 2.367 -0.712) (xy 2.367 -0.664) (xy 2.366 -0.625) (xy 2.366 -0.592) (xy 2.365 -0.566)
				(xy 2.364 -0.546) (xy 2.363 -0.531) (xy 2.361 -0.52) (xy 2.358 -0.512) (xy 2.355 -0.507) (xy 2.352 -0.504)
				(xy 2.348 -0.503) (xy 2.343 -0.501) (xy 2.34 -0.501) (xy 2.333 -0.499) (xy 2.317 -0.496) (xy 2.293 -0.492)
				(xy 2.261 -0.486) (xy 2.224 -0.479) (xy 2.181 -0.471) (xy 2.134 -0.462) (xy 2.084 -0.453) (xy 2.054 -0.448)
				(xy 2.002 -0.438) (xy 1.953 -0.429) (xy 1.907 -0.42) (xy 1.866 -0.412) (xy 1.831 -0.404) (xy 1.802 -0.398)
				(xy 1.78 -0.394) (xy 1.767 -0.391) (xy 1.764 -0.39) (xy 1.76 -0.387) (xy 1.757 -0.384) (xy 1.753 -0.379)
				(xy 1.748 -0.371) (xy 1.742 -0.36) (xy 1.735 -0.344) (xy 1.726 -0.324) (xy 1.715 -0.297) (xy 1.701 -0.264)
				(xy 1.685 -0.223) (xy 1.665 -0.174) (xy 1.653 -0.145) (xy 1.63 -0.086) (xy 1.61 -0.037) (xy 1.594 0.005)
				(xy 1.582 0.038) (xy 1.572 0.064) (xy 1.566 0.084) (xy 1.562 0.097) (xy 1.561 0.104) (xy 1.562 0.105)
				(xy 1.565 0.111) (xy 1.574 0.125) (xy 1.587 0.146) (xy 1.604 0.173) (xy 1.626 0.205) (xy 1.65 0.241)
				(xy 1.677 0.281) (xy 1.706 0.324) (xy 1.729 0.358) (xy 1.768 0.413) (xy 1.8 0.461) (xy 1.827 0.502)
				(xy 1.85 0.535) (xy 1.867 0.562) (xy 1.88 0.583) (xy 1.889 0.598) (xy 1.893 0.608) (xy 1.894 0.612)
				(xy 1.893 0.616) (xy 1.89 0.622) (xy 1.885 0.63) (xy 1.876 0.64) (xy 1.863 0.655) (xy 1.846 0.673)
				(xy 1.825 0.695) (xy 1.798 0.723) (xy 1.765 0.756) (xy 1.727 0.795) (xy 1.682 0.839) (xy 1.635 0.886)
				(xy 1.595 0.926) (xy 1.561 0.96) (xy 1.532 0.989) (xy 1.508 1.012) (xy 1.488 1.03) (xy 1.473 1.044)
				(xy 1.461 1.054) (xy 1.452 1.061) (xy 1.445 1.065) (xy 1.44 1.066) (xy 1.438 1.066) (xy 1.433 1.064)
				(xy 1.421 1.055) (xy 1.401 1.043) (xy 1.376 1.026) (xy 1.345 1.005) (xy 1.31 0.981) (xy 1.27 0.954)
				(xy 1.228 0.925) (xy 1.193 0.901) (xy 1.138 0.864) (xy 1.089 0.83) (xy 1.046 0.802) (xy 1.01 0.778)
				(xy 0.981 0.759) (xy 0.96 0.746) (xy 0.946 0.738) (xy 0.94 0.736) (xy 0.932 0.738) (xy 0.917 0.745)
				(xy 0.895 0.755) (xy 0.869 0.768) (xy 0.84 0.783) (xy 0.816 0.795) (xy 0.781 0.814) (xy 0.753 0.828)
				(xy 0.732 0.838) (xy 0.717 0.845) (xy 0.707 0.849) (xy 0.699 0.85) (xy 0.694 0.849) (xy 0.691 0.847)
				(xy 0.687 0.84) (xy 0.682 0.829) (xy 0.674 0.814) (xy 0.665 0.793) (xy 0.653 0.767) (xy 0.639 0.735)
				(xy 0.623 0.696) (xy 0.604 0.651) (xy 0.582 0.598) (xy 0.556 0.538) (xy 0.528 0.469) (xy 0.496 0.391)
				(xy 0.47 0.329) (xy 0.436 0.247) (xy 0.406 0.173) (xy 0.379 0.108) (xy 0.355 0.05) (xy 0.335 0)
				(xy 0.317 -0.043) (xy 0.303 -0.079) (xy 0.291 -0.11) (xy 0.281 -0.135) (xy 0.273 -0.155) (xy 0.268 -0.171)
				(xy 0.264 -0.183) (xy 0.262 -0.191) (xy 0.262 -0.196) (xy 0.262 -0.198) (xy 0.269 -0.207) (xy 0.283 -0.219)
				(xy 0.302 -0.233) (xy 0.303 -0.234) (xy 0.354 -0.268) (xy 0.398 -0.3) (xy 0.435 -0.331) (xy 0.469 -0.363)
				(xy 0.5 -0.397) (xy 0.507 -0.405) (xy 0.556 -0.472) (xy 0.596 -0.543) (xy 0.627 -0.619) (xy 0.643 -0.672)
				(xy 0.651 -0.718) (xy 0.657 -0.77) (xy 0.66 -0.824) (xy 0.659 -0.878) (xy 0.654 -0.927) (xy 0.652 -0.936)
				(xy 0.634 -1.015) (xy 0.607 -1.09) (xy 0.571 -1.161) (xy 0.528 -1.227) (xy 0.477 -1.287) (xy 0.419 -1.341)
				(xy 0.355 -1.387) (xy 0.285 -1.426) (xy 0.21 -1.456) (xy 0.205 -1.458) (xy 0.131 -1.477) (xy 0.054 -1.487)
				(xy -0.025 -1.489) (xy -0.103 -1.482) (xy -0.178 -1.466) (xy -0.206 -1.458) (xy -0.281 -1.428) (xy -0.351 -1.39)
				(xy -0.416 -1.344) (xy -0.474 -1.29) (xy -0.526 -1.23) (xy -0.571 -1.164) (xy -0.607 -1.093) (xy -0.63 -1.034)
				(xy -0.649 -0.96) (xy -0.659 -0.883) (xy -0.661 -0.804) (xy -0.654 -0.726) (xy -0.638 -0.651) (xy -0.63 -0.623)
				(xy -0.618 -0.591) (xy -0.602 -0.554) (xy -0.584 -0.518) (xy -0.566 -0.485) (xy -0.553 -0.463) (xy -0.509 -0.407)
				(xy -0.457 -0.352) (xy -0.397 -0.299) (xy -0.33 -0.25) (xy -0.289 -0.224) (xy -0.273 -0.212) (xy -0.263 -0.2)
				(xy -0.262 -0.197) (xy -0.263 -0.19) (xy -0.268 -0.175) (xy -0.277 -0.151) (xy -0.288 -0.121) (xy -0.302 -0.084)
				(xy -0.319 -0.042) (xy -0.338 0.005) (xy -0.358 0.056) (xy -0.381 0.111) (xy -0.404 0.168) (xy -0.428 0.228)
				(xy -0.453 0.288) (xy -0.478 0.349) (xy -0.504 0.41) (xy -0.529 0.47) (xy -0.553 0.527) (xy -0.576 0.583)
				(xy -0.598 0.635) (xy -0.619 0.683) (xy -0.638 0.727) (xy -0.655 0.765) (xy -0.669 0.797) (xy -0.68 0.822)
				(xy -0.689 0.839) (xy -0.694 0.848) (xy -0.695 0.849) (xy -0.699 0.85) (xy -0.706 0.849) (xy -0.717 0.845)
				(xy -0.732 0.839) (xy -0.752 0.829) (xy -0.779 0.815) (xy -0.814 0.797) (xy -0.817 0.795) (xy -0.848 0.779)
				(xy -0.877 0.764) (xy -0.902 0.752) (xy -0.922 0.743) (xy -0.936 0.737) (xy -0.941 0.736) (xy -0.949 0.739)
				(xy -0.964 0.748) (xy -0.987 0.761) (xy -1.015 0.78) (xy -1.05 0.803) (xy -1.072 0.818) (xy -1.138 0.863)
				(xy -1.195 0.903) (xy -1.245 0.937) (xy -1.289 0.966) (xy -1.325 0.991) (xy -1.356 1.012) (xy -1.381 1.029)
				(xy -1.401 1.042) (xy -1.416 1.052) (xy -1.427 1.059) (xy -1.435 1.064) (xy -1.439 1.066) (xy -1.44 1.066)
				(xy -1.449 1.064) (xy -1.453 1.061) (xy -1.458 1.057) (xy -1.47 1.046) (xy -1.487 1.029) (xy -1.509 1.007)
				(xy -1.537 0.98) (xy -1.568 0.95) (xy -1.602 0.915) (xy -1.639 0.879) (xy -1.678 0.84) (xy -1.678 0.839)
				(xy -1.726 0.792) (xy -1.767 0.751) (xy -1.801 0.716) (xy -1.829 0.687) (xy -1.852 0.663) (xy -1.869 0.644)
				(xy -1.882 0.63) (xy -1.89 0.62) (xy -1.894 0.613) (xy -1.895 0.61) (xy -1.892 0.603) (xy -1.884 0.588)
				(xy -1.87 0.565) (xy -1.85 0.536) (xy -1.826 0.499) (xy -1.797 0.455) (xy -1.763 0.405) (xy -1.73 0.358)
				(xy -1.7 0.313) (xy -1.671 0.271) (xy -1.645 0.232) (xy -1.621 0.197) (xy -1.601 0.166) (xy -1.584 0.141)
				(xy -1.572 0.121) (xy -1.565 0.109) (xy -1.563 0.105) (xy -1.563 0.099) (xy -1.566 0.087) (xy -1.572 0.07)
				(xy -1.58 0.045) (xy -1.592 0.013) (xy -1.607 -0.026) (xy -1.626 -0.074) (xy -1.648 -0.13) (xy -1.654 -0.145)
				(xy -1.676 -0.199) (xy -1.695 -0.245) (xy -1.71 -0.282) (xy -1.723 -0.313) (xy -1.733 -0.337) (xy -1.741 -0.356)
				(xy -1.748 -0.369) (xy -1.753 -0.379) (xy -1.758 -0.385) (xy -1.761 -0.388) (xy -1.763 -0.389) (xy -1.767 -0.39)
				(xy -1.774 -0.392) (xy -1.784 -0.395) (xy -1.799 -0.398) (xy -1.818 -0.402) (xy -1.843 -0.407) (xy -1.873 -0.413)
				(xy -1.91 -0.42) (xy -1.954 -0.429) (xy -2.005 -0.438) (xy -2.065 -0.449) (xy -2.133 -0.462) (xy -2.211 -0.477)
				(xy -2.22 -0.478) (xy -2.26 -0.486) (xy -2.29 -0.491) (xy -2.313 -0.496) (xy -2.33 -0.499) (xy -2.341 -0.502)
				(xy -2.349 -0.504) (xy -2.353 -0.506) (xy -2.356 -0.508) (xy -2.359 -0.51) (xy -2.36 -0.511) (xy -2.361 -0.514)
				(xy -2.363 -0.518) (xy -2.364 -0.526) (xy -2.365 -0.536) (xy -2.366 -0.551) (xy -2.366 -0.571) (xy -2.367 -0.597)
				(xy -2.367 -0.629) (xy -2.368 -0.668) (xy -2.368 -0.715) (xy -2.368 -0.771) (xy -2.368 -0.834) (xy -2.368 -1.148)
				(xy -2.356 -1.155) (xy -2.349 -1.158) (xy -2.333 -1.162) (xy -2.309 -1.167) (xy -2.278 -1.173) (xy -2.24 -1.181)
				(xy -2.197 -1.189) (xy -2.149 -1.198) (xy -2.098 -1.208) (xy -2.051 -1.217) (xy -1.996 -1.227) (xy -1.945 -1.237)
				(xy -1.897 -1.246) (xy -1.854 -1.254) (xy -1.817 -1.262) (xy -1.787 -1.268) (xy -1.764 -1.273) (xy -1.75 -1.277)
				(xy -1.745 -1.279) (xy -1.741 -1.285) (xy -1.733 -1.3) (xy -1.722 -1.322) (xy -1.709 -1.35) (xy -1.694 -1.382)
				(xy -1.677 -1.419) (xy -1.66 -1.458) (xy -1.642 -1.498) (xy -1.625 -1.539) (xy -1.608 -1.58) (xy -1.592 -1.618)
				(xy -1.578 -1.653) (xy -1.565 -1.684) (xy -1.556 -1.709) (xy -1.549 -1.729) (xy -1.546 -1.74) (xy -1.546 -1.742)
				(xy -1.549 -1.749) (xy -1.558 -1.763) (xy -1.571 -1.784) (xy -1.588 -1.811) (xy -1.61 -1.843) (xy -1.634 -1.88)
				(xy -1.661 -1.92) (xy -1.691 -1.963) (xy -1.722 -2.008) (xy -1.762 -2.067) (xy -1.796 -2.117) (xy -1.825 -2.16)
				(xy -1.848 -2.196) (xy -1.867 -2.225) (xy -1.881 -2.247) (xy -1.89 -2.262) (xy -1.895 -2.272) (xy -1.895 -2.275)
				(xy -1.894 -2.279) (xy -1.891 -2.285) (xy -1.884 -2.293) (xy -1.875 -2.305) (xy -1.861 -2.32) (xy -1.843 -2.339)
				(xy -1.82 -2.363) (xy -1.792 -2.392) (xy -1.758 -2.426) (xy -1.718 -2.466) (xy -1.676 -2.509) (xy -1.627 -2.557)
				(xy -1.585 -2.599) (xy -1.549 -2.634) (xy -1.52 -2.663) (xy -1.495 -2.686) (xy -1.476 -2.704) (xy -1.462 -2.716)
				(xy -1.452 -2.724) (xy -1.446 -2.728) (xy -1.444 -2.728) (xy -1.437 -2.726) (xy -1.423 -2.717) (xy -1.401 -2.703)
				(xy -1.372 -2.685) (xy -1.337 -2.661) (xy -1.295 -2.634) (xy -1.248 -2.602) (xy -1.196 -2.566) (xy -1.173 -2.551)
				(xy -1.118 -2.513) (xy -1.071 -2.481) (xy -1.031 -2.454) (xy -0.998 -2.432) (xy -0.97 -2.413) (xy -0.948 -2.399)
				(xy -0.931 -2.389) (xy -0.917 -2.381) (xy -0.907 -2.376) (xy -0.901 -2.373) (xy -0.897 -2.373) (xy -0.888 -2.375)
				(xy -0.87 -2.38) (xy -0.845 -2.39) (xy -0.813 -2.402) (xy -0.774 -2.417) (xy -0.73 -2.434) (xy -0.681 -2.454)
				(xy -0.629 -2.475) (xy -0.586 -2.493) (xy -0.55 -2.508) (xy -0.522 -2.52) (xy -0.499 -2.529) (xy -0.482 -2.537)
				(xy -0.47 -2.543) (xy -0.461 -2.548) (xy -0.455 -2.551) (xy -0.452 -2.554) (xy -0.449 -2.557) (xy -0.448 -2.56)
				(xy -0.447 -2.566) (xy -0.443 -2.582) (xy -0.438 -2.605) (xy -0.432 -2.637) (xy -0.425 -2.674) (xy -0.417 -2.717)
				(xy -0.407 -2.765) (xy -0.398 -2.817) (xy -0.388 -2.871) (xy -0.387 -2.876) (xy -0.375 -2.94) (xy -0.364 -2.995)
				(xy -0.356 -3.042) (xy -0.348 -3.081) (xy -0.342 -3.112) (xy -0.337 -3.137) (xy -0.332 -3.157) (xy -0.328 -3.171)
				(xy -0.325 -3.181) (xy -0.323 -3.188) (xy -0.32 -3.191) (xy -0.32 -3.192) (xy -0.317 -3.194) (xy -0.313 -3.195)
				(xy -0.307 -3.197) (xy -0.298 -3.198) (xy -0.286 -3.199) (xy -0.269 -3.199) (xy -0.247 -3.2) (xy -0.219 -3.2)
				(xy -0.184 -3.201) (xy -0.142 -3.201) (xy -0.092 -3.201) (xy -0.033 -3.201) (xy -0.001 -3.201) (xy 0.063 -3.201)
			)
			(stroke
				(width 0.01)
				(type solid)
			)
			(fill solid)
			(layer "F.Mask")
		)
		(fp_rect
			(start -4.05 -4.21)
			(end 4.06 4.21)
			(stroke
				(width 0.05)
				(type default)
			)
			(fill none)
			(layer "F.CrtYd")
		)
		(fp_text user "License: Apache-2.0"
			(at -3.081 7.604 90)
			(layer "F.Fab")
			(hide yes)
			(effects
				(font
					(size 0.7 0.7)
					(thickness 0.15)
				)
				(justify left bottom)
			)
		)
		(fp_text user "${REFERENCE}"
			(at -3.081 5.204 90)
			(layer "F.Fab")
			(hide yes)
			(effects
				(font
					(size 0.7 0.7)
					(thickness 0.15)
				)
				(justify left bottom)
			)
		)
		(fp_text user "Author: Antmicro"
			(at -3.081 6.404 90)
			(layer "F.Fab")
			(hide yes)
			(effects
				(font
					(size 0.7 0.7)
					(thickness 0.15)
				)
				(justify left bottom)
			)
		)
	)
	(footprint "antmicro-footprints:R_0402_1005Metric"
		(layer "B.Cu")
		(at 114.67 130.28 90)
		(descr "Resistor SMD 0402")
		(tags "resistor SMD 0402")
		(property "Reference" "R45"
			(at -2.95 -0.38 90)
			(layer "B.SilkS")
			(effects
				(font
					(size 0.7 0.7)
					(thickness 0.15)
				)
				(justify right top mirror)
			)
		)
		(property "Value" "R_0R_0402"
			(at -1.011843 -1.772047 90)
			(layer "B.Fab")
			(effects
				(font
					(size 0.7 0.7)
					(thickness 0.15)
				)
				(justify right top mirror)
			)
		)
		(property "Footprint" "antmicro-footprints:R_0402_1005Metric"
			(at 0 0 90)
			(layer "B.Fab")
			(hide yes)
			(effects
				(font
					(size 1.27 1.27)
					(thickness 0.15)
				)
				(justify mirror)
			)
		)
		(property "Datasheet" "https://industrial.panasonic.com/cdbs/www-data/pdf/RDA0000/AOA0000C301.pdf"
			(at 0 0 90)
			(layer "B.Fab")
			(hide yes)
			(effects
				(font
					(size 1.27 1.27)
					(thickness 0.15)
				)
				(justify mirror)
			)
		)
		(property "Description" "SMD Chip Resistor, Jumper, 0 ohm, 100 mW, 0402 [1005 Metric], Thick Film, General Purpose"
			(at 0 0 90)
			(layer "B.Fab")
			(hide yes)
			(effects
				(font
					(size 1.27 1.27)
					(thickness 0.15)
				)
				(justify mirror)
			)
		)
		(property "MPN" "ERJ2GE0R00X"
			(at 0 0 -90)
			(unlocked yes)
			(layer "B.Fab")
			(hide yes)
			(effects
				(font
					(size 1 1)
					(thickness 0.15)
				)
				(justify mirror)
			)
		)
		(property "Manufacturer" "Panasonic"
			(at 0 0 -90)
			(unlocked yes)
			(layer "B.Fab")
			(hide yes)
			(effects
				(font
					(size 1 1)
					(thickness 0.15)
				)
				(justify mirror)
			)
		)
		(property "License" "Apache-2.0"
			(at 0 0 -90)
			(unlocked yes)
			(layer "B.Fab")
			(hide yes)
			(effects
				(font
					(size 1 1)
					(thickness 0.15)
				)
				(justify mirror)
			)
		)
		(property "Author" "Antmicro"
			(at 0 0 -90)
			(unlocked yes)
			(layer "B.Fab")
			(hide yes)
			(effects
				(font
					(size 1 1)
					(thickness 0.15)
				)
				(justify mirror)
			)
		)
		(property "Val" "0R"
			(at 0 0 -90)
			(unlocked yes)
			(layer "B.Fab")
			(hide yes)
			(effects
				(font
					(size 1 1)
					(thickness 0.15)
				)
				(justify mirror)
			)
		)
		(property "Tolerance" ""
			(at 0 0 -90)
			(unlocked yes)
			(layer "B.Fab")
			(hide yes)
			(effects
				(font
					(size 1 1)
					(thickness 0.15)
				)
				(justify mirror)
			)
		)
		(property "Current" "1A"
			(at 0 0 -90)
			(unlocked yes)
			(layer "B.Fab")
			(hide yes)
			(effects
				(font
					(size 1 1)
					(thickness 0.15)
				)
				(justify mirror)
			)
		)
		(property "Public" "False"
			(at 0 0 -90)
			(unlocked yes)
			(layer "B.Fab")
			(hide yes)
			(effects
				(font
					(size 1 1)
					(thickness 0.15)
				)
				(justify mirror)
			)
		)
		(sheetname "Root")
		(sheetfile "jetson-orin-baseboard-oculink-expansion.kicad_sch")
		(attr smd dnp)
		(fp_rect
			(start -0.925 0.47)
			(end 0.925 -0.47)
			(stroke
				(width 0.05)
				(type default)
			)
			(fill none)
			(layer "B.CrtYd")
		)
		(fp_rect
			(start -0.5 0.25)
			(end 0.5 -0.25)
			(stroke
				(width 0.15)
				(type solid)
			)
			(fill none)
			(layer "B.Fab")
		)
		(fp_text user "Author: Antmicro"
			(at -0.95 -4.169 90)
			(layer "B.Fab")
			(hide yes)
			(effects
				(font
					(size 0.7 0.7)
					(thickness 0.15)
				)
				(justify right top mirror)
			)
		)
		(fp_text user "${REFERENCE}"
			(at -0.95 -3.168 90)
			(layer "B.Fab")
			(hide yes)
			(effects
				(font
					(size 0.7 0.7)
					(thickness 0.15)
				)
				(justify right top mirror)
			)
		)
		(fp_text user "License: Apache-2.0"
			(at -0.95 -5.169 90)
			(layer "B.Fab")
			(hide yes)
			(effects
				(font
					(size 0.7 0.7)
					(thickness 0.15)
				)
				(justify right top mirror)
			)
		)
		(pad "1" smd roundrect
			(at -0.48 0 90)
			(size 0.59 0.64)
			(layers "B.Cu" "B.Paste" "B.Mask")
			(roundrect_rratio 0.25)
			(net 64 "/I2C_SCL")
			(pintype "passive")
		)
		(pad "2" smd roundrect
			(at 0.48 0 90)
			(size 0.59 0.64)
			(layers "B.Cu" "B.Paste" "B.Mask")
			(roundrect_rratio 0.25)
			(net 108 "Net-(U3-SCL)")
			(pintype "passive")
		)
	)
	(footprint "antmicro-footprints:C_0402_1005Metric"
		(layer "B.Cu")
		(at 119.775 127.913 -90)
		(descr "Capacitor SMD 0402")
		(tags "capacitor SMD 0402")
		(property "Reference" "C25"
			(at 1.627 -0.445 90)
			(layer "B.SilkS")
			(effects
				(font
					(size 0.7 0.7)
					(thickness 0.15)
				)
				(justify left bottom mirror)
			)
		)
		(property "Value" "C_100n_0402"
			(at -1.022927 -2.155213 90)
			(layer "B.Fab")
			(effects
				(font
					(size 0.7 0.7)
					(thickness 0.15)
				)
				(justify left bottom mirror)
			)
		)
		(property "Footprint" "antmicro-footprints:C_0402_1005Metric"
			(at 0 0 90)
			(layer "B.Fab")
			(hide yes)
			(effects
				(font
					(size 1.27 1.27)
					(thickness 0.15)
				)
				(justify mirror)
			)
		)
		(property "Datasheet" "https://www.murata.com/products/productdetail?partno=GRM155R61H104KE14%23"
			(at 0 0 90)
			(layer "B.Fab")
			(hide yes)
			(effects
				(font
					(size 1.27 1.27)
					(thickness 0.15)
				)
				(justify mirror)
			)
		)
		(property "Description" "SMD Multilayer Ceramic Capacitor, 0.1 µF, 50 V, 0402 [1005 Metric], ± 10%, X5R, GRM Series"
			(at 0 0 90)
			(layer "B.Fab")
			(hide yes)
			(effects
				(font
					(size 1.27 1.27)
					(thickness 0.15)
				)
				(justify mirror)
			)
		)
		(property "MPN" "GRM155R61H104KE14D"
			(at 0 0 90)
			(unlocked yes)
			(layer "B.Fab")
			(hide yes)
			(effects
				(font
					(size 1 1)
					(thickness 0.15)
				)
				(justify mirror)
			)
		)
		(property "Manufacturer" "Murata"
			(at 0 0 90)
			(unlocked yes)
			(layer "B.Fab")
			(hide yes)
			(effects
				(font
					(size 1 1)
					(thickness 0.15)
				)
				(justify mirror)
			)
		)
		(property "License" "Apache-2.0"
			(at 0 0 90)
			(unlocked yes)
			(layer "B.Fab")
			(hide yes)
			(effects
				(font
					(size 1 1)
					(thickness 0.15)
				)
				(justify mirror)
			)
		)
		(property "Author" "Antmicro"
			(at 0 0 90)
			(unlocked yes)
			(layer "B.Fab")
			(hide yes)
			(effects
				(font
					(size 1 1)
					(thickness 0.15)
				)
				(justify mirror)
			)
		)
		(property "Val" "100n"
			(at 0 0 90)
			(unlocked yes)
			(layer "B.Fab")
			(hide yes)
			(effects
				(font
					(size 1 1)
					(thickness 0.15)
				)
				(justify mirror)
			)
		)
		(property "Voltage" "50V"
			(at 0 0 90)
			(unlocked yes)
			(layer "B.Fab")
			(hide yes)
			(effects
				(font
					(size 1 1)
					(thickness 0.15)
				)
				(justify mirror)
			)
		)
		(property "Dielectric" "X5R"
			(at 0 0 90)
			(unlocked yes)
			(layer "B.Fab")
			(hide yes)
			(effects
				(font
					(size 1 1)
					(thickness 0.15)
				)
				(justify mirror)
			)
		)
		(property "Public" "False"
			(at 0 0 90)
			(unlocked yes)
			(layer "B.Fab")
			(hide yes)
			(effects
				(font
					(size 1 1)
					(thickness 0.15)
				)
				(justify mirror)
			)
		)
		(sheetname "Root")
		(sheetfile "jetson-orin-baseboard-oculink-expansion.kicad_sch")
		(attr smd)
		(fp_rect
			(start -0.925 0.47)
			(end 0.925 -0.47)
			(stroke
				(width 0.05)
				(type default)
			)
			(fill none)
			(layer "B.CrtYd")
		)
		(fp_line
			(start -0.494 0.25)
			(end -0.494 -0.248)
			(stroke
				(width 0.15)
				(type solid)
			)
			(layer "B.Fab")
		)
		(fp_line
			(start 0.504 0.25)
			(end -0.494 0.25)
			(stroke
				(width 0.15)
				(type solid)
			)
			(layer "B.Fab")
		)
		(fp_line
			(start -0.494 -0.248)
			(end 0.504 -0.248)
			(stroke
				(width 0.15)
				(type solid)
			)
			(layer "B.Fab")
		)
		(fp_line
			(start 0.504 -0.248)
			(end 0.504 0.25)
			(stroke
				(width 0.15)
				(type solid)
			)
			(layer "B.Fab")
		)
		(fp_text user "Author: Antmicro"
			(at -0.939 -3.399 90)
			(layer "B.Fab")
			(hide yes)
			(effects
				(font
					(size 0.7 0.7)
					(thickness 0.15)
				)
				(justify left bottom mirror)
			)
		)
		(fp_text user "${REFERENCE}"
			(at -0.939 -4.599 90)
			(layer "B.Fab")
			(hide yes)
			(effects
				(font
					(size 0.7 0.7)
					(thickness 0.15)
				)
				(justify left bottom mirror)
			)
		)
		(fp_text user "License: Apache-2.0"
			(at -0.939 -5.799 90)
			(layer "B.Fab")
			(hide yes)
			(effects
				(font
					(size 0.7 0.7)
					(thickness 0.15)
				)
				(justify left bottom mirror)
			)
		)
		(pad "1" smd roundrect
			(at -0.48 0 270)
			(size 0.59 0.64)
			(layers "B.Cu" "B.Paste" "B.Mask")
			(roundrect_rratio 0.25)
			(net 51 "GND")
			(pintype "passive")
		)
		(pad "2" smd roundrect
			(at 0.48 0 270)
			(size 0.59 0.64)
			(layers "B.Cu" "B.Paste" "B.Mask")
			(roundrect_rratio 0.25)
			(net 23 "+3V3")
			(pintype "passive")
		)
	)
	(footprint "antmicro-footprints:R_0402_1005Metric"
		(layer "B.Cu")
		(at 115.776 126.834)
		(descr "Resistor SMD 0402")
		(tags "resistor SMD 0402")
		(property "Reference" "R40"
			(at -2.936 -0.364 0)
			(layer "B.SilkS")
			(effects
				(font
					(size 0.7 0.7)
					(thickness 0.15)
				)
				(justify right top mirror)
			)
		)
		(property "Value" "R_10k_0402"
			(at -1.011843 -1.772047 0)
			(layer "B.Fab")
			(effects
				(font
					(size 0.7 0.7)
					(thickness 0.15)
				)
				(justify right top mirror)
			)
		)
		(property "Footprint" "antmicro-footprints:R_0402_1005Metric"
			(at 0 0 0)
			(layer "B.Fab")
			(hide yes)
			(effects
				(font
					(size 1.27 1.27)
					(thickness 0.15)
				)
				(justify mirror)
			)
		)
		(property "Datasheet" "https://www.bourns.com/docs/product-datasheets/cr.pdf"
			(at 0 0 0)
			(layer "B.Fab")
			(hide yes)
			(effects
				(font
					(size 1.27 1.27)
					(thickness 0.15)
				)
				(justify mirror)
			)
		)
		(property "Description" "SMD Chip Resistor, 10 kohm, ± 1%, 62.5 mW, 0402 [1005 Metric], Thick Film, General Purpose"
			(at 0 0 0)
			(layer "B.Fab")
			(hide yes)
			(effects
				(font
					(size 1.27 1.27)
					(thickness 0.15)
				)
				(justify mirror)
			)
		)
		(property "MPN" "CR0402-FX-1002GLF"
			(at 0 0 180)
			(unlocked yes)
			(layer "B.Fab")
			(hide yes)
			(effects
				(font
					(size 1 1)
					(thickness 0.15)
				)
				(justify mirror)
			)
		)
		(property "Manufacturer" "Bourns"
			(at 0 0 180)
			(unlocked yes)
			(layer "B.Fab")
			(hide yes)
			(effects
				(font
					(size 1 1)
					(thickness 0.15)
				)
				(justify mirror)
			)
		)
		(property "License" "Apache-2.0"
			(at 0 0 180)
			(unlocked yes)
			(layer "B.Fab")
			(hide yes)
			(effects
				(font
					(size 1 1)
					(thickness 0.15)
				)
				(justify mirror)
			)
		)
		(property "Author" "Antmicro"
			(at 0 0 180)
			(unlocked yes)
			(layer "B.Fab")
			(hide yes)
			(effects
				(font
					(size 1 1)
					(thickness 0.15)
				)
				(justify mirror)
			)
		)
		(property "Val" "10k"
			(at 0 0 180)
			(unlocked yes)
			(layer "B.Fab")
			(hide yes)
			(effects
				(font
					(size 1 1)
					(thickness 0.15)
				)
				(justify mirror)
			)
		)
		(property "Tolerance" "1%"
			(at 0 0 180)
			(unlocked yes)
			(layer "B.Fab")
			(hide yes)
			(effects
				(font
					(size 1 1)
					(thickness 0.15)
				)
				(justify mirror)
			)
		)
		(sheetname "Root")
		(sheetfile "jetson-orin-baseboard-oculink-expansion.kicad_sch")
		(attr smd)
		(fp_rect
			(start -0.925 0.47)
			(end 0.925 -0.47)
			(stroke
				(width 0.05)
				(type default)
			)
			(fill none)
			(layer "B.CrtYd")
		)
		(fp_rect
			(start -0.5 0.25)
			(end 0.5 -0.25)
			(stroke
				(width 0.15)
				(type solid)
			)
			(fill none)
			(layer "B.Fab")
		)
		(fp_text user "${REFERENCE}"
			(at -0.95 -3.168 0)
			(layer "B.Fab")
			(hide yes)
			(effects
				(font
					(size 0.7 0.7)
					(thickness 0.15)
				)
				(justify right top mirror)
			)
		)
		(fp_text user "License: Apache-2.0"
			(at -0.95 -5.169 0)
			(layer "B.Fab")
			(hide yes)
			(effects
				(font
					(size 0.7 0.7)
					(thickness 0.15)
				)
				(justify right top mirror)
			)
		)
		(fp_text user "Author: Antmicro"
			(at -0.95 -4.169 0)
			(layer "B.Fab")
			(hide yes)
			(effects
				(font
					(size 0.7 0.7)
					(thickness 0.15)
				)
				(justify right top mirror)
			)
		)
		(pad "1" smd roundrect
			(at -0.48 0)
			(size 0.59 0.64)
			(layers "B.Cu" "B.Paste" "B.Mask")
			(roundrect_rratio 0.25)
			(net 108 "Net-(U3-SCL)")
			(pintype "passive")
		)
		(pad "2" smd roundrect
			(at 0.48 0)
			(size 0.59 0.64)
			(layers "B.Cu" "B.Paste" "B.Mask")
			(roundrect_rratio 0.25)
			(net 23 "+3V3")
			(pintype "passive")
		)
	)
	(footprint "antmicro-footprints:R_0402_1005Metric"
		(layer "B.Cu")
		(at 127.954 123.78775)
		(descr "Resistor SMD 0402")
		(tags "resistor SMD 0402")
		(property "Reference" "R29"
			(at -3.284 -0.37775 0)
			(layer "B.SilkS")
			(effects
				(font
					(size 0.7 0.7)
					(thickness 0.15)
				)
				(justify right top mirror)
			)
		)
		(property "Value" "R_1k_0402"
			(at -1.011843 -1.772047 0)
			(layer "B.Fab")
			(effects
				(font
					(size 0.7 0.7)
					(thickness 0.15)
				)
				(justify right top mirror)
			)
		)
		(property "Footprint" "antmicro-footprints:R_0402_1005Metric"
			(at 0 0 0)
			(layer "B.Fab")
			(hide yes)
			(effects
				(font
					(size 1.27 1.27)
					(thickness 0.15)
				)
				(justify mirror)
			)
		)
		(property "Datasheet" "https://www.bourns.com/docs/product-datasheets/cr.pdf"
			(at 0 0 0)
			(layer "B.Fab")
			(hide yes)
			(effects
				(font
					(size 1.27 1.27)
					(thickness 0.15)
				)
				(justify mirror)
			)
		)
		(property "Description" "SMD Chip Resistor, 1 kohm, ± 1%, 63 mW, 0402 [1005 Metric], Thick Film, General Purpose"
			(at 0 0 0)
			(layer "B.Fab")
			(hide yes)
			(effects
				(font
					(size 1.27 1.27)
					(thickness 0.15)
				)
				(justify mirror)
			)
		)
		(property "MPN" "CR0402-FX-1001GLF"
			(at 0 0 180)
			(unlocked yes)
			(layer "B.Fab")
			(hide yes)
			(effects
				(font
					(size 1 1)
					(thickness 0.15)
				)
				(justify mirror)
			)
		)
		(property "Manufacturer" "Bourns"
			(at 0 0 180)
			(unlocked yes)
			(layer "B.Fab")
			(hide yes)
			(effects
				(font
					(size 1 1)
					(thickness 0.15)
				)
				(justify mirror)
			)
		)
		(property "License" "Apache-2.0"
			(at 0 0 180)
			(unlocked yes)
			(layer "B.Fab")
			(hide yes)
			(effects
				(font
					(size 1 1)
					(thickness 0.15)
				)
				(justify mirror)
			)
		)
		(property "Author" "Antmicro"
			(at 0 0 180)
			(unlocked yes)
			(layer "B.Fab")
			(hide yes)
			(effects
				(font
					(size 1 1)
					(thickness 0.15)
				)
				(justify mirror)
			)
		)
		(property "Val" "1k"
			(at 0 0 180)
			(unlocked yes)
			(layer "B.Fab")
			(hide yes)
			(effects
				(font
					(size 1 1)
					(thickness 0.15)
				)
				(justify mirror)
			)
		)
		(property "Tolerance" "1%"
			(at 0 0 180)
			(unlocked yes)
			(layer "B.Fab")
			(hide yes)
			(effects
				(font
					(size 1 1)
					(thickness 0.15)
				)
				(justify mirror)
			)
		)
		(property "Public" "False"
			(at 0 0 180)
			(unlocked yes)
			(layer "B.Fab")
			(hide yes)
			(effects
				(font
					(size 1 1)
					(thickness 0.15)
				)
				(justify mirror)
			)
		)
		(sheetname "Root")
		(sheetfile "jetson-orin-baseboard-oculink-expansion.kicad_sch")
		(attr smd)
		(fp_rect
			(start -0.925 0.47)
			(end 0.925 -0.47)
			(stroke
				(width 0.05)
				(type default)
			)
			(fill none)
			(layer "B.CrtYd")
		)
		(fp_rect
			(start -0.5 0.25)
			(end 0.5 -0.25)
			(stroke
				(width 0.15)
				(type solid)
			)
			(fill none)
			(layer "B.Fab")
		)
		(fp_text user "License: Apache-2.0"
			(at -0.95 -5.169 0)
			(layer "B.Fab")
			(hide yes)
			(effects
				(font
					(size 0.7 0.7)
					(thickness 0.15)
				)
				(justify right top mirror)
			)
		)
		(fp_text user "${REFERENCE}"
			(at -0.95 -3.168 0)
			(layer "B.Fab")
			(hide yes)
			(effects
				(font
					(size 0.7 0.7)
					(thickness 0.15)
				)
				(justify right top mirror)
			)
		)
		(fp_text user "Author: Antmicro"
			(at -0.95 -4.169 0)
			(layer "B.Fab")
			(hide yes)
			(effects
				(font
					(size 0.7 0.7)
					(thickness 0.15)
				)
				(justify right top mirror)
			)
		)
		(pad "1" smd roundrect
			(at -0.48 0)
			(size 0.59 0.64)
			(layers "B.Cu" "B.Paste" "B.Mask")
			(roundrect_rratio 0.25)
			(net 23 "+3V3")
			(pintype "passive")
		)
		(pad "2" smd roundrect
			(at 0.48 0)
			(size 0.59 0.64)
			(layers "B.Cu" "B.Paste" "B.Mask")
			(roundrect_rratio 0.25)
			(net 102 "/TX_SW")
			(pintype "passive")
		)
	)
	(footprint "antmicro-footprints:C_0402_1005Metric"
		(layer "B.Cu")
		(at 122.005 116.687251 -90)
		(descr "Capacitor SMD 0402")
		(tags "capacitor SMD 0402")
		(property "Reference" "C28"
			(at 1.782749 -0.445 90)
			(layer "B.SilkS")
			(effects
				(font
					(size 0.7 0.7)
					(thickness 0.15)
				)
				(justify left bottom mirror)
			)
		)
		(property "Value" "C_100n_0402"
			(at -1.022927 -2.155213 90)
			(layer "B.Fab")
			(effects
				(font
					(size 0.7 0.7)
					(thickness 0.15)
				)
				(justify left bottom mirror)
			)
		)
		(property "Footprint" "antmicro-footprints:C_0402_1005Metric"
			(at 0 0 90)
			(layer "B.Fab")
			(hide yes)
			(effects
				(font
					(size 1.27 1.27)
					(thickness 0.15)
				)
				(justify mirror)
			)
		)
		(property "Datasheet" "https://www.murata.com/products/productdetail?partno=GRM155R61H104KE14%23"
			(at 0 0 90)
			(layer "B.Fab")
			(hide yes)
			(effects
				(font
					(size 1.27 1.27)
					(thickness 0.15)
				)
				(justify mirror)
			)
		)
		(property "Description" "SMD Multilayer Ceramic Capacitor, 0.1 µF, 50 V, 0402 [1005 Metric], ± 10%, X5R, GRM Series"
			(at 0 0 90)
			(layer "B.Fab")
			(hide yes)
			(effects
				(font
					(size 1.27 1.27)
					(thickness 0.15)
				)
				(justify mirror)
			)
		)
		(property "MPN" "GRM155R61H104KE14D"
			(at 0 0 90)
			(unlocked yes)
			(layer "B.Fab")
			(hide yes)
			(effects
				(font
					(size 1 1)
					(thickness 0.15)
				)
				(justify mirror)
			)
		)
		(property "Manufacturer" "Murata"
			(at 0 0 90)
			(unlocked yes)
			(layer "B.Fab")
			(hide yes)
			(effects
				(font
					(size 1 1)
					(thickness 0.15)
				)
				(justify mirror)
			)
		)
		(property "License" "Apache-2.0"
			(at 0 0 90)
			(unlocked yes)
			(layer "B.Fab")
			(hide yes)
			(effects
				(font
					(size 1 1)
					(thickness 0.15)
				)
				(justify mirror)
			)
		)
		(property "Author" "Antmicro"
			(at 0 0 90)
			(unlocked yes)
			(layer "B.Fab")
			(hide yes)
			(effects
				(font
					(size 1 1)
					(thickness 0.15)
				)
				(justify mirror)
			)
		)
		(property "Val" "100n"
			(at 0 0 90)
			(unlocked yes)
			(layer "B.Fab")
			(hide yes)
			(effects
				(font
					(size 1 1)
					(thickness 0.15)
				)
				(justify mirror)
			)
		)
		(property "Voltage" "50V"
			(at 0 0 90)
			(unlocked yes)
			(layer "B.Fab")
			(hide yes)
			(effects
				(font
					(size 1 1)
					(thickness 0.15)
				)
				(justify mirror)
			)
		)
		(property "Dielectric" "X5R"
			(at 0 0 90)
			(unlocked yes)
			(layer "B.Fab")
			(hide yes)
			(effects
				(font
					(size 1 1)
					(thickness 0.15)
				)
				(justify mirror)
			)
		)
		(property "Public" "False"
			(at 0 0 90)
			(unlocked yes)
			(layer "B.Fab")
			(hide yes)
			(effects
				(font
					(size 1 1)
					(thickness 0.15)
				)
				(justify mirror)
			)
		)
		(sheetname "Root")
		(sheetfile "jetson-orin-baseboard-oculink-expansion.kicad_sch")
		(attr smd)
		(fp_rect
			(start -0.925 0.47)
			(end 0.925 -0.47)
			(stroke
				(width 0.05)
				(type default)
			)
			(fill none)
			(layer "B.CrtYd")
		)
		(fp_line
			(start -0.494 0.25)
			(end -0.494 -0.248)
			(stroke
				(width 0.15)
				(type solid)
			)
			(layer "B.Fab")
		)
		(fp_line
			(start 0.504 0.25)
			(end -0.494 0.25)
			(stroke
				(width 0.15)
				(type solid)
			)
			(layer "B.Fab")
		)
		(fp_line
			(start -0.494 -0.248)
			(end 0.504 -0.248)
			(stroke
				(width 0.15)
				(type solid)
			)
			(layer "B.Fab")
		)
		(fp_line
			(start 0.504 -0.248)
			(end 0.504 0.25)
			(stroke
				(width 0.15)
				(type solid)
			)
			(layer "B.Fab")
		)
		(fp_text user "${REFERENCE}"
			(at -0.939 -4.599 90)
			(layer "B.Fab")
			(hide yes)
			(effects
				(font
					(size 0.7 0.7)
					(thickness 0.15)
				)
				(justify left bottom mirror)
			)
		)
		(fp_text user "License: Apache-2.0"
			(at -0.939 -5.799 90)
			(layer "B.Fab")
			(hide yes)
			(effects
				(font
					(size 0.7 0.7)
					(thickness 0.15)
				)
				(justify left bottom mirror)
			)
		)
		(fp_text user "Author: Antmicro"
			(at -0.939 -3.399 90)
			(layer "B.Fab")
			(hide yes)
			(effects
				(font
					(size 0.7 0.7)
					(thickness 0.15)
				)
				(justify left bottom mirror)
			)
		)
		(pad "1" smd roundrect
			(at -0.48 0 270)
			(size 0.59 0.64)
			(layers "B.Cu" "B.Paste" "B.Mask")
			(roundrect_rratio 0.25)
			(net 51 "GND")
			(pintype "passive")
		)
		(pad "2" smd roundrect
			(at 0.48 0 270)
			(size 0.59 0.64)
			(layers "B.Cu" "B.Paste" "B.Mask")
			(roundrect_rratio 0.25)
			(net 23 "+3V3")
			(pintype "passive")
		)
	)
	(footprint "antmicro-footprints:R_0402_1005Metric"
		(layer "B.Cu")
		(at 127.945 130.88775)
		(descr "Resistor SMD 0402")
		(tags "resistor SMD 0402")
		(property "Reference" "R25"
			(at -3.275 -0.37775 0)
			(layer "B.SilkS")
			(effects
				(font
					(size 0.7 0.7)
					(thickness 0.15)
				)
				(justify right top mirror)
			)
		)
		(property "Value" "R_1k_0402"
			(at -1.011843 -1.772047 0)
			(layer "B.Fab")
			(effects
				(font
					(size 0.7 0.7)
					(thickness 0.15)
				)
				(justify right top mirror)
			)
		)
		(property "Footprint" "antmicro-footprints:R_0402_1005Metric"
			(at 0 0 0)
			(layer "B.Fab")
			(hide yes)
			(effects
				(font
					(size 1.27 1.27)
					(thickness 0.15)
				)
				(justify mirror)
			)
		)
		(property "Datasheet" "https://www.bourns.com/docs/product-datasheets/cr.pdf"
			(at 0 0 0)
			(layer "B.Fab")
			(hide yes)
			(effects
				(font
					(size 1.27 1.27)
					(thickness 0.15)
				)
				(justify mirror)
			)
		)
		(property "Description" "SMD Chip Resistor, 1 kohm, ± 1%, 63 mW, 0402 [1005 Metric], Thick Film, General Purpose"
			(at 0 0 0)
			(layer "B.Fab")
			(hide yes)
			(effects
				(font
					(size 1.27 1.27)
					(thickness 0.15)
				)
				(justify mirror)
			)
		)
		(property "MPN" "CR0402-FX-1001GLF"
			(at 0 0 180)
			(unlocked yes)
			(layer "B.Fab")
			(hide yes)
			(effects
				(font
					(size 1 1)
					(thickness 0.15)
				)
				(justify mirror)
			)
		)
		(property "Manufacturer" "Bourns"
			(at 0 0 180)
			(unlocked yes)
			(layer "B.Fab")
			(hide yes)
			(effects
				(font
					(size 1 1)
					(thickness 0.15)
				)
				(justify mirror)
			)
		)
		(property "License" "Apache-2.0"
			(at 0 0 180)
			(unlocked yes)
			(layer "B.Fab")
			(hide yes)
			(effects
				(font
					(size 1 1)
					(thickness 0.15)
				)
				(justify mirror)
			)
		)
		(property "Author" "Antmicro"
			(at 0 0 180)
			(unlocked yes)
			(layer "B.Fab")
			(hide yes)
			(effects
				(font
					(size 1 1)
					(thickness 0.15)
				)
				(justify mirror)
			)
		)
		(property "Val" "1k"
			(at 0 0 180)
			(unlocked yes)
			(layer "B.Fab")
			(hide yes)
			(effects
				(font
					(size 1 1)
					(thickness 0.15)
				)
				(justify mirror)
			)
		)
		(property "Tolerance" "1%"
			(at 0 0 180)
			(unlocked yes)
			(layer "B.Fab")
			(hide yes)
			(effects
				(font
					(size 1 1)
					(thickness 0.15)
				)
				(justify mirror)
			)
		)
		(property "Public" "False"
			(at 0 0 180)
			(unlocked yes)
			(layer "B.Fab")
			(hide yes)
			(effects
				(font
					(size 1 1)
					(thickness 0.15)
				)
				(justify mirror)
			)
		)
		(sheetname "Root")
		(sheetfile "jetson-orin-baseboard-oculink-expansion.kicad_sch")
		(attr smd dnp)
		(fp_rect
			(start -0.925 0.47)
			(end 0.925 -0.47)
			(stroke
				(width 0.05)
				(type default)
			)
			(fill none)
			(layer "B.CrtYd")
		)
		(fp_rect
			(start -0.5 0.25)
			(end 0.5 -0.25)
			(stroke
				(width 0.15)
				(type solid)
			)
			(fill none)
			(layer "B.Fab")
		)
		(fp_text user "Author: Antmicro"
			(at -0.95 -4.169 0)
			(layer "B.Fab")
			(hide yes)
			(effects
				(font
					(size 0.7 0.7)
					(thickness 0.15)
				)
				(justify right top mirror)
			)
		)
		(fp_text user "License: Apache-2.0"
			(at -0.95 -5.169 0)
			(layer "B.Fab")
			(hide yes)
			(effects
				(font
					(size 0.7 0.7)
					(thickness 0.15)
				)
				(justify right top mirror)
			)
		)
		(fp_text user "${REFERENCE}"
			(at -0.95 -3.168 0)
			(layer "B.Fab")
			(hide yes)
			(effects
				(font
					(size 0.7 0.7)
					(thickness 0.15)
				)
				(justify right top mirror)
			)
		)
		(pad "1" smd roundrect
			(at -0.48 0)
			(size 0.59 0.64)
			(layers "B.Cu" "B.Paste" "B.Mask")
			(roundrect_rratio 0.25)
			(net 23 "+3V3")
			(pintype "passive")
		)
		(pad "2" smd roundrect
			(at 0.48 0)
			(size 0.59 0.64)
			(layers "B.Cu" "B.Paste" "B.Mask")
			(roundrect_rratio 0.25)
			(net 100 "/TX_FG0")
			(pintype "passive")
		)
	)
	(footprint "antmicro-footprints:antmicro-logo_scaled_15mm"
		(layer "B.Cu")
		(at 118.795 94.22 180)
		(property "Reference" "N2"
			(at 0.1 3 0)
			(layer "B.SilkS")
			(hide yes)
			(effects
				(font
					(size 0.7 0.7)
					(thickness 0.15)
				)
				(justify left bottom mirror)
			)
		)
		(property "Value" "antmicro_logo"
			(at 0 -3.1 0)
			(layer "B.Fab")
			(hide yes)
			(effects
				(font
					(size 0.7 0.7)
					(thickness 0.15)
				)
				(justify left bottom mirror)
			)
		)
		(property "Footprint" "antmicro-footprints:antmicro-logo_scaled_15mm"
			(at 0 0 0)
			(layer "B.Fab")
			(hide yes)
			(effects
				(font
					(size 1.27 1.27)
					(thickness 0.15)
				)
				(justify mirror)
			)
		)
		(property "Description" "Mechanical part"
			(at 0 0 0)
			(layer "B.Fab")
			(hide yes)
			(effects
				(font
					(size 1.27 1.27)
					(thickness 0.15)
				)
				(justify mirror)
			)
		)
		(property "MPN" ""
			(at 0 0 0)
			(unlocked yes)
			(layer "B.Fab")
			(hide yes)
			(effects
				(font
					(size 1 1)
					(thickness 0.15)
				)
				(justify mirror)
			)
		)
		(property "Manufacturer" ""
			(at 0 0 0)
			(unlocked yes)
			(layer "B.Fab")
			(hide yes)
			(effects
				(font
					(size 1 1)
					(thickness 0.15)
				)
				(justify mirror)
			)
		)
		(property "Author" "Antmicro"
			(at 0 0 0)
			(unlocked yes)
			(layer "B.Fab")
			(hide yes)
			(effects
				(font
					(size 1 1)
					(thickness 0.15)
				)
				(justify mirror)
			)
		)
		(property "License" "Apache-2.0"
			(at 0 0 0)
			(unlocked yes)
			(layer "B.Fab")
			(hide yes)
			(effects
				(font
					(size 1 1)
					(thickness 0.15)
				)
				(justify mirror)
			)
		)
		(sheetname "Root")
		(sheetfile "jetson-orin-baseboard-oculink-expansion.kicad_sch")
		(attr exclude_from_pos_files exclude_from_bom allow_soldermask_bridges)
		(fp_poly
			(pts
				(xy 3.455 -0.778) (xy 3.172 -0.778) (xy 3.172 0.9) (xy 3.455 0.9) (xy 3.455 -0.778)
			)
			(stroke
				(width 0.001395)
				(type solid)
			)
			(fill solid)
			(layer "B.Cu")
		)
		(fp_poly
			(pts
				(xy 5.669 0.922) (xy 5.69 0.919) (xy 5.698 0.914) (xy 5.7 0.912) (xy 5.695 0.894) (xy 5.687 0.86)
				(xy 5.674 0.816) (xy 5.668 0.798) (xy 5.652 0.749) (xy 5.64 0.72) (xy 5.629 0.706) (xy 5.618 0.704)
				(xy 5.616 0.704) (xy 5.543 0.72) (xy 5.461 0.725) (xy 5.379 0.72) (xy 5.309 0.705) (xy 5.294 0.7)
				(xy 5.262 0.688) (xy 5.262 -0.778) (xy 4.978 -0.778) (xy 4.978 0.814) (xy 5.065 0.845) (xy 5.139 0.87)
				(xy 5.206 0.888) (xy 5.275 0.903) (xy 5.349 0.912) (xy 5.437 0.918) (xy 5.501 0.92) (xy 5.578 0.923)
				(xy 5.632 0.923) (xy 5.669 0.922)
			)
			(stroke
				(width 0.001395)
				(type solid)
			)
			(fill solid)
			(layer "B.Cu")
		)
		(fp_poly
			(pts
				(xy 0.142 1.349) (xy 0.144 1.317) (xy 0.146 1.27) (xy 0.147 1.21) (xy 0.147 1.139) (xy 0.147 1.13)
				(xy 0.147 0.9) (xy 0.431 0.9) (xy 0.431 0.71) (xy 0.147 0.71) (xy 0.147 -0.442) (xy 0.174 -0.493)
				(xy 0.209 -0.543) (xy 0.253 -0.572) (xy 0.311 -0.585) (xy 0.357 -0.586) (xy 0.431 -0.582) (xy 0.431 -0.674)
				(xy 0.429 -0.729) (xy 0.423 -0.763) (xy 0.416 -0.774) (xy 0.4 -0.778) (xy 0.363 -0.782) (xy 0.316 -0.785)
				(xy 0.283 -0.787) (xy 0.219 -0.787) (xy 0.171 -0.784) (xy 0.13 -0.776) (xy 0.103 -0.768) (xy 0.032 -0.733)
				(xy -0.026 -0.687) (xy -0.073 -0.621) (xy -0.088 -0.594) (xy -0.13 -0.515) (xy -0.133 0.099) (xy -0.137 0.71)
				(xy -0.325 0.71) (xy -0.325 0.9) (xy -0.136 0.9) (xy -0.136 1.276) (xy -0.001 1.319) (xy 0.051 1.335)
				(xy 0.096 1.349) (xy 0.126 1.357) (xy 0.14 1.361) (xy 0.142 1.349)
			)
			(stroke
				(width 0.001395)
				(type solid)
			)
			(fill solid)
			(layer "B.Cu")
		)
		(fp_poly
			(pts
				(xy -1.069 0.917) (xy -1.006 0.916) (xy -0.958 0.913) (xy -0.92 0.907) (xy -0.886 0.9) (xy -0.874 0.895)
				(xy -0.767 0.854) (xy -0.681 0.804) (xy -0.613 0.742) (xy -0.569 0.679) (xy -0.556 0.652) (xy -0.544 0.626)
				(xy -0.534 0.6) (xy -0.525 0.572) (xy -0.519 0.54) (xy -0.512 0.499) (xy -0.508 0.451) (xy -0.505 0.391)
				(xy -0.503 0.316) (xy -0.502 0.229) (xy -0.501 0.122) (xy -0.501 -0.003) (xy -0.501 -0.148) (xy -0.501 -0.778)
				(xy -0.786 -0.778) (xy -0.786 -0.153) (xy -0.786 -0.007) (xy -0.786 0.118) (xy -0.787 0.224) (xy -0.788 0.311)
				(xy -0.79 0.384) (xy -0.793 0.442) (xy -0.798 0.489) (xy -0.803 0.527) (xy -0.81 0.556) (xy -0.818 0.578)
				(xy -0.829 0.598) (xy -0.842 0.615) (xy -0.857 0.633) (xy -0.858 0.634) (xy -0.908 0.679) (xy -0.966 0.709)
				(xy -1.043 0.73) (xy -1.071 0.734) (xy -1.149 0.739) (xy -1.238 0.735) (xy -1.323 0.722) (xy -1.384 0.706)
				(xy -1.428 0.69) (xy -1.432 -0.043) (xy -1.434 -0.778) (xy -1.718 -0.778) (xy -1.718 0.814) (xy -1.609 0.849)
				(xy -1.533 0.873) (xy -1.47 0.891) (xy -1.41 0.904) (xy -1.351 0.912) (xy -1.283 0.916) (xy -1.2 0.918)
				(xy -1.151 0.918) (xy -1.069 0.917)
			)
			(stroke
				(width 0.001395)
				(type solid)
			)
			(fill solid)
			(layer "B.Cu")
		)
		(fp_poly
			(pts
				(xy 2.363 0.915) (xy 2.479 0.889) (xy 2.577 0.847) (xy 2.66 0.791) (xy 2.726 0.716) (xy 2.757 0.664)
				(xy 2.77 0.638) (xy 2.781 0.613) (xy 2.789 0.587) (xy 2.797 0.559) (xy 2.802 0.524) (xy 2.807 0.481)
				(xy 2.811 0.429) (xy 2.813 0.366) (xy 2.815 0.289) (xy 2.817 0.197) (xy 2.818 0.086) (xy 2.818 -0.046)
				(xy 2.818 -0.152) (xy 2.818 -0.778) (xy 2.535 -0.778) (xy 2.531 -0.124) (xy 2.527 0.528) (xy 2.494 0.589)
				(xy 2.447 0.652) (xy 2.386 0.697) (xy 2.314 0.727) (xy 2.236 0.739) (xy 2.152 0.735) (xy 2.071 0.714)
				(xy 1.991 0.677) (xy 1.935 0.634) (xy 1.884 0.59) (xy 1.884 -0.778) (xy 1.6 -0.778) (xy 1.6 -0.139)
				(xy 1.6 0.022) (xy 1.6 0.159) (xy 1.598 0.276) (xy 1.598 0.369) (xy 1.596 0.443) (xy 1.592 0.497)
				(xy 1.59 0.533) (xy 1.588 0.547) (xy 1.556 0.613) (xy 1.505 0.667) (xy 1.439 0.706) (xy 1.356 0.73)
				(xy 1.259 0.74) (xy 1.161 0.735) (xy 1.108 0.728) (xy 1.07 0.722) (xy 1.038 0.715) (xy 1.004 0.704)
				(xy 0.983 0.696) (xy 0.951 0.685) (xy 0.951 -0.778) (xy 0.68 -0.778) (xy 0.68 0.815) (xy 0.792 0.852)
				(xy 0.919 0.887) (xy 1.038 0.911) (xy 1.157 0.921) (xy 1.282 0.921) (xy 1.381 0.915) (xy 1.463 0.904)
				(xy 1.533 0.885) (xy 1.594 0.858) (xy 1.653 0.822) (xy 1.679 0.805) (xy 1.755 0.745) (xy 1.806 0.787)
				(xy 1.9 0.849) (xy 2.008 0.892) (xy 2.128 0.918) (xy 2.233 0.923) (xy 2.363 0.915)
			)
			(stroke
				(width 0.001395)
				(type solid)
			)
			(fill solid)
			(layer "B.Cu")
		)
		(fp_poly
			(pts
				(xy 6.504 0.916) (xy 6.61 0.891) (xy 6.703 0.849) (xy 6.788 0.791) (xy 6.828 0.753) (xy 6.901 0.663)
				(xy 6.961 0.555) (xy 7.006 0.43) (xy 7.034 0.288) (xy 7.044 0.197) (xy 7.049 0.031) (xy 7.041 -0.123)
				(xy 7.015 -0.266) (xy 6.977 -0.395) (xy 6.924 -0.507) (xy 6.857 -0.604) (xy 6.778 -0.684) (xy 6.73 -0.719)
				(xy 6.652 -0.757) (xy 6.559 -0.787) (xy 6.461 -0.804) (xy 6.36 -0.809) (xy 6.27 -0.801) (xy 6.153 -0.769)
				(xy 6.051 -0.717) (xy 5.961 -0.648) (xy 5.885 -0.559) (xy 5.825 -0.453) (xy 5.778 -0.329) (xy 5.753 -0.22)
				(xy 5.732 -0.06) (xy 5.728 0.068) (xy 6.01 0.068) (xy 6.015 -0.065) (xy 6.031 -0.192) (xy 6.057 -0.307)
				(xy 6.094 -0.406) (xy 6.139 -0.483) (xy 6.198 -0.545) (xy 6.267 -0.586) (xy 6.341 -0.609) (xy 6.418 -0.612)
				(xy 6.498 -0.593) (xy 6.523 -0.581) (xy 6.589 -0.539) (xy 6.644 -0.478) (xy 6.688 -0.402) (xy 6.722 -0.305)
				(xy 6.748 -0.19) (xy 6.761 -0.069) (xy 6.767 0.079) (xy 6.761 0.217) (xy 6.743 0.344) (xy 6.714 0.455)
				(xy 6.674 0.55) (xy 6.624 0.626) (xy 6.594 0.66) (xy 6.526 0.707) (xy 6.453 0.733) (xy 6.377 0.74)
				(xy 6.302 0.727) (xy 6.232 0.695) (xy 6.169 0.646) (xy 6.116 0.578) (xy 6.095 0.541) (xy 6.059 0.441)
				(xy 6.031 0.326) (xy 6.015 0.2) (xy 6.01 0.068) (xy 5.728 0.068) (xy 5.727 0.094) (xy 5.738 0.243)
				(xy 5.761 0.382) (xy 5.801 0.509) (xy 5.853 0.622) (xy 5.919 0.719) (xy 5.938 0.741) (xy 6.023 0.817)
				(xy 6.119 0.872) (xy 6.227 0.908) (xy 6.347 0.923) (xy 6.384 0.924) (xy 6.504 0.916)
			)
			(stroke
				(width 0.001395)
				(type solid)
			)
			(fill solid)
			(layer "B.Cu")
		)
		(fp_poly
			(pts
				(xy 4.406 0.922) (xy 4.483 0.914) (xy 4.527 0.906) (xy 4.571 0.892) (xy 4.62 0.875) (xy 4.664 0.855)
				(xy 4.7 0.837) (xy 4.722 0.822) (xy 4.722 0.82) (xy 4.722 0.806) (xy 4.712 0.777) (xy 4.7 0.74)
				(xy 4.684 0.703) (xy 4.671 0.673) (xy 4.66 0.656) (xy 4.658 0.654) (xy 4.642 0.658) (xy 4.613 0.67)
				(xy 4.584 0.683) (xy 4.493 0.713) (xy 4.405 0.725) (xy 4.32 0.718) (xy 4.246 0.692) (xy 4.184 0.649)
				(xy 4.128 0.583) (xy 4.078 0.5) (xy 4.036 0.403) (xy 4.019 0.346) (xy 4.006 0.277) (xy 3.996 0.19)
				(xy 3.992 0.096) (xy 3.994 -0.001) (xy 3.999 -0.092) (xy 4.011 -0.172) (xy 4.019 -0.212) (xy 4.059 -0.33)
				(xy 4.11 -0.425) (xy 4.171 -0.501) (xy 4.243 -0.557) (xy 4.248 -0.56) (xy 4.285 -0.577) (xy 4.315 -0.588)
				(xy 4.352 -0.592) (xy 4.403 -0.593) (xy 4.405 -0.593) (xy 4.459 -0.591) (xy 4.506 -0.583) (xy 4.554 -0.567)
				(xy 4.608 -0.543) (xy 4.65 -0.521) (xy 4.655 -0.524) (xy 4.663 -0.54) (xy 4.677 -0.569) (xy 4.698 -0.616)
				(xy 4.724 -0.684) (xy 4.727 -0.689) (xy 4.719 -0.702) (xy 4.695 -0.72) (xy 4.66 -0.74) (xy 4.615 -0.76)
				(xy 4.568 -0.778) (xy 4.557 -0.782) (xy 4.493 -0.796) (xy 4.416 -0.804) (xy 4.336 -0.808) (xy 4.264 -0.805)
				(xy 4.235 -0.801) (xy 4.19 -0.79) (xy 4.137 -0.771) (xy 4.086 -0.748) (xy 3.988 -0.687) (xy 3.904 -0.607)
				(xy 3.833 -0.508) (xy 3.777 -0.393) (xy 3.734 -0.258) (xy 3.721 -0.193) (xy 3.71 -0.116) (xy 3.704 -0.024)
				(xy 3.704 0.075) (xy 3.708 0.176) (xy 3.716 0.271) (xy 3.728 0.353) (xy 3.737 0.398) (xy 3.783 0.529)
				(xy 3.845 0.643) (xy 3.918 0.738) (xy 4.006 0.816) (xy 4.107 0.874) (xy 4.187 0.905) (xy 4.248 0.917)
				(xy 4.325 0.923) (xy 4.406 0.922)
			)
			(stroke
				(width 0.001395)
				(type solid)
			)
			(fill solid)
			(layer "B.Cu")
		)
		(fp_poly
			(pts
				(xy -2.526 0.916) (xy -2.452 0.902) (xy -2.367 0.875) (xy -2.298 0.843) (xy -2.238 0.801) (xy -2.21 0.774)
				(xy -2.166 0.72) (xy -2.129 0.652) (xy -2.098 0.576) (xy -2.085 0.524) (xy -2.081 0.496) (xy -2.08 0.448)
				(xy -2.077 0.38) (xy -2.076 0.294) (xy -2.074 0.194) (xy -2.073 0.078) (xy -2.073 -0.049) (xy -2.073 -0.117)
				(xy -2.073 -0.693) (xy -2.127 -0.718) (xy -2.226 -0.753) (xy -2.342 -0.782) (xy -2.465 -0.8) (xy -2.592 -0.809)
				(xy -2.713 -0.807) (xy -2.776 -0.801) (xy -2.901 -0.776) (xy -3.008 -0.735) (xy -3.097 -0.682) (xy -3.167 -0.613)
				(xy -3.218 -0.531) (xy -3.25 -0.434) (xy -3.263 -0.325) (xy -3.263 -0.27) (xy -3.262 -0.26) (xy -2.992 -0.26)
				(xy -2.988 -0.357) (xy -2.968 -0.441) (xy -2.927 -0.513) (xy -2.87 -0.567) (xy -2.794 -0.608) (xy -2.758 -0.62)
				(xy -2.711 -0.628) (xy -2.649 -0.631) (xy -2.58 -0.631) (xy -2.509 -0.627) (xy -2.445 -0.619) (xy -2.395 -0.608)
				(xy -2.388 -0.606) (xy -2.332 -0.586) (xy -2.332 0.157) (xy -2.4 0.149) (xy -2.444 0.142) (xy -2.5 0.132)
				(xy -2.558 0.118) (xy -2.577 0.114) (xy -2.698 0.076) (xy -2.798 0.03) (xy -2.875 -0.025) (xy -2.933 -0.088)
				(xy -2.972 -0.163) (xy -2.991 -0.247) (xy -2.992 -0.26) (xy -3.262 -0.26) (xy -3.247 -0.164) (xy -3.213 -0.069)
				(xy -3.155 0.015) (xy -3.124 0.05) (xy -3.052 0.105) (xy -2.961 0.157) (xy -2.852 0.204) (xy -2.73 0.243)
				(xy -2.596 0.276) (xy -2.453 0.298) (xy -2.452 0.298) (xy -2.33 0.313) (xy -2.336 0.413) (xy -2.35 0.508)
				(xy -2.377 0.584) (xy -2.419 0.643) (xy -2.476 0.686) (xy -2.552 0.714) (xy -2.588 0.722) (xy -2.685 0.731)
				(xy -2.794 0.723) (xy -2.908 0.699) (xy -3.024 0.661) (xy -3.033 0.656) (xy -3.069 0.642) (xy -3.097 0.632)
				(xy -3.106 0.631) (xy -3.113 0.644) (xy -3.125 0.672) (xy -3.138 0.707) (xy -3.153 0.745) (xy -3.163 0.778)
				(xy -3.17 0.798) (xy -3.17 0.801) (xy -3.161 0.808) (xy -3.135 0.821) (xy -3.106 0.835) (xy -3 0.873)
				(xy -2.883 0.902) (xy -2.76 0.918) (xy -2.639 0.923) (xy -2.526 0.916)
			)
			(stroke
				(width 0.001395)
				(type solid)
			)
			(fill solid)
			(layer "B.Cu")
		)
		(fp_poly
			(pts
				(xy -5.818 2.456) (xy -5.77 2.444) (xy -5.768 2.444) (xy -5.753 2.436) (xy -5.72 2.417) (xy -5.669 2.388)
				(xy -5.603 2.351) (xy -5.523 2.307) (xy -5.433 2.254) (xy -5.332 2.198) (xy -5.225 2.135) (xy -5.111 2.07)
				(xy -4.992 2.002) (xy -4.872 1.934) (xy -4.75 1.863) (xy -4.63 1.795) (xy -4.515 1.728) (xy -4.401 1.662)
				(xy -4.297 1.601) (xy -4.199 1.545) (xy -4.113 1.494) (xy -4.037 1.45) (xy -3.976 1.416) (xy -3.931 1.388)
				(xy -3.903 1.371) (xy -3.899 1.369) (xy -3.85 1.329) (xy -3.811 1.279) (xy -3.779 1.224) (xy -3.775 0.099)
				(xy -3.775 -0.117) (xy -3.775 -0.311) (xy -3.775 -0.484) (xy -3.775 -0.635) (xy -3.776 -0.764) (xy -3.778 -0.872)
				(xy -3.779 -0.956) (xy -3.782 -1.018) (xy -3.783 -1.058) (xy -3.784 -1.072) (xy -3.79 -1.09) (xy -3.794 -1.106)
				(xy -3.802 -1.122) (xy -3.81 -1.136) (xy -3.824 -1.153) (xy -3.843 -1.171) (xy -3.868 -1.191) (xy -3.9 -1.215)
				(xy -3.943 -1.245) (xy -3.995 -1.277) (xy -4.058 -1.316) (xy -4.133 -1.362) (xy -4.223 -1.415) (xy -4.327 -1.475)
				(xy -4.449 -1.546) (xy -4.587 -1.625) (xy -4.744 -1.717) (xy -4.813 -1.757) (xy -5.763 -2.306) (xy -5.853 -2.31)
				(xy -5.941 -2.314) (xy -6.289 -2.115) (xy -6.502 -1.991) (xy -6.696 -1.88) (xy -6.872 -1.779) (xy -7.029 -1.689)
				(xy -7.17 -1.608) (xy -7.295 -1.534) (xy -7.406 -1.471) (xy -7.502 -1.413) (xy -7.587 -1.364) (xy -7.659 -1.32)
				(xy -7.72 -1.284) (xy -7.77 -1.25) (xy -7.813 -1.223) (xy -7.846 -1.199) (xy -7.874 -1.179) (xy -7.893 -1.163)
				(xy -7.909 -1.147) (xy -7.92 -1.133) (xy -7.927 -1.122) (xy -7.933 -1.11) (xy -7.936 -1.098) (xy -7.939 -1.084)
				(xy -7.943 -1.072) (xy -7.946 -1.05) (xy -7.947 -1.006) (xy -7.949 -0.939) (xy -7.951 -0.849) (xy -7.951 -0.737)
				(xy -7.951 -0.603) (xy -7.952 -0.446) (xy -7.952 -0.269) (xy -7.952 -0.07) (xy -7.951 0.072) (xy -7.223 0.072)
				(xy -7.223 -0.081) (xy -7.221 -0.212) (xy -7.221 -0.324) (xy -7.22 -0.417) (xy -7.22 -0.494) (xy -7.217 -0.557)
				(xy -7.215 -0.606) (xy -7.212 -0.646) (xy -7.207 -0.675) (xy -7.201 -0.697) (xy -7.193 -0.713) (xy -7.185 -0.726)
				(xy -7.175 -0.737) (xy -7.162 -0.747) (xy -7.161 -0.748) (xy -7.145 -0.759) (xy -7.111 -0.781) (xy -7.061 -0.811)
				(xy -6.997 -0.848) (xy -6.922 -0.892) (xy -6.837 -0.942) (xy -6.745 -0.995) (xy -6.649 -1.052) (xy -6.55 -1.108)
				(xy -6.451 -1.167) (xy -6.353 -1.223) (xy -6.258 -1.276) (xy -6.17 -1.326) (xy -6.092 -1.37) (xy -6.023 -1.409)
				(xy -5.967 -1.439) (xy -5.927 -1.461) (xy -5.903 -1.473) (xy -5.901 -1.475) (xy -5.87 -1.483) (xy -5.85 -1.483)
				(xy -5.826 -1.475) (xy -5.811 -1.469) (xy -5.792 -1.459) (xy -5.754 -1.439) (xy -5.701 -1.409) (xy -5.635 -1.372)
				(xy -5.558 -1.328) (xy -5.473 -1.28) (xy -5.379 -1.227) (xy -5.282 -1.171) (xy -5.183 -1.114) (xy -5.084 -1.056)
				(xy -4.987 -0.999) (xy -4.895 -0.946) (xy -4.81 -0.897) (xy -4.734 -0.851) (xy -4.67 -0.813) (xy -4.619 -0.783)
				(xy -4.584 -0.761) (xy -4.566 -0.749) (xy -4.553 -0.738) (xy -4.544 -0.727) (xy -4.534 -0.714) (xy -4.528 -0.698)
				(xy -4.521 -0.677) (xy -4.516 -0.648) (xy -4.513 -0.609) (xy -4.51 -0.562) (xy -4.508 -0.499) (xy -4.507 -0.423)
				(xy -4.507 -0.332) (xy -4.505 -0.221) (xy -4.505 -0.091) (xy -4.505 0.059) (xy -4.505 0.072) (xy -4.505 0.228)
				(xy -4.505 0.359) (xy -4.507 0.471) (xy -4.507 0.565) (xy -4.508 0.644) (xy -4.51 0.706) (xy -4.513 0.756)
				(xy -4.518 0.796) (xy -4.523 0.825) (xy -4.529 0.847) (xy -4.537 0.864) (xy -4.547 0.877) (xy -4.558 0.887)
				(xy -4.572 0.899) (xy -4.579 0.903) (xy -4.595 0.914) (xy -4.632 0.936) (xy -4.683 0.966) (xy -4.75 1.005)
				(xy -4.83 1.053) (xy -4.92 1.105) (xy -5.02 1.162) (xy -5.127 1.224) (xy -5.215 1.275) (xy -5.342 1.349)
				(xy -5.451 1.412) (xy -5.544 1.464) (xy -5.619 1.506) (xy -5.683 1.541) (xy -5.733 1.569) (xy -5.773 1.589)
				(xy -5.802 1.603) (xy -5.826 1.613) (xy -5.843 1.617) (xy -5.858 1.621) (xy -5.862 1.621) (xy -5.874 1.619)
				(xy -5.89 1.615) (xy -5.911 1.607) (xy -5.938 1.595) (xy -5.973 1.579) (xy -6.018 1.555) (xy -6.074 1.523)
				(xy -6.144 1.484) (xy -6.228 1.438) (xy -6.329 1.379) (xy -6.446 1.313) (xy -6.528 1.264) (xy -6.64 1.2)
				(xy -6.745 1.139) (xy -6.842 1.083) (xy -6.931 1.031) (xy -7.008 0.985) (xy -7.072 0.947) (xy -7.122 0.919)
				(xy -7.154 0.899) (xy -7.167 0.889) (xy -7.178 0.879) (xy -7.188 0.869) (xy -7.196 0.856) (xy -7.202 0.839)
				(xy -7.207 0.817) (xy -7.212 0.787) (xy -7.215 0.746) (xy -7.217 0.694) (xy -7.22 0.63) (xy -7.22 0.552)
				(xy -7.221 0.455) (xy -7.221 0.341) (xy -7.223 0.205) (xy -7.223 0.072) (xy -7.951 0.072) (xy -7.951 0.099)
				(xy -7.951 0.29) (xy -7.951 0.46) (xy -7.951 0.607) (xy -7.949 0.736) (xy -7.949 0.848) (xy -7.947 0.943)
				(xy -7.946 1.023) (xy -7.944 1.089) (xy -7.941 1.143) (xy -7.938 1.188) (xy -7.934 1.222) (xy -7.93 1.248)
				(xy -7.925 1.268) (xy -7.917 1.285) (xy -7.909 1.297) (xy -7.901 1.307) (xy -7.89 1.315) (xy -7.878 1.327)
				(xy -7.874 1.331) (xy -7.858 1.341) (xy -7.824 1.363) (xy -7.773 1.393) (xy -7.705 1.434) (xy -7.624 1.484)
				(xy -7.528 1.539) (xy -7.422 1.601) (xy -7.305 1.67) (xy -7.18 1.742) (xy -7.048 1.819) (xy -6.911 1.898)
				(xy -6.896 1.907) (xy -6.736 2) (xy -6.595 2.081) (xy -6.473 2.153) (xy -6.366 2.214) (xy -6.273 2.266)
				(xy -6.196 2.311) (xy -6.13 2.347) (xy -6.076 2.376) (xy -6.031 2.4) (xy -5.995 2.419) (xy -5.967 2.432)
				(xy -5.944 2.443) (xy -5.927 2.448) (xy -5.911 2.452) (xy -5.898 2.456) (xy -5.885 2.456) (xy -5.882 2.456)
				(xy -5.818 2.456)
			)
			(stroke
				(width 0.001395)
				(type solid)
			)
			(fill solid)
			(layer "B.Cu")
		)
		(fp_poly
			(pts
				(xy -5.8 1.041) (xy -5.789 1.037) (xy -5.736 1.001) (xy -5.696 0.951) (xy -5.673 0.891) (xy -5.672 0.827)
				(xy -5.675 0.813) (xy -5.697 0.751) (xy -5.739 0.706) (xy -5.779 0.682) (xy -5.829 0.658) (xy -5.829 0.38)
				(xy -5.622 0.38) (xy -5.537 0.465) (xy -5.452 0.549) (xy -5.459 0.609) (xy -5.459 0.61) (xy -5.379 0.61)
				(xy -5.366 0.583) (xy -5.337 0.57) (xy -5.305 0.573) (xy -5.281 0.587) (xy -5.263 0.615) (xy -5.27 0.644)
				(xy -5.286 0.664) (xy -5.308 0.683) (xy -5.326 0.685) (xy -5.351 0.671) (xy -5.353 0.669) (xy -5.374 0.643)
				(xy -5.379 0.61) (xy -5.459 0.61) (xy -5.46 0.649) (xy -5.455 0.675) (xy -5.441 0.699) (xy -5.433 0.707)
				(xy -5.39 0.744) (xy -5.343 0.76) (xy -5.295 0.759) (xy -5.252 0.743) (xy -5.215 0.714) (xy -5.191 0.674)
				(xy -5.183 0.624) (xy -5.191 0.575) (xy -5.217 0.529) (xy -5.26 0.498) (xy -5.316 0.486) (xy -5.326 0.486)
				(xy -5.351 0.485) (xy -5.372 0.481) (xy -5.393 0.47) (xy -5.419 0.451) (xy -5.454 0.418) (xy -5.483 0.392)
				(xy -5.584 0.297) (xy -5.829 0.297) (xy -5.829 0.108) (xy -5.38 0.108) (xy -5.362 0.142) (xy -5.33 0.18)
				(xy -5.286 0.204) (xy -5.236 0.21) (xy -5.188 0.201) (xy -5.145 0.172) (xy -5.141 0.169) (xy -5.111 0.12)
				(xy -5.1 0.071) (xy -5.108 0.026) (xy -5.129 -0.016) (xy -5.164 -0.046) (xy -5.207 -0.065) (xy -5.255 -0.068)
				(xy -5.308 -0.05) (xy -5.318 -0.044) (xy -5.346 -0.024) (xy -5.364 -0.002) (xy -5.364 0.002) (xy -5.367 0.01)
				(xy -5.374 0.016) (xy -5.39 0.02) (xy -5.414 0.023) (xy -5.451 0.024) (xy -5.507 0.026) (xy -5.58 0.026)
				(xy -5.6 0.026) (xy -5.829 0.026) (xy -5.829 -0.151) (xy -5.585 -0.151) (xy -5.39 -0.348) (xy -5.334 -0.343)
				(xy -5.276 -0.347) (xy -5.229 -0.37) (xy -5.197 -0.411) (xy -5.189 -0.433) (xy -5.181 -0.489) (xy -5.196 -0.539)
				(xy -5.225 -0.577) (xy -5.27 -0.609) (xy -5.319 -0.62) (xy -5.366 -0.614) (xy -5.409 -0.591) (xy -5.439 -0.555)
				(xy -5.457 -0.506) (xy -5.459 -0.47) (xy -5.377 -0.47) (xy -5.374 -0.5) (xy -5.362 -0.518) (xy -5.335 -0.538)
				(xy -5.31 -0.537) (xy -5.286 -0.518) (xy -5.265 -0.488) (xy -5.266 -0.463) (xy -5.284 -0.441) (xy -5.313 -0.426)
				(xy -5.342 -0.429) (xy -5.366 -0.445) (xy -5.377 -0.47) (xy -5.459 -0.47) (xy -5.459 -0.46) (xy -5.451 -0.404)
				(xy -5.622 -0.234) (xy -5.829 -0.234) (xy -5.829 -0.514) (xy -5.779 -0.536) (xy -5.728 -0.57) (xy -5.693 -0.617)
				(xy -5.675 -0.674) (xy -5.67 -0.731) (xy -5.685 -0.789) (xy -5.713 -0.838) (xy -5.76 -0.878) (xy -5.77 -0.884)
				(xy -5.832 -0.904) (xy -5.898 -0.904) (xy -5.959 -0.884) (xy -5.96 -0.883) (xy -6.008 -0.845) (xy -6.04 -0.797)
				(xy -6.055 -0.74) (xy -6.055 -0.712) (xy -5.975 -0.712) (xy -5.97 -0.747) (xy -5.952 -0.776) (xy -5.936 -0.791)
				(xy -5.893 -0.818) (xy -5.85 -0.822) (xy -5.806 -0.804) (xy -5.79 -0.791) (xy -5.765 -0.761) (xy -5.753 -0.731)
				(xy -5.752 -0.712) (xy -5.763 -0.67) (xy -5.792 -0.632) (xy -5.829 -0.607) (xy -5.864 -0.6) (xy -5.906 -0.61)
				(xy -5.943 -0.638) (xy -5.967 -0.678) (xy -5.975 -0.712) (xy -6.055 -0.712) (xy -6.055 -0.682) (xy -6.037 -0.625)
				(xy -6.004 -0.576) (xy -5.957 -0.54) (xy -5.947 -0.536) (xy -5.899 -0.514) (xy -5.899 -0.234) (xy -6.106 -0.234)
				(xy -6.276 -0.404) (xy -6.269 -0.46) (xy -6.271 -0.516) (xy -6.292 -0.562) (xy -6.326 -0.596) (xy -6.369 -0.616)
				(xy -6.417 -0.62) (xy -6.465 -0.605) (xy -6.502 -0.577) (xy -6.536 -0.533) (xy -6.547 -0.482) (xy -6.544 -0.468)
				(xy -6.463 -0.468) (xy -6.46 -0.493) (xy -6.443 -0.518) (xy -6.414 -0.539) (xy -6.388 -0.537) (xy -6.366 -0.519)
				(xy -6.351 -0.487) (xy -6.356 -0.457) (xy -6.375 -0.433) (xy -6.39 -0.427) (xy -6.425 -0.429) (xy -6.443 -0.441)
				(xy -6.463 -0.468) (xy -6.544 -0.468) (xy -6.537 -0.433) (xy -6.512 -0.386) (xy -6.473 -0.355) (xy -6.419 -0.343)
				(xy -6.393 -0.343) (xy -6.338 -0.348) (xy -6.141 -0.151) (xy -5.899 -0.151) (xy -5.899 0.026) (xy -6.128 0.026)
				(xy -6.207 0.026) (xy -6.266 0.026) (xy -6.308 0.023) (xy -6.335 0.022) (xy -6.351 0.018) (xy -6.361 0.012)
				(xy -6.364 0.004) (xy -6.366 0.001) (xy -6.385 -0.025) (xy -6.419 -0.05) (xy -6.46 -0.066) (xy -6.487 -0.069)
				(xy -6.542 -0.058) (xy -6.584 -0.033) (xy -6.614 0.007) (xy -6.627 0.054) (xy -6.625 0.071) (xy -6.547 0.071)
				(xy -6.544 0.053) (xy -6.531 0.038) (xy -6.5 0.018) (xy -6.47 0.018) (xy -6.449 0.032) (xy -6.433 0.062)
				(xy -6.435 0.083) (xy -5.295 0.083) (xy -5.29 0.05) (xy -5.278 0.032) (xy -5.249 0.015) (xy -5.217 0.022)
				(xy -5.196 0.038) (xy -5.181 0.058) (xy -5.183 0.075) (xy -5.191 0.094) (xy -5.217 0.121) (xy -5.247 0.13)
				(xy -5.276 0.117) (xy -5.278 0.115) (xy -5.295 0.083) (xy -6.435 0.083) (xy -6.438 0.094) (xy -6.454 0.114)
				(xy -6.483 0.13) (xy -6.512 0.122) (xy -6.536 0.094) (xy -6.547 0.071) (xy -6.625 0.071) (xy -6.622 0.104)
				(xy -6.598 0.153) (xy -6.587 0.169) (xy -6.544 0.2) (xy -6.495 0.211) (xy -6.444 0.204) (xy -6.399 0.18)
				(xy -6.367 0.143) (xy -6.346 0.108) (xy -5.899 0.108) (xy -5.899 0.297) (xy -6.143 0.297) (xy -6.244 0.392)
				(xy -6.289 0.432) (xy -6.319 0.46) (xy -6.342 0.475) (xy -6.364 0.483) (xy -6.385 0.486) (xy -6.404 0.486)
				(xy -6.462 0.494) (xy -6.504 0.521) (xy -6.532 0.565) (xy -6.539 0.58) (xy -6.544 0.623) (xy -6.467 0.623)
				(xy -6.457 0.596) (xy -6.431 0.577) (xy -6.399 0.569) (xy -6.37 0.576) (xy -6.362 0.583) (xy -6.348 0.611)
				(xy -6.353 0.643) (xy -6.374 0.669) (xy -6.396 0.683) (xy -6.409 0.688) (xy -6.427 0.679) (xy -6.447 0.658)
				(xy -6.462 0.634) (xy -6.467 0.623) (xy -6.544 0.623) (xy -6.544 0.635) (xy -6.532 0.684) (xy -6.505 0.722)
				(xy -6.467 0.748) (xy -6.422 0.761) (xy -6.374 0.759) (xy -6.327 0.738) (xy -6.294 0.707) (xy -6.276 0.682)
				(xy -6.268 0.658) (xy -6.268 0.623) (xy -6.268 0.609) (xy -6.276 0.549) (xy -6.191 0.465) (xy -6.106 0.38)
				(xy -5.899 0.38) (xy -5.899 0.659) (xy -5.946 0.68) (xy -6.002 0.715) (xy -6.039 0.766) (xy -6.052 0.806)
				(xy -6.058 0.86) (xy -5.978 0.86) (xy -5.973 0.833) (xy -5.965 0.813) (xy -5.935 0.773) (xy -5.895 0.75)
				(xy -5.85 0.748) (xy -5.805 0.767) (xy -5.8 0.772) (xy -5.765 0.809) (xy -5.752 0.849) (xy -5.762 0.892)
				(xy -5.79 0.938) (xy -5.829 0.962) (xy -5.87 0.968) (xy -5.912 0.956) (xy -5.949 0.926) (xy -5.97 0.889)
				(xy -5.978 0.86) (xy -6.058 0.86) (xy -6.06 0.868) (xy -6.045 0.928) (xy -6.015 0.977) (xy -5.973 1.017)
				(xy -5.92 1.043) (xy -5.861 1.053) (xy -5.8 1.041)
			)
			(stroke
				(width 0.001395)
				(type solid)
			)
			(fill solid)
			(layer "B.Cu")
		)
		(fp_poly
			(pts
				(xy 3.455 -0.778) (xy 3.172 -0.778) (xy 3.172 0.9) (xy 3.455 0.9) (xy 3.455 -0.778)
			)
			(stroke
				(width 0.001395)
				(type solid)
			)
			(fill solid)
			(layer "B.Mask")
		)
		(fp_poly
			(pts
				(xy 5.669 0.922) (xy 5.69 0.919) (xy 5.698 0.914) (xy 5.7 0.912) (xy 5.695 0.894) (xy 5.687 0.86)
				(xy 5.674 0.816) (xy 5.668 0.798) (xy 5.652 0.749) (xy 5.64 0.72) (xy 5.629 0.706) (xy 5.618 0.704)
				(xy 5.616 0.704) (xy 5.543 0.72) (xy 5.461 0.725) (xy 5.379 0.72) (xy 5.309 0.705) (xy 5.294 0.7)
				(xy 5.262 0.688) (xy 5.262 -0.778) (xy 4.978 -0.778) (xy 4.978 0.814) (xy 5.065 0.845) (xy 5.139 0.87)
				(xy 5.206 0.888) (xy 5.275 0.903) (xy 5.349 0.912) (xy 5.437 0.918) (xy 5.501 0.92) (xy 5.578 0.923)
				(xy 5.632 0.923) (xy 5.669 0.922)
			)
			(stroke
				(width 0.001395)
				(type solid)
			)
			(fill solid)
			(layer "B.Mask")
		)
		(fp_poly
			(pts
				(xy 0.142 1.349) (xy 0.144 1.317) (xy 0.146 1.27) (xy 0.147 1.21) (xy 0.147 1.139) (xy 0.147 1.13)
				(xy 0.147 0.9) (xy 0.431 0.9) (xy 0.431 0.71) (xy 0.147 0.71) (xy 0.147 -0.442) (xy 0.174 -0.493)
				(xy 0.209 -0.543) (xy 0.253 -0.572) (xy 0.311 -0.585) (xy 0.357 -0.586) (xy 0.431 -0.582) (xy 0.431 -0.674)
				(xy 0.429 -0.729) (xy 0.423 -0.763) (xy 0.416 -0.774) (xy 0.4 -0.778) (xy 0.363 -0.782) (xy 0.316 -0.785)
				(xy 0.283 -0.787) (xy 0.219 -0.787) (xy 0.171 -0.784) (xy 0.13 -0.776) (xy 0.103 -0.768) (xy 0.032 -0.733)
				(xy -0.026 -0.687) (xy -0.073 -0.621) (xy -0.088 -0.594) (xy -0.13 -0.515) (xy -0.133 0.099) (xy -0.137 0.71)
				(xy -0.325 0.71) (xy -0.325 0.9) (xy -0.136 0.9) (xy -0.136 1.276) (xy -0.001 1.319) (xy 0.051 1.335)
				(xy 0.096 1.349) (xy 0.126 1.357) (xy 0.14 1.361) (xy 0.142 1.349)
			)
			(stroke
				(width 0.001395)
				(type solid)
			)
			(fill solid)
			(layer "B.Mask")
		)
		(fp_poly
			(pts
				(xy -1.069 0.917) (xy -1.006 0.916) (xy -0.958 0.913) (xy -0.92 0.907) (xy -0.886 0.9) (xy -0.874 0.895)
				(xy -0.767 0.854) (xy -0.681 0.804) (xy -0.613 0.742) (xy -0.569 0.679) (xy -0.556 0.652) (xy -0.544 0.626)
				(xy -0.534 0.6) (xy -0.525 0.572) (xy -0.519 0.54) (xy -0.512 0.499) (xy -0.508 0.451) (xy -0.505 0.391)
				(xy -0.503 0.316) (xy -0.502 0.229) (xy -0.501 0.122) (xy -0.501 -0.003) (xy -0.501 -0.148) (xy -0.501 -0.778)
				(xy -0.786 -0.778) (xy -0.786 -0.153) (xy -0.786 -0.007) (xy -0.786 0.118) (xy -0.787 0.224) (xy -0.788 0.311)
				(xy -0.79 0.384) (xy -0.793 0.442) (xy -0.798 0.489) (xy -0.803 0.527) (xy -0.81 0.556) (xy -0.818 0.578)
				(xy -0.829 0.598) (xy -0.842 0.615) (xy -0.857 0.633) (xy -0.858 0.634) (xy -0.908 0.679) (xy -0.966 0.709)
				(xy -1.043 0.73) (xy -1.071 0.734) (xy -1.149 0.739) (xy -1.238 0.735) (xy -1.323 0.722) (xy -1.384 0.706)
				(xy -1.428 0.69) (xy -1.432 -0.043) (xy -1.434 -0.778) (xy -1.718 -0.778) (xy -1.718 0.814) (xy -1.609 0.849)
				(xy -1.533 0.873) (xy -1.47 0.891) (xy -1.41 0.904) (xy -1.351 0.912) (xy -1.283 0.916) (xy -1.2 0.918)
				(xy -1.151 0.918) (xy -1.069 0.917)
			)
			(stroke
				(width 0.001395)
				(type solid)
			)
			(fill solid)
			(layer "B.Mask")
		)
		(fp_poly
			(pts
				(xy 2.363 0.915) (xy 2.479 0.889) (xy 2.577 0.847) (xy 2.66 0.791) (xy 2.726 0.716) (xy 2.757 0.664)
				(xy 2.77 0.638) (xy 2.781 0.613) (xy 2.789 0.587) (xy 2.797 0.559) (xy 2.802 0.524) (xy 2.807 0.481)
				(xy 2.811 0.429) (xy 2.813 0.366) (xy 2.815 0.289) (xy 2.817 0.197) (xy 2.818 0.086) (xy 2.818 -0.046)
				(xy 2.818 -0.152) (xy 2.818 -0.778) (xy 2.535 -0.778) (xy 2.531 -0.124) (xy 2.527 0.528) (xy 2.494 0.589)
				(xy 2.447 0.652) (xy 2.386 0.697) (xy 2.314 0.727) (xy 2.236 0.739) (xy 2.152 0.735) (xy 2.071 0.714)
				(xy 1.991 0.677) (xy 1.935 0.634) (xy 1.884 0.59) (xy 1.884 -0.778) (xy 1.6 -0.778) (xy 1.6 -0.139)
				(xy 1.6 0.022) (xy 1.6 0.159) (xy 1.598 0.276) (xy 1.598 0.369) (xy 1.596 0.443) (xy 1.592 0.497)
				(xy 1.59 0.533) (xy 1.588 0.547) (xy 1.556 0.613) (xy 1.505 0.667) (xy 1.439 0.706) (xy 1.356 0.73)
				(xy 1.259 0.74) (xy 1.161 0.735) (xy 1.108 0.728) (xy 1.07 0.722) (xy 1.038 0.715) (xy 1.004 0.704)
				(xy 0.983 0.696) (xy 0.951 0.685) (xy 0.951 -0.778) (xy 0.68 -0.778) (xy 0.68 0.815) (xy 0.792 0.852)
				(xy 0.919 0.887) (xy 1.038 0.911) (xy 1.157 0.921) (xy 1.282 0.921) (xy 1.381 0.915) (xy 1.463 0.904)
				(xy 1.533 0.885) (xy 1.594 0.858) (xy 1.653 0.822) (xy 1.679 0.805) (xy 1.755 0.745) (xy 1.806 0.787)
				(xy 1.9 0.849) (xy 2.008 0.892) (xy 2.128 0.918) (xy 2.233 0.923) (xy 2.363 0.915)
			)
			(stroke
				(width 0.001395)
				(type solid)
			)
			(fill solid)
			(layer "B.Mask")
		)
		(fp_poly
			(pts
				(xy 6.504 0.916) (xy 6.61 0.891) (xy 6.703 0.849) (xy 6.788 0.791) (xy 6.828 0.753) (xy 6.901 0.663)
				(xy 6.961 0.555) (xy 7.006 0.43) (xy 7.034 0.288) (xy 7.044 0.197) (xy 7.049 0.031) (xy 7.041 -0.123)
				(xy 7.015 -0.266) (xy 6.977 -0.395) (xy 6.924 -0.507) (xy 6.857 -0.604) (xy 6.778 -0.684) (xy 6.73 -0.719)
				(xy 6.652 -0.757) (xy 6.559 -0.787) (xy 6.461 -0.804) (xy 6.36 -0.809) (xy 6.27 -0.801) (xy 6.153 -0.769)
				(xy 6.051 -0.717) (xy 5.961 -0.648) (xy 5.885 -0.559) (xy 5.825 -0.453) (xy 5.778 -0.329) (xy 5.753 -0.22)
				(xy 5.732 -0.06) (xy 5.728 0.068) (xy 6.01 0.068) (xy 6.015 -0.065) (xy 6.031 -0.192) (xy 6.057 -0.307)
				(xy 6.094 -0.406) (xy 6.139 -0.483) (xy 6.198 -0.545) (xy 6.267 -0.586) (xy 6.341 -0.609) (xy 6.418 -0.612)
				(xy 6.498 -0.593) (xy 6.523 -0.581) (xy 6.589 -0.539) (xy 6.644 -0.478) (xy 6.688 -0.402) (xy 6.722 -0.305)
				(xy 6.748 -0.19) (xy 6.761 -0.069) (xy 6.767 0.079) (xy 6.761 0.217) (xy 6.743 0.344) (xy 6.714 0.455)
				(xy 6.674 0.55) (xy 6.624 0.626) (xy 6.594 0.66) (xy 6.526 0.707) (xy 6.453 0.733) (xy 6.377 0.74)
				(xy 6.302 0.727) (xy 6.232 0.695) (xy 6.169 0.646) (xy 6.116 0.578) (xy 6.095 0.541) (xy 6.059 0.441)
				(xy 6.031 0.326) (xy 6.015 0.2) (xy 6.01 0.068) (xy 5.728 0.068) (xy 5.727 0.094) (xy 5.738 0.243)
				(xy 5.761 0.382) (xy 5.801 0.509) (xy 5.853 0.622) (xy 5.919 0.719) (xy 5.938 0.741) (xy 6.023 0.817)
				(xy 6.119 0.872) (xy 6.227 0.908) (xy 6.347 0.923) (xy 6.384 0.924) (xy 6.504 0.916)
			)
			(stroke
				(width 0.001395)
				(type solid)
			)
			(fill solid)
			(layer "B.Mask")
		)
		(fp_poly
			(pts
				(xy 4.406 0.922) (xy 4.483 0.914) (xy 4.527 0.906) (xy 4.571 0.892) (xy 4.62 0.875) (xy 4.664 0.855)
				(xy 4.7 0.837) (xy 4.722 0.822) (xy 4.722 0.82) (xy 4.722 0.806) (xy 4.712 0.777) (xy 4.7 0.74)
				(xy 4.684 0.703) (xy 4.671 0.673) (xy 4.66 0.656) (xy 4.658 0.654) (xy 4.642 0.658) (xy 4.613 0.67)
				(xy 4.584 0.683) (xy 4.493 0.713) (xy 4.405 0.725) (xy 4.32 0.718) (xy 4.246 0.692) (xy 4.184 0.649)
				(xy 4.128 0.583) (xy 4.078 0.5) (xy 4.036 0.403) (xy 4.019 0.346) (xy 4.006 0.277) (xy 3.996 0.19)
				(xy 3.992 0.096) (xy 3.994 -0.001) (xy 3.999 -0.092) (xy 4.011 -0.172) (xy 4.019 -0.212) (xy 4.059 -0.33)
				(xy 4.11 -0.425) (xy 4.171 -0.501) (xy 4.243 -0.557) (xy 4.248 -0.56) (xy 4.285 -0.577) (xy 4.315 -0.588)
				(xy 4.352 -0.592) (xy 4.403 -0.593) (xy 4.405 -0.593) (xy 4.459 -0.591) (xy 4.506 -0.583) (xy 4.554 -0.567)
				(xy 4.608 -0.543) (xy 4.65 -0.521) (xy 4.655 -0.524) (xy 4.663 -0.54) (xy 4.677 -0.569) (xy 4.698 -0.616)
				(xy 4.724 -0.684) (xy 4.727 -0.689) (xy 4.719 -0.702) (xy 4.695 -0.72) (xy 4.66 -0.74) (xy 4.615 -0.76)
				(xy 4.568 -0.778) (xy 4.557 -0.782) (xy 4.493 -0.796) (xy 4.416 -0.804) (xy 4.336 -0.808) (xy 4.264 -0.805)
				(xy 4.235 -0.801) (xy 4.19 -0.79) (xy 4.137 -0.771) (xy 4.086 -0.748) (xy 3.988 -0.687) (xy 3.904 -0.607)
				(xy 3.833 -0.508) (xy 3.777 -0.393) (xy 3.734 -0.258) (xy 3.721 -0.193) (xy 3.71 -0.116) (xy 3.704 -0.024)
				(xy 3.704 0.075) (xy 3.708 0.176) (xy 3.716 0.271) (xy 3.728 0.353) (xy 3.737 0.398) (xy 3.783 0.529)
				(xy 3.845 0.643) (xy 3.918 0.738) (xy 4.006 0.816) (xy 4.107 0.874) (xy 4.187 0.905) (xy 4.248 0.917)
				(xy 4.325 0.923) (xy 4.406 0.922)
			)
			(stroke
				(width 0.001395)
				(type solid)
			)
			(fill solid)
			(layer "B.Mask")
		)
		(fp_poly
			(pts
				(xy -2.526 0.916) (xy -2.452 0.902) (xy -2.367 0.875) (xy -2.298 0.843) (xy -2.238 0.801) (xy -2.21 0.774)
				(xy -2.166 0.72) (xy -2.129 0.652) (xy -2.098 0.576) (xy -2.085 0.524) (xy -2.081 0.496) (xy -2.08 0.448)
				(xy -2.077 0.38) (xy -2.076 0.294) (xy -2.074 0.194) (xy -2.073 0.078) (xy -2.073 -0.049) (xy -2.073 -0.117)
				(xy -2.073 -0.693) (xy -2.127 -0.718) (xy -2.226 -0.753) (xy -2.342 -0.782) (xy -2.465 -0.8) (xy -2.592 -0.809)
				(xy -2.713 -0.807) (xy -2.776 -0.801) (xy -2.901 -0.776) (xy -3.008 -0.735) (xy -3.097 -0.682) (xy -3.167 -0.613)
				(xy -3.218 -0.531) (xy -3.25 -0.434) (xy -3.263 -0.325) (xy -3.263 -0.27) (xy -3.262 -0.26) (xy -2.992 -0.26)
				(xy -2.988 -0.357) (xy -2.968 -0.441) (xy -2.927 -0.513) (xy -2.87 -0.567) (xy -2.794 -0.608) (xy -2.758 -0.62)
				(xy -2.711 -0.628) (xy -2.649 -0.631) (xy -2.58 -0.631) (xy -2.509 -0.627) (xy -2.445 -0.619) (xy -2.395 -0.608)
				(xy -2.388 -0.606) (xy -2.332 -0.586) (xy -2.332 0.157) (xy -2.4 0.149) (xy -2.444 0.142) (xy -2.5 0.132)
				(xy -2.558 0.118) (xy -2.577 0.114) (xy -2.698 0.076) (xy -2.798 0.03) (xy -2.875 -0.025) (xy -2.933 -0.088)
				(xy -2.972 -0.163) (xy -2.991 -0.247) (xy -2.992 -0.26) (xy -3.262 -0.26) (xy -3.247 -0.164) (xy -3.213 -0.069)
				(xy -3.155 0.015) (xy -3.124 0.05) (xy -3.052 0.105) (xy -2.961 0.157) (xy -2.852 0.204) (xy -2.73 0.243)
				(xy -2.596 0.276) (xy -2.453 0.298) (xy -2.452 0.298) (xy -2.33 0.313) (xy -2.336 0.413) (xy -2.35 0.508)
				(xy -2.377 0.584) (xy -2.419 0.643) (xy -2.476 0.686) (xy -2.552 0.714) (xy -2.588 0.722) (xy -2.685 0.731)
				(xy -2.794 0.723) (xy -2.908 0.699) (xy -3.024 0.661) (xy -3.033 0.656) (xy -3.069 0.642) (xy -3.097 0.632)
				(xy -3.106 0.631) (xy -3.113 0.644) (xy -3.125 0.672) (xy -3.138 0.707) (xy -3.153 0.745) (xy -3.163 0.778)
				(xy -3.17 0.798) (xy -3.17 0.801) (xy -3.161 0.808) (xy -3.135 0.821) (xy -3.106 0.835) (xy -3 0.873)
				(xy -2.883 0.902) (xy -2.76 0.918) (xy -2.639 0.923) (xy -2.526 0.916)
			)
			(stroke
				(width 0.001395)
				(type solid)
			)
			(fill solid)
			(layer "B.Mask")
		)
		(fp_poly
			(pts
				(xy -5.818 2.456) (xy -5.77 2.444) (xy -5.768 2.444) (xy -5.753 2.436) (xy -5.72 2.417) (xy -5.669 2.388)
				(xy -5.603 2.351) (xy -5.523 2.307) (xy -5.433 2.254) (xy -5.332 2.198) (xy -5.225 2.135) (xy -5.111 2.07)
				(xy -4.992 2.002) (xy -4.872 1.934) (xy -4.75 1.863) (xy -4.63 1.795) (xy -4.515 1.728) (xy -4.401 1.662)
				(xy -4.297 1.601) (xy -4.199 1.545) (xy -4.113 1.494) (xy -4.037 1.45) (xy -3.976 1.416) (xy -3.931 1.388)
				(xy -3.903 1.371) (xy -3.899 1.369) (xy -3.85 1.329) (xy -3.811 1.279) (xy -3.779 1.224) (xy -3.775 0.099)
				(xy -3.775 -0.117) (xy -3.775 -0.311) (xy -3.775 -0.484) (xy -3.775 -0.635) (xy -3.776 -0.764) (xy -3.778 -0.872)
				(xy -3.779 -0.956) (xy -3.782 -1.018) (xy -3.783 -1.058) (xy -3.784 -1.072) (xy -3.79 -1.09) (xy -3.794 -1.106)
				(xy -3.802 -1.122) (xy -3.81 -1.136) (xy -3.824 -1.153) (xy -3.843 -1.171) (xy -3.868 -1.191) (xy -3.9 -1.215)
				(xy -3.943 -1.245) (xy -3.995 -1.277) (xy -4.058 -1.316) (xy -4.133 -1.362) (xy -4.223 -1.415) (xy -4.327 -1.475)
				(xy -4.449 -1.546) (xy -4.587 -1.625) (xy -4.744 -1.717) (xy -4.813 -1.757) (xy -5.763 -2.306) (xy -5.853 -2.31)
				(xy -5.941 -2.314) (xy -6.289 -2.115) (xy -6.502 -1.991) (xy -6.696 -1.88) (xy -6.872 -1.779) (xy -7.029 -1.689)
				(xy -7.17 -1.608) (xy -7.295 -1.534) (xy -7.406 -1.471) (xy -7.502 -1.413) (xy -7.587 -1.364) (xy -7.659 -1.32)
				(xy -7.72 -1.284) (xy -7.77 -1.25) (xy -7.813 -1.223) (xy -7.846 -1.199) (xy -7.874 -1.179) (xy -7.893 -1.163)
				(xy -7.909 -1.147) (xy -7.92 -1.133) (xy -7.927 -1.122) (xy -7.933 -1.11) (xy -7.936 -1.098) (xy -7.939 -1.084)
				(xy -7.943 -1.072) (xy -7.946 -1.05) (xy -7.947 -1.006) (xy -7.949 -0.939) (xy -7.951 -0.849) (xy -7.951 -0.737)
				(xy -7.951 -0.603) (xy -7.952 -0.446) (xy -7.952 -0.269) (xy -7.952 -0.07) (xy -7.951 0.072) (xy -7.223 0.072)
				(xy -7.223 -0.081) (xy -7.221 -0.212) (xy -7.221 -0.324) (xy -7.22 -0.417) (xy -7.22 -0.494) (xy -7.217 -0.557)
				(xy -7.215 -0.606) (xy -7.212 -0.646) (xy -7.207 -0.675) (xy -7.201 -0.697) (xy -7.193 -0.713) (xy -7.185 -0.726)
				(xy -7.175 -0.737) (xy -7.162 -0.747) (xy -7.161 -0.748) (xy -7.145 -0.759) (xy -7.111 -0.781) (xy -7.061 -0.811)
				(xy -6.997 -0.848) (xy -6.922 -0.892) (xy -6.837 -0.942) (xy -6.745 -0.995) (xy -6.649 -1.052) (xy -6.55 -1.108)
				(xy -6.451 -1.167) (xy -6.353 -1.223) (xy -6.258 -1.276) (xy -6.17 -1.326) (xy -6.092 -1.37) (xy -6.023 -1.409)
				(xy -5.967 -1.439) (xy -5.927 -1.461) (xy -5.903 -1.473) (xy -5.901 -1.475) (xy -5.87 -1.483) (xy -5.85 -1.483)
				(xy -5.826 -1.475) (xy -5.811 -1.469) (xy -5.792 -1.459) (xy -5.754 -1.439) (xy -5.701 -1.409) (xy -5.635 -1.372)
				(xy -5.558 -1.328) (xy -5.473 -1.28) (xy -5.379 -1.227) (xy -5.282 -1.171) (xy -5.183 -1.114) (xy -5.084 -1.056)
				(xy -4.987 -0.999) (xy -4.895 -0.946) (xy -4.81 -0.897) (xy -4.734 -0.851) (xy -4.67 -0.813) (xy -4.619 -0.783)
				(xy -4.584 -0.761) (xy -4.566 -0.749) (xy -4.553 -0.738) (xy -4.544 -0.727) (xy -4.534 -0.714) (xy -4.528 -0.698)
				(xy -4.521 -0.677) (xy -4.516 -0.648) (xy -4.513 -0.609) (xy -4.51 -0.562) (xy -4.508 -0.499) (xy -4.507 -0.423)
				(xy -4.507 -0.332) (xy -4.505 -0.221) (xy -4.505 -0.091) (xy -4.505 0.059) (xy -4.505 0.072) (xy -4.505 0.228)
				(xy -4.505 0.359) (xy -4.507 0.471) (xy -4.507 0.565) (xy -4.508 0.644) (xy -4.51 0.706) (xy -4.513 0.756)
				(xy -4.518 0.796) (xy -4.523 0.825) (xy -4.529 0.847) (xy -4.537 0.864) (xy -4.547 0.877) (xy -4.558 0.887)
				(xy -4.572 0.899) (xy -4.579 0.903) (xy -4.595 0.914) (xy -4.632 0.936) (xy -4.683 0.966) (xy -4.75 1.005)
				(xy -4.83 1.053) (xy -4.92 1.105) (xy -5.02 1.162) (xy -5.127 1.224) (xy -5.215 1.275) (xy -5.342 1.349)
				(xy -5.451 1.412) (xy -5.544 1.464) (xy -5.619 1.506) (xy -5.683 1.541) (xy -5.733 1.569) (xy -5.773 1.589)
				(xy -5.802 1.603) (xy -5.826 1.613) (xy -5.843 1.617) (xy -5.858 1.621) (xy -5.862 1.621) (xy -5.874 1.619)
				(xy -5.89 1.615) (xy -5.911 1.607) (xy -5.938 1.595) (xy -5.973 1.579) (xy -6.018 1.555) (xy -6.074 1.523)
				(xy -6.144 1.484) (xy -6.228 1.438) (xy -6.329 1.379) (xy -6.446 1.313) (xy -6.528 1.264) (xy -6.64 1.2)
				(xy -6.745 1.139) (xy -6.842 1.083) (xy -6.931 1.031) (xy -7.008 0.985) (xy -7.072 0.947) (xy -7.122 0.919)
				(xy -7.154 0.899) (xy -7.167 0.889) (xy -7.178 0.879) (xy -7.188 0.869) (xy -7.196 0.856) (xy -7.202 0.839)
				(xy -7.207 0.817) (xy -7.212 0.787) (xy -7.215 0.746) (xy -7.217 0.694) (xy -7.22 0.63) (xy -7.22 0.552)
				(xy -7.221 0.455) (xy -7.221 0.341) (xy -7.223 0.205) (xy -7.223 0.072) (xy -7.951 0.072) (xy -7.951 0.099)
				(xy -7.951 0.29) (xy -7.951 0.46) (xy -7.951 0.607) (xy -7.949 0.736) (xy -7.949 0.848) (xy -7.947 0.943)
				(xy -7.946 1.023) (xy -7.944 1.089) (xy -7.941 1.143) (xy -7.938 1.188) (xy -7.934 1.222) (xy -7.93 1.248)
				(xy -7.925 1.268) (xy -7.917 1.285) (xy -7.909 1.297) (xy -7.901 1.307) (xy -7.89 1.315) (xy -7.878 1.327)
				(xy -7.874 1.331) (xy -7.858 1.341) (xy -7.824 1.363) (xy -7.773 1.393) (xy -7.705 1.434) (xy -7.624 1.484)
				(xy -7.528 1.539) (xy -7.422 1.601) (xy -7.305 1.67) (xy -7.18 1.742) (xy -7.048 1.819) (xy -6.911 1.898)
				(xy -6.896 1.907) (xy -6.736 2) (xy -6.595 2.081) (xy -6.473 2.153) (xy -6.366 2.214) (xy -6.273 2.266)
				(xy -6.196 2.311) (xy -6.13 2.347) (xy -6.076 2.376) (xy -6.031 2.4) (xy -5.995 2.419) (xy -5.967 2.432)
				(xy -5.944 2.443) (xy -5.927 2.448) (xy -5.911 2.452) (xy -5.898 2.456) (xy -5.885 2.456) (xy -5.882 2.456)
				(xy -5.818 2.456)
			)
			(stroke
				(width 0.001395)
				(type solid)
			)
			(fill solid)
			(layer "B.Mask")
		)
		(fp_poly
			(pts
				(xy -5.8 1.041) (xy -5.789 1.037) (xy -5.736 1.001) (xy -5.696 0.951) (xy -5.673 0.891) (xy -5.672 0.827)
				(xy -5.675 0.813) (xy -5.697 0.751) (xy -5.739 0.706) (xy -5.779 0.682) (xy -5.829 0.658) (xy -5.829 0.38)
				(xy -5.622 0.38) (xy -5.537 0.465) (xy -5.452 0.549) (xy -5.459 0.609) (xy -5.459 0.61) (xy -5.379 0.61)
				(xy -5.366 0.583) (xy -5.337 0.57) (xy -5.305 0.573) (xy -5.281 0.587) (xy -5.263 0.615) (xy -5.27 0.644)
				(xy -5.286 0.664) (xy -5.308 0.683) (xy -5.326 0.685) (xy -5.351 0.671) (xy -5.353 0.669) (xy -5.374 0.643)
				(xy -5.379 0.61) (xy -5.459 0.61) (xy -5.46 0.649) (xy -5.455 0.675) (xy -5.441 0.699) (xy -5.433 0.707)
				(xy -5.39 0.744) (xy -5.343 0.76) (xy -5.295 0.759) (xy -5.252 0.743) (xy -5.215 0.714) (xy -5.191 0.674)
				(xy -5.183 0.624) (xy -5.191 0.575) (xy -5.217 0.529) (xy -5.26 0.498) (xy -5.316 0.486) (xy -5.326 0.486)
				(xy -5.351 0.485) (xy -5.372 0.481) (xy -5.393 0.47) (xy -5.419 0.451) (xy -5.454 0.418) (xy -5.483 0.392)
				(xy -5.584 0.297) (xy -5.829 0.297) (xy -5.829 0.108) (xy -5.38 0.108) (xy -5.362 0.142) (xy -5.33 0.18)
				(xy -5.286 0.204) (xy -5.236 0.21) (xy -5.188 0.201) (xy -5.145 0.172) (xy -5.141 0.169) (xy -5.111 0.12)
				(xy -5.1 0.071) (xy -5.108 0.026) (xy -5.129 -0.016) (xy -5.164 -0.046) (xy -5.207 -0.065) (xy -5.255 -0.068)
				(xy -5.308 -0.05) (xy -5.318 -0.044) (xy -5.346 -0.024) (xy -5.364 -0.002) (xy -5.364 0.002) (xy -5.367 0.01)
				(xy -5.374 0.016) (xy -5.39 0.02) (xy -5.414 0.023) (xy -5.451 0.024) (xy -5.507 0.026) (xy -5.58 0.026)
				(xy -5.6 0.026) (xy -5.829 0.026) (xy -5.829 -0.151) (xy -5.585 -0.151) (xy -5.39 -0.348) (xy -5.334 -0.343)
				(xy -5.276 -0.347) (xy -5.229 -0.37) (xy -5.197 -0.411) (xy -5.189 -0.433) (xy -5.181 -0.489) (xy -5.196 -0.539)
				(xy -5.225 -0.577) (xy -5.27 -0.609) (xy -5.319 -0.62) (xy -5.366 -0.614) (xy -5.409 -0.591) (xy -5.439 -0.555)
				(xy -5.457 -0.506) (xy -5.459 -0.47) (xy -5.377 -0.47) (xy -5.374 -0.5) (xy -5.362 -0.518) (xy -5.335 -0.538)
				(xy -5.31 -0.537) (xy -5.286 -0.518) (xy -5.265 -0.488) (xy -5.266 -0.463) (xy -5.284 -0.441) (xy -5.313 -0.426)
				(xy -5.342 -0.429) (xy -5.366 -0.445) (xy -5.377 -0.47) (xy -5.459 -0.47) (xy -5.459 -0.46) (xy -5.451 -0.404)
				(xy -5.622 -0.234) (xy -5.829 -0.234) (xy -5.829 -0.514) (xy -5.779 -0.536) (xy -5.728 -0.57) (xy -5.693 -0.617)
				(xy -5.675 -0.674) (xy -5.67 -0.731) (xy -5.685 -0.789) (xy -5.713 -0.838) (xy -5.76 -0.878) (xy -5.77 -0.884)
				(xy -5.832 -0.904) (xy -5.898 -0.904) (xy -5.959 -0.884) (xy -5.96 -0.883) (xy -6.008 -0.845) (xy -6.04 -0.797)
				(xy -6.055 -0.74) (xy -6.055 -0.712) (xy -5.975 -0.712) (xy -5.97 -0.747) (xy -5.952 -0.776) (xy -5.936 -0.791)
				(xy -5.893 -0.818) (xy -5.85 -0.822) (xy -5.806 -0.804) (xy -5.79 -0.791) (xy -5.765 -0.761) (xy -5.753 -0.731)
				(xy -5.752 -0.712) (xy -5.763 -0.67) (xy -5.792 -0.632) (xy -5.829 -0.607) (xy -5.864 -0.6) (xy -5.906 -0.61)
				(xy -5.943 -0.638) (xy -5.967 -0.678) (xy -5.975 -0.712) (xy -6.055 -0.712) (xy -6.055 -0.682) (xy -6.037 -0.625)
				(xy -6.004 -0.576) (xy -5.957 -0.54) (xy -5.947 -0.536) (xy -5.899 -0.514) (xy -5.899 -0.234) (xy -6.106 -0.234)
				(xy -6.276 -0.404) (xy -6.269 -0.46) (xy -6.271 -0.516) (xy -6.292 -0.562) (xy -6.326 -0.596) (xy -6.369 -0.616)
				(xy -6.417 -0.62) (xy -6.465 -0.605) (xy -6.502 -0.577) (xy -6.536 -0.533) (xy -6.547 -0.482) (xy -6.544 -0.468)
				(xy -6.463 -0.468) (xy -6.46 -0.493) (xy -6.443 -0.518) (xy -6.414 -0.539) (xy -6.388 -0.537) (xy -6.366 -0.519)
				(xy -6.351 -0.487) (xy -6.356 -0.457) (xy -6.375 -0.433) (xy -6.39 -0.427) (xy -6.425 -0.429) (xy -6.443 -0.441)
				(xy -6.463 -0.468) (xy -6.544 -0.468) (xy -6.537 -0.433) (xy -6.512 -0.386) (xy -6.473 -0.355) (xy -6.419 -0.343)
				(xy -6.393 -0.343) (xy -6.338 -0.348) (xy -6.141 -0.151) (xy -5.899 -0.151) (xy -5.899 0.026) (xy -6.128 0.026)
				(xy -6.207 0.026) (xy -6.266 0.026) (xy -6.308 0.023) (xy -6.335 0.022) (xy -6.351 0.018) (xy -6.361 0.012)
				(xy -6.364 0.004) (xy -6.366 0.001) (xy -6.385 -0.025) (xy -6.419 -0.05) (xy -6.46 -0.066) (xy -6.487 -0.069)
				(xy -6.542 -0.058) (xy -6.584 -0.033) (xy -6.614 0.007) (xy -6.627 0.054) (xy -6.625 0.071) (xy -6.547 0.071)
				(xy -6.544 0.053) (xy -6.531 0.038) (xy -6.5 0.018) (xy -6.47 0.018) (xy -6.449 0.032) (xy -6.433 0.062)
				(xy -6.435 0.083) (xy -5.295 0.083) (xy -5.29 0.05) (xy -5.278 0.032) (xy -5.249 0.015) (xy -5.217 0.022)
				(xy -5.196 0.038) (xy -5.181 0.058) (xy -5.183 0.075) (xy -5.191 0.094) (xy -5.217 0.121) (xy -5.247 0.13)
				(xy -5.276 0.117) (xy -5.278 0.115) (xy -5.295 0.083) (xy -6.435 0.083) (xy -6.438 0.094) (xy -6.454 0.114)
				(xy -6.483 0.13) (xy -6.512 0.122) (xy -6.536 0.094) (xy -6.547 0.071) (xy -6.625 0.071) (xy -6.622 0.104)
				(xy -6.598 0.153) (xy -6.587 0.169) (xy -6.544 0.2) (xy -6.495 0.211) (xy -6.444 0.204) (xy -6.399 0.18)
				(xy -6.367 0.143) (xy -6.346 0.108) (xy -5.899 0.108) (xy -5.899 0.297) (xy -6.143 0.297) (xy -6.244 0.392)
				(xy -6.289 0.432) (xy -6.319 0.46) (xy -6.342 0.475) (xy -6.364 0.483) (xy -6.385 0.486) (xy -6.404 0.486)
				(xy -6.462 0.494) (xy -6.504 0.521) (xy -6.532 0.565) (xy -6.539 0.58) (xy -6.544 0.623) (xy -6.467 0.623)
				(xy -6.457 0.596) (xy -6.431 0.577) (xy -6.399 0.569) (xy -6.37 0.576) (xy -6.362 0.583) (xy -6.348 0.611)
				(xy -6.353 0.643) (xy -6.374 0.669) (xy -6.396 0.683) (xy -6.409 0.688) (xy -6.427 0.679) (xy -6.447 0.658)
				(xy -6.462 0.634) (xy -6.467 0.623) (xy -6.544 0.623) (xy -6.544 0.635) (xy -6.532 0.684) (xy -6.505 0.722)
				(xy -6.467 0.748) (xy -6.422 0.761) (xy -6.374 0.759) (xy -6.327 0.738) (xy -6.294 0.707) (xy -6.276 0.682)
				(xy -6.268 0.658) (xy -6.268 0.623) (xy -6.268 0.609) (xy -6.276 0.549) (xy -6.191 0.465) (xy -6.106 0.38)
				(xy -5.899 0.38) (xy -5.899 0.659) (xy -5.946 0.68) (xy -6.002 0.715) (xy -6.039 0.766) (xy -6.052 0.806)
				(xy -6.058 0.86) (xy -5.978 0.86) (xy -5.973 0.833) (xy -5.965 0.813) (xy -5.935 0.773) (xy -5.895 0.75)
				(xy -5.85 0.748) (xy -5.805 0.767) (xy -5.8 0.772) (xy -5.765 0.809) (xy -5.752 0.849) (xy -5.762 0.892)
				(xy -5.79 0.938) (xy -5.829 0.962) (xy -5.87 0.968) (xy -5.912 0.956) (xy -5.949 0.926) (xy -5.97 0.889)
				(xy -5.978 0.86) (xy -6.058 0.86) (xy -6.06 0.868) (xy -6.045 0.928) (xy -6.015 0.977) (xy -5.973 1.017)
				(xy -5.92 1.043) (xy -5.861 1.053) (xy -5.8 1.041)
			)
			(stroke
				(width 0.001395)
				(type solid)
			)
			(fill solid)
			(layer "B.Mask")
		)
		(fp_rect
			(start -9.683 4.203)
			(end 8.773 -4.063)
			(stroke
				(width 0.05)
				(type default)
			)
			(fill none)
			(layer "B.CrtYd")
		)
		(fp_text user "License: Apache-2.0"
			(at -7.952 -13.298 0)
			(layer "B.Fab")
			(hide yes)
			(effects
				(font
					(size 0.7 0.7)
					(thickness 0.15)
				)
				(justify left bottom mirror)
			)
		)
		(fp_text user "Author: Antmicro"
			(at -7.952 -12.098 0)
			(layer "B.Fab")
			(hide yes)
			(effects
				(font
					(size 0.7 0.7)
					(thickness 0.15)
				)
				(justify left bottom mirror)
			)
		)
		(fp_text user "${REFERENCE}"
			(at -7.952 -14.498 0)
			(layer "B.Fab")
			(hide yes)
			(effects
				(font
					(size 0.7 0.7)
					(thickness 0.15)
				)
				(justify left bottom mirror)
			)
		)
	)
	(footprint "antmicro-footprints:oshw-logo"
		(layer "B.Cu")
		(at 143.945 95.042 180)
		(descr "OSHW Logo")
		(tags "OSHW Logo")
		(property "Reference" "N1"
			(at 0 4.4 0)
			(layer "B.SilkS")
			(hide yes)
			(effects
				(font
					(size 0.7 0.7)
					(thickness 0.15)
				)
				(justify left bottom mirror)
			)
		)
		(property "Value" "oshw_logo"
			(at 0 3.4 0)
			(layer "B.Fab")
			(hide yes)
			(effects
				(font
					(size 0.7 0.7)
					(thickness 0.15)
				)
				(justify left bottom mirror)
			)
		)
		(property "Footprint" "antmicro-footprints:oshw-logo"
			(at 0 0 0)
			(layer "B.Fab")
			(hide yes)
			(effects
				(font
					(size 1.27 1.27)
					(thickness 0.15)
				)
				(justify mirror)
			)
		)
		(property "Description" "Mechanical part"
			(at 0 0 0)
			(layer "B.Fab")
			(hide yes)
			(effects
				(font
					(size 1.27 1.27)
					(thickness 0.15)
				)
				(justify mirror)
			)
		)
		(property "Author" "Antmicro"
			(at 0 0 0)
			(unlocked yes)
			(layer "B.Fab")
			(hide yes)
			(effects
				(font
					(size 1 1)
					(thickness 0.15)
				)
				(justify mirror)
			)
		)
		(property "License" "Apache-2.0"
			(at 0 0 0)
			(unlocked yes)
			(layer "B.Fab")
			(hide yes)
			(effects
				(font
					(size 1 1)
					(thickness 0.15)
				)
				(justify mirror)
			)
		)
		(property "MPN" ""
			(at 0 0 0)
			(unlocked yes)
			(layer "B.Fab")
			(hide yes)
			(effects
				(font
					(size 1 1)
					(thickness 0.15)
				)
				(justify mirror)
			)
		)
		(property "Manufacturer" ""
			(at 0 0 0)
			(unlocked yes)
			(layer "B.Fab")
			(hide yes)
			(effects
				(font
					(size 1 1)
					(thickness 0.15)
				)
				(justify mirror)
			)
		)
		(sheetname "Root")
		(sheetfile "jetson-orin-baseboard-oculink-expansion.kicad_sch")
		(attr exclude_from_pos_files exclude_from_bom allow_soldermask_bridges)
		(fp_poly
			(pts
				(xy -0.843 -2.558) (xy -0.815 -2.564) (xy -0.794 -2.572) (xy -0.773 -2.581) (xy -0.759 -2.589) (xy -0.738 -2.603)
				(xy -0.783 -2.658) (xy -0.8 -2.677) (xy -0.814 -2.694) (xy -0.825 -2.706) (xy -0.831 -2.712) (xy -0.832 -2.712)
				(xy -0.837 -2.71) (xy -0.847 -2.703) (xy -0.849 -2.702) (xy -0.874 -2.69) (xy -0.904 -2.684) (xy -0.935 -2.685)
				(xy -0.942 -2.686) (xy -0.975 -2.698) (xy -1.001 -2.717) (xy -1.02 -2.741) (xy -1.034 -2.766) (xy -1.039 -3.197)
				(xy -1.164 -3.2) (xy -1.164 -2.565) (xy -1.037 -2.565) (xy -1.037 -2.626) (xy -1.009 -2.604) (xy -0.972 -2.579)
				(xy -0.931 -2.563) (xy -0.887 -2.556) (xy -0.843 -2.558)
			)
			(stroke
				(width 0.01)
				(type solid)
			)
			(fill solid)
			(layer "B.Cu")
		)
		(fp_poly
			(pts
				(xy 1.889 -1.554) (xy 1.907 -1.559) (xy 1.927 -1.566) (xy 1.948 -1.574) (xy 1.966 -1.583) (xy 1.979 -1.592)
				(xy 1.984 -1.597) (xy 1.982 -1.604) (xy 1.974 -1.616) (xy 1.962 -1.633) (xy 1.946 -1.652) (xy 1.945 -1.654)
				(xy 1.929 -1.673) (xy 1.915 -1.689) (xy 1.906 -1.7) (xy 1.901 -1.706) (xy 1.896 -1.705) (xy 1.885 -1.7)
				(xy 1.873 -1.695) (xy 1.84 -1.683) (xy 1.808 -1.68) (xy 1.776 -1.685) (xy 1.747 -1.698) (xy 1.723 -1.717)
				(xy 1.704 -1.742) (xy 1.696 -1.763) (xy 1.695 -1.772) (xy 1.694 -1.79) (xy 1.693 -1.817) (xy 1.692 -1.85)
				(xy 1.692 -1.89) (xy 1.691 -1.934) (xy 1.691 -1.983) (xy 1.691 -2.194) (xy 1.559 -2.194) (xy 1.559 -1.559)
				(xy 1.691 -1.559) (xy 1.691 -1.626) (xy 1.71 -1.607) (xy 1.739 -1.585) (xy 1.775 -1.568) (xy 1.814 -1.556)
				(xy 1.855 -1.552) (xy 1.889 -1.554)
			)
			(stroke
				(width 0.01)
				(type solid)
			)
			(fill solid)
			(layer "B.Cu")
		)
		(fp_poly
			(pts
				(xy -0.837 -1.56) (xy -0.797 -1.576) (xy -0.761 -1.6) (xy -0.73 -1.63) (xy -0.706 -1.667) (xy -0.69 -1.709)
				(xy -0.687 -1.721) (xy -0.685 -1.734) (xy -0.684 -1.757) (xy -0.683 -1.79) (xy -0.682 -1.833) (xy -0.681 -1.884)
				(xy -0.681 -1.945) (xy -0.681 -1.971) (xy -0.681 -2.194) (xy -0.808 -2.194) (xy -0.809 -1.984) (xy -0.811 -1.774)
				(xy -0.826 -1.744) (xy -0.845 -1.716) (xy -0.868 -1.697) (xy -0.897 -1.686) (xy -0.925 -1.682) (xy -0.947 -1.682)
				(xy -0.967 -1.684) (xy -0.979 -1.686) (xy -1.001 -1.698) (xy -1.023 -1.716) (xy -1.041 -1.738) (xy -1.049 -1.752)
				(xy -1.052 -1.758) (xy -1.054 -1.765) (xy -1.056 -1.773) (xy -1.057 -1.783) (xy -1.058 -1.797) (xy -1.059 -1.815)
				(xy -1.06 -1.839) (xy -1.06 -1.869) (xy -1.061 -1.907) (xy -1.061 -1.953) (xy -1.061 -1.985) (xy -1.063 -2.194)
				(xy -1.189 -2.194) (xy -1.189 -1.559) (xy -1.062 -1.559) (xy -1.062 -1.625) (xy -1.033 -1.602) (xy -1.001 -1.579)
				(xy -0.969 -1.564) (xy -0.934 -1.555) (xy -0.927 -1.554) (xy -0.881 -1.553) (xy -0.837 -1.56)
			)
			(stroke
				(width 0.01)
				(type solid)
			)
			(fill solid)
			(layer "B.Cu")
		)
		(fp_poly
			(pts
				(xy 1.042 -1.769) (xy 1.043 -1.979) (xy 1.059 -2.009) (xy 1.077 -2.036) (xy 1.1 -2.056) (xy 1.129 -2.067)
				(xy 1.159 -2.071) (xy 1.193 -2.07) (xy 1.221 -2.063) (xy 1.245 -2.047) (xy 1.258 -2.034) (xy 1.266 -2.025)
				(xy 1.273 -2.016) (xy 1.278 -2.008) (xy 1.282 -1.997) (xy 1.286 -1.985) (xy 1.288 -1.969) (xy 1.29 -1.948)
				(xy 1.291 -1.922) (xy 1.292 -1.89) (xy 1.293 -1.85) (xy 1.293 -1.801) (xy 1.294 -1.766) (xy 1.295 -1.559)
				(xy 1.422 -1.559) (xy 1.422 -2.194) (xy 1.295 -2.194) (xy 1.295 -2.161) (xy 1.295 -2.144) (xy 1.293 -2.132)
				(xy 1.292 -2.128) (xy 1.287 -2.131) (xy 1.278 -2.14) (xy 1.271 -2.147) (xy 1.256 -2.159) (xy 1.236 -2.171)
				(xy 1.219 -2.181) (xy 1.202 -2.188) (xy 1.186 -2.193) (xy 1.17 -2.196) (xy 1.148 -2.197) (xy 1.135 -2.198)
				(xy 1.107 -2.198) (xy 1.087 -2.197) (xy 1.07 -2.194) (xy 1.059 -2.19) (xy 1.036 -2.181) (xy 1.019 -2.172)
				(xy 1.003 -2.161) (xy 0.985 -2.146) (xy 0.981 -2.141) (xy 0.952 -2.107) (xy 0.931 -2.068) (xy 0.92 -2.033)
				(xy 0.918 -2.019) (xy 0.917 -1.996) (xy 0.916 -1.963) (xy 0.915 -1.92) (xy 0.914 -1.869) (xy 0.914 -1.808)
				(xy 0.914 -1.782) (xy 0.914 -1.559) (xy 1.04 -1.559) (xy 1.042 -1.769)
			)
			(stroke
				(width 0.01)
				(type solid)
			)
			(fill solid)
			(layer "B.Cu")
		)
		(fp_poly
			(pts
				(xy 1.753 -2.563) (xy 1.768 -2.568) (xy 1.787 -2.577) (xy 1.804 -2.586) (xy 1.818 -2.595) (xy 1.826 -2.602)
				(xy 1.827 -2.606) (xy 1.824 -2.611) (xy 1.815 -2.621) (xy 1.803 -2.636) (xy 1.789 -2.654) (xy 1.775 -2.671)
				(xy 1.761 -2.688) (xy 1.749 -2.701) (xy 1.742 -2.71) (xy 1.739 -2.712) (xy 1.735 -2.71) (xy 1.724 -2.704)
				(xy 1.713 -2.698) (xy 1.697 -2.69) (xy 1.682 -2.686) (xy 1.664 -2.685) (xy 1.653 -2.685) (xy 1.618 -2.688)
				(xy 1.59 -2.699) (xy 1.566 -2.718) (xy 1.561 -2.723) (xy 1.554 -2.732) (xy 1.548 -2.74) (xy 1.544 -2.748)
				(xy 1.54 -2.758) (xy 1.537 -2.769) (xy 1.534 -2.785) (xy 1.533 -2.804) (xy 1.532 -2.829) (xy 1.531 -2.861)
				(xy 1.53 -2.899) (xy 1.53 -2.947) (xy 1.53 -2.988) (xy 1.528 -3.2) (xy 1.468 -3.2) (xy 1.444 -3.2)
				(xy 1.425 -3.199) (xy 1.411 -3.198) (xy 1.405 -3.197) (xy 1.404 -3.191) (xy 1.404 -3.176) (xy 1.403 -3.153)
				(xy 1.403 -3.122) (xy 1.402 -3.085) (xy 1.402 -3.042) (xy 1.402 -2.993) (xy 1.402 -2.941) (xy 1.402 -2.886)
				(xy 1.402 -2.565) (xy 1.529 -2.565) (xy 1.529 -2.595) (xy 1.529 -2.611) (xy 1.53 -2.623) (xy 1.532 -2.626)
				(xy 1.537 -2.623) (xy 1.547 -2.615) (xy 1.554 -2.608) (xy 1.588 -2.584) (xy 1.627 -2.567) (xy 1.669 -2.558)
				(xy 1.712 -2.556) (xy 1.753 -2.563)
			)
			(stroke
				(width 0.01)
				(type solid)
			)
			(fill solid)
			(layer "B.Cu")
		)
		(fp_poly
			(pts
				(xy 2.316 -1.557) (xy 2.365 -1.57) (xy 2.41 -1.593) (xy 2.453 -1.625) (xy 2.46 -1.631) (xy 2.491 -1.661)
				(xy 2.466 -1.684) (xy 2.448 -1.699) (xy 2.43 -1.715) (xy 2.419 -1.725) (xy 2.397 -1.743) (xy 2.376 -1.724)
				(xy 2.345 -1.701) (xy 2.312 -1.687) (xy 2.274 -1.681) (xy 2.265 -1.681) (xy 2.226 -1.684) (xy 2.195 -1.693)
				(xy 2.167 -1.708) (xy 2.159 -1.715) (xy 2.136 -1.741) (xy 2.118 -1.776) (xy 2.107 -1.817) (xy 2.103 -1.866)
				(xy 2.103 -1.876) (xy 2.106 -1.926) (xy 2.116 -1.97) (xy 2.132 -2.006) (xy 2.155 -2.034) (xy 2.184 -2.055)
				(xy 2.219 -2.067) (xy 2.259 -2.072) (xy 2.274 -2.071) (xy 2.309 -2.066) (xy 2.339 -2.056) (xy 2.366 -2.038)
				(xy 2.377 -2.028) (xy 2.386 -2.02) (xy 2.393 -2.016) (xy 2.4 -2.015) (xy 2.409 -2.018) (xy 2.42 -2.027)
				(xy 2.436 -2.041) (xy 2.456 -2.059) (xy 2.491 -2.092) (xy 2.476 -2.108) (xy 2.449 -2.132) (xy 2.416 -2.155)
				(xy 2.38 -2.174) (xy 2.35 -2.186) (xy 2.327 -2.193) (xy 2.306 -2.197) (xy 2.283 -2.199) (xy 2.259 -2.199)
				(xy 2.233 -2.198) (xy 2.209 -2.196) (xy 2.189 -2.193) (xy 2.182 -2.191) (xy 2.133 -2.173) (xy 2.089 -2.146)
				(xy 2.053 -2.112) (xy 2.023 -2.071) (xy 2.012 -2.051) (xy 2 -2.023) (xy 1.991 -1.999) (xy 1.984 -1.975)
				(xy 1.981 -1.948) (xy 1.979 -1.917) (xy 1.978 -1.879) (xy 1.978 -1.877) (xy 1.979 -1.838) (xy 1.98 -1.806)
				(xy 1.984 -1.78) (xy 1.99 -1.756) (xy 1.999 -1.731) (xy 2.011 -1.704) (xy 2.012 -1.701) (xy 2.039 -1.657)
				(xy 2.072 -1.62) (xy 2.111 -1.591) (xy 2.156 -1.57) (xy 2.207 -1.557) (xy 2.263 -1.552) (xy 2.316 -1.557)
			)
			(stroke
				(width 0.01)
				(type solid)
			)
			(fill solid)
			(layer "B.Cu")
		)
		(fp_poly
			(pts
				(xy -1.494 -1.56) (xy -1.447 -1.576) (xy -1.405 -1.6) (xy -1.368 -1.633) (xy -1.341 -1.668) (xy -1.326 -1.692)
				(xy -1.316 -1.716) (xy -1.308 -1.743) (xy -1.302 -1.774) (xy -1.299 -1.811) (xy -1.297 -1.845) (xy -1.294 -1.925)
				(xy -1.692 -1.925) (xy -1.692 -1.942) (xy -1.687 -1.977) (xy -1.673 -2.011) (xy -1.65 -2.039) (xy -1.626 -2.059)
				(xy -1.601 -2.071) (xy -1.572 -2.078) (xy -1.537 -2.079) (xy -1.497 -2.074) (xy -1.458 -2.06) (xy -1.422 -2.036)
				(xy -1.421 -2.036) (xy -1.402 -2.021) (xy -1.359 -2.057) (xy -1.342 -2.072) (xy -1.327 -2.085) (xy -1.317 -2.094)
				(xy -1.314 -2.098) (xy -1.316 -2.103) (xy -1.324 -2.113) (xy -1.338 -2.126) (xy -1.354 -2.139) (xy -1.372 -2.152)
				(xy -1.389 -2.163) (xy -1.399 -2.168) (xy -1.421 -2.178) (xy -1.445 -2.187) (xy -1.461 -2.191) (xy -1.488 -2.196)
				(xy -1.522 -2.199) (xy -1.557 -2.199) (xy -1.591 -2.196) (xy -1.62 -2.192) (xy -1.629 -2.19) (xy -1.677 -2.171)
				(xy -1.718 -2.146) (xy -1.752 -2.114) (xy -1.779 -2.074) (xy -1.8 -2.026) (xy -1.802 -2.02) (xy -1.81 -1.989)
				(xy -1.815 -1.951) (xy -1.818 -1.908) (xy -1.819 -1.865) (xy -1.818 -1.823) (xy -1.816 -1.804) (xy -1.692 -1.804)
				(xy -1.692 -1.818) (xy -1.428 -1.818) (xy -1.428 -1.801) (xy -1.432 -1.775) (xy -1.442 -1.748) (xy -1.457 -1.722)
				(xy -1.469 -1.707) (xy -1.495 -1.688) (xy -1.526 -1.676) (xy -1.56 -1.672) (xy -1.593 -1.676) (xy -1.619 -1.685)
				(xy -1.646 -1.704) (xy -1.668 -1.73) (xy -1.683 -1.76) (xy -1.691 -1.792) (xy -1.692 -1.804) (xy -1.816 -1.804)
				(xy -1.814 -1.786) (xy -1.812 -1.777) (xy -1.797 -1.724) (xy -1.775 -1.676) (xy -1.747 -1.636) (xy -1.713 -1.603)
				(xy -1.673 -1.578) (xy -1.629 -1.561) (xy -1.597 -1.554) (xy -1.544 -1.552) (xy -1.494 -1.56)
			)
			(stroke
				(width 0.01)
				(type solid)
			)
			(fill solid)
			(layer "B.Cu")
		)
		(fp_poly
			(pts
				(xy 2.835 -1.557) (xy 2.883 -1.57) (xy 2.926 -1.592) (xy 2.964 -1.621) (xy 2.996 -1.657) (xy 3.021 -1.699)
				(xy 3.038 -1.747) (xy 3.04 -1.757) (xy 3.043 -1.776) (xy 3.045 -1.802) (xy 3.047 -1.832) (xy 3.047 -1.858)
				(xy 3.047 -1.925) (xy 2.65 -1.925) (xy 2.653 -1.951) (xy 2.663 -1.991) (xy 2.68 -2.024) (xy 2.703 -2.049)
				(xy 2.733 -2.067) (xy 2.77 -2.077) (xy 2.801 -2.079) (xy 2.845 -2.075) (xy 2.883 -2.063) (xy 2.916 -2.042)
				(xy 2.92 -2.039) (xy 2.929 -2.031) (xy 2.935 -2.026) (xy 2.941 -2.025) (xy 2.949 -2.027) (xy 2.959 -2.034)
				(xy 2.974 -2.047) (xy 2.994 -2.064) (xy 3.01 -2.078) (xy 3.023 -2.088) (xy 3.03 -2.095) (xy 3.032 -2.096)
				(xy 3.03 -2.1) (xy 3.022 -2.11) (xy 3.01 -2.122) (xy 3.009 -2.123) (xy 2.98 -2.147) (xy 2.945 -2.169)
				(xy 2.906 -2.185) (xy 2.887 -2.191) (xy 2.861 -2.196) (xy 2.828 -2.198) (xy 2.793 -2.198) (xy 2.759 -2.197)
				(xy 2.729 -2.193) (xy 2.721 -2.191) (xy 2.675 -2.175) (xy 2.634 -2.15) (xy 2.599 -2.118) (xy 2.569 -2.077)
				(xy 2.547 -2.029) (xy 2.536 -1.996) (xy 2.532 -1.973) (xy 2.529 -1.942) (xy 2.527 -1.906) (xy 2.527 -1.869)
				(xy 2.528 -1.832) (xy 2.529 -1.818) (xy 2.65 -1.818) (xy 2.922 -1.818) (xy 2.918 -1.799) (xy 2.908 -1.758)
				(xy 2.891 -1.725) (xy 2.869 -1.7) (xy 2.84 -1.683) (xy 2.826 -1.678) (xy 2.788 -1.672) (xy 2.753 -1.675)
				(xy 2.722 -1.687) (xy 2.695 -1.706) (xy 2.674 -1.734) (xy 2.659 -1.768) (xy 2.654 -1.794) (xy 2.65 -1.818)
				(xy 2.529 -1.818) (xy 2.53 -1.798) (xy 2.534 -1.769) (xy 2.536 -1.76) (xy 2.554 -1.707) (xy 2.578 -1.662)
				(xy 2.609 -1.624) (xy 2.645 -1.593) (xy 2.687 -1.571) (xy 2.734 -1.557) (xy 2.783 -1.553) (xy 2.835 -1.557)
			)
			(stroke
				(width 0.01)
				(type solid)
			)
			(fill solid)
			(layer "B.Cu")
		)
		(fp_poly
			(pts
				(xy 2.148 -2.561) (xy 2.193 -2.574) (xy 2.235 -2.595) (xy 2.273 -2.623) (xy 2.304 -2.657) (xy 2.326 -2.691)
				(xy 2.338 -2.718) (xy 2.346 -2.745) (xy 2.352 -2.774) (xy 2.355 -2.808) (xy 2.357 -2.85) (xy 2.357 -2.858)
				(xy 2.357 -2.931) (xy 1.96 -2.931) (xy 1.963 -2.955) (xy 1.973 -2.993) (xy 1.991 -3.026) (xy 2.015 -3.053)
				(xy 2.039 -3.069) (xy 2.057 -3.076) (xy 2.08 -3.08) (xy 2.103 -3.082) (xy 2.144 -3.081) (xy 2.18 -3.071)
				(xy 2.214 -3.054) (xy 2.227 -3.045) (xy 2.24 -3.035) (xy 2.25 -3.029) (xy 2.253 -3.027) (xy 2.258 -3.03)
				(xy 2.269 -3.039) (xy 2.284 -3.05) (xy 2.3 -3.064) (xy 2.315 -3.078) (xy 2.329 -3.09) (xy 2.338 -3.099)
				(xy 2.341 -3.103) (xy 2.337 -3.11) (xy 2.327 -3.121) (xy 2.312 -3.134) (xy 2.294 -3.148) (xy 2.276 -3.161)
				(xy 2.259 -3.171) (xy 2.252 -3.175) (xy 2.204 -3.192) (xy 2.152 -3.202) (xy 2.098 -3.204) (xy 2.046 -3.198)
				(xy 2.032 -3.195) (xy 1.984 -3.178) (xy 1.943 -3.154) (xy 1.909 -3.123) (xy 1.881 -3.084) (xy 1.859 -3.037)
				(xy 1.847 -3.003) (xy 1.841 -2.972) (xy 1.838 -2.934) (xy 1.836 -2.893) (xy 1.837 -2.851) (xy 1.839 -2.824)
				(xy 1.96 -2.824) (xy 2.23 -2.824) (xy 2.23 -2.813) (xy 2.225 -2.783) (xy 2.214 -2.753) (xy 2.196 -2.725)
				(xy 2.175 -2.702) (xy 2.151 -2.686) (xy 2.128 -2.68) (xy 2.101 -2.677) (xy 2.072 -2.678) (xy 2.051 -2.683)
				(xy 2.023 -2.696) (xy 2 -2.717) (xy 1.981 -2.746) (xy 1.968 -2.779) (xy 1.963 -2.8) (xy 1.96 -2.824)
				(xy 1.839 -2.824) (xy 1.839 -2.811) (xy 1.844 -2.776) (xy 1.848 -2.76) (xy 1.866 -2.708) (xy 1.889 -2.663)
				(xy 1.919 -2.627) (xy 1.954 -2.598) (xy 1.996 -2.575) (xy 2.007 -2.571) (xy 2.054 -2.559) (xy 2.101 -2.556)
				(xy 2.148 -2.561)
			)
			(stroke
				(width 0.01)
				(type solid)
			)
			(fill solid)
			(layer "B.Cu")
		)
		(fp_poly
			(pts
				(xy -2.733 -1.557) (xy -2.685 -1.57) (xy -2.642 -1.592) (xy -2.604 -1.622) (xy -2.581 -1.649) (xy -2.562 -1.676)
				(xy -2.548 -1.706) (xy -2.537 -1.739) (xy -2.53 -1.777) (xy -2.527 -1.821) (xy -2.526 -1.873) (xy -2.527 -1.907)
				(xy -2.529 -1.956) (xy -2.534 -1.997) (xy -2.542 -2.031) (xy -2.553 -2.06) (xy -2.567 -2.086) (xy -2.587 -2.111)
				(xy -2.603 -2.129) (xy -2.637 -2.158) (xy -2.673 -2.178) (xy -2.714 -2.192) (xy -2.76 -2.198) (xy -2.789 -2.199)
				(xy -2.813 -2.198) (xy -2.835 -2.196) (xy -2.852 -2.194) (xy -2.857 -2.194) (xy -2.898 -2.179) (xy -2.937 -2.155)
				(xy -2.97 -2.126) (xy -2.993 -2.101) (xy -3.011 -2.077) (xy -3.024 -2.051) (xy -3.034 -2.022) (xy -3.041 -1.988)
				(xy -3.045 -1.947) (xy -3.047 -1.91) (xy -3.047 -1.882) (xy -2.919 -1.882) (xy -2.919 -1.968) (xy -2.903 -2.001)
				(xy -2.885 -2.031) (xy -2.863 -2.051) (xy -2.837 -2.064) (xy -2.804 -2.07) (xy -2.779 -2.07) (xy -2.755 -2.069)
				(xy -2.737 -2.065) (xy -2.722 -2.058) (xy -2.717 -2.055) (xy -2.697 -2.041) (xy -2.681 -2.025) (xy -2.67 -2.004)
				(xy -2.662 -1.978) (xy -2.657 -1.945) (xy -2.654 -1.903) (xy -2.654 -1.899) (xy -2.653 -1.848) (xy -2.656 -1.806)
				(xy -2.662 -1.772) (xy -2.673 -1.744) (xy -2.687 -1.722) (xy -2.707 -1.705) (xy -2.723 -1.695) (xy -2.755 -1.684)
				(xy -2.788 -1.68) (xy -2.821 -1.684) (xy -2.851 -1.695) (xy -2.877 -1.713) (xy -2.892 -1.729) (xy -2.901 -1.745)
				(xy -2.908 -1.76) (xy -2.913 -1.778) (xy -2.916 -1.8) (xy -2.918 -1.828) (xy -2.919 -1.864) (xy -2.919 -1.882)
				(xy -3.047 -1.882) (xy -3.048 -1.844) (xy -3.043 -1.786) (xy -3.034 -1.736) (xy -3.021 -1.695) (xy -3.004 -1.664)
				(xy -2.972 -1.624) (xy -2.935 -1.594) (xy -2.893 -1.571) (xy -2.846 -1.558) (xy -2.794 -1.553) (xy -2.787 -1.553)
				(xy -2.733 -1.557)
			)
			(stroke
				(width 0.01)
				(type solid)
			)
			(fill solid)
			(layer "B.Cu")
		)
		(fp_poly
			(pts
				(xy -0.229 -3.2) (xy -0.354 -3.197) (xy -0.355 -3.165) (xy -0.357 -3.133) (xy -0.374 -3.148) (xy -0.411 -3.175)
				(xy -0.453 -3.193) (xy -0.497 -3.203) (xy -0.542 -3.204) (xy -0.585 -3.195) (xy -0.586 -3.195) (xy -0.621 -3.181)
				(xy -0.651 -3.16) (xy -0.673 -3.141) (xy -0.689 -3.123) (xy -0.702 -3.106) (xy -0.712 -3.086) (xy -0.72 -3.064)
				(xy -0.726 -3.038) (xy -0.73 -3.007) (xy -0.732 -2.968) (xy -0.733 -2.922) (xy -0.733 -2.88) (xy -0.602 -2.88)
				(xy -0.602 -2.915) (xy -0.602 -2.942) (xy -0.601 -2.962) (xy -0.6 -2.977) (xy -0.598 -2.988) (xy -0.596 -2.998)
				(xy -0.592 -3.007) (xy -0.591 -3.01) (xy -0.574 -3.039) (xy -0.552 -3.059) (xy -0.525 -3.071) (xy -0.492 -3.076)
				(xy -0.472 -3.076) (xy -0.442 -3.072) (xy -0.418 -3.063) (xy -0.398 -3.048) (xy -0.382 -3.029) (xy -0.371 -3.004)
				(xy -0.363 -2.972) (xy -0.358 -2.933) (xy -0.356 -2.885) (xy -0.356 -2.88) (xy -0.358 -2.828) (xy -0.363 -2.785)
				(xy -0.373 -2.75) (xy -0.387 -2.724) (xy -0.406 -2.704) (xy -0.43 -2.692) (xy -0.46 -2.686) (xy -0.483 -2.685)
				(xy -0.517 -2.687) (xy -0.544 -2.696) (xy -0.565 -2.711) (xy -0.583 -2.734) (xy -0.591 -2.751) (xy -0.595 -2.76)
				(xy -0.598 -2.769) (xy -0.6 -2.779) (xy -0.601 -2.793) (xy -0.602 -2.811) (xy -0.602 -2.836) (xy -0.602 -2.869)
				(xy -0.602 -2.88) (xy -0.733 -2.88) (xy -0.733 -2.827) (xy -0.732 -2.783) (xy -0.729 -2.746) (xy -0.725 -2.716)
				(xy -0.719 -2.691) (xy -0.71 -2.67) (xy -0.699 -2.651) (xy -0.685 -2.633) (xy -0.668 -2.616) (xy -0.668 -2.615)
				(xy -0.632 -2.587) (xy -0.592 -2.567) (xy -0.55 -2.557) (xy -0.506 -2.556) (xy -0.463 -2.564) (xy -0.421 -2.582)
				(xy -0.411 -2.587) (xy -0.394 -2.598) (xy -0.377 -2.61) (xy -0.373 -2.614) (xy -0.356 -2.627) (xy -0.356 -2.306)
				(xy -0.229 -2.306) (xy -0.229 -3.2)
			)
			(stroke
				(width 0.01)
				(type solid)
			)
			(fill solid)
			(layer "B.Cu")
		)
		(fp_poly
			(pts
				(xy 0.605 -1.558) (xy 0.651 -1.574) (xy 0.694 -1.598) (xy 0.728 -1.627) (xy 0.75 -1.652) (xy 0.768 -1.678)
				(xy 0.781 -1.707) (xy 0.791 -1.739) (xy 0.797 -1.777) (xy 0.801 -1.822) (xy 0.802 -1.876) (xy 0.802 -1.877)
				(xy 0.801 -1.929) (xy 0.798 -1.973) (xy 0.792 -2.009) (xy 0.784 -2.04) (xy 0.774 -2.062) (xy 0.748 -2.103)
				(xy 0.715 -2.139) (xy 0.675 -2.167) (xy 0.632 -2.187) (xy 0.626 -2.189) (xy 0.599 -2.195) (xy 0.567 -2.198)
				(xy 0.532 -2.199) (xy 0.499 -2.197) (xy 0.471 -2.193) (xy 0.466 -2.192) (xy 0.428 -2.177) (xy 0.391 -2.155)
				(xy 0.359 -2.129) (xy 0.354 -2.123) (xy 0.332 -2.098) (xy 0.316 -2.073) (xy 0.303 -2.047) (xy 0.294 -2.017)
				(xy 0.287 -1.983) (xy 0.284 -1.943) (xy 0.282 -1.894) (xy 0.282 -1.877) (xy 0.409 -1.877) (xy 0.41 -1.918)
				(xy 0.412 -1.95) (xy 0.416 -1.976) (xy 0.423 -1.997) (xy 0.432 -2.015) (xy 0.445 -2.03) (xy 0.451 -2.037)
				(xy 0.471 -2.054) (xy 0.491 -2.064) (xy 0.514 -2.07) (xy 0.543 -2.072) (xy 0.569 -2.07) (xy 0.59 -2.065)
				(xy 0.601 -2.06) (xy 0.625 -2.047) (xy 0.642 -2.031) (xy 0.656 -2.009) (xy 0.661 -1.998) (xy 0.665 -1.989)
				(xy 0.668 -1.98) (xy 0.67 -1.969) (xy 0.671 -1.954) (xy 0.672 -1.935) (xy 0.673 -1.909) (xy 0.673 -1.877)
				(xy 0.673 -1.842) (xy 0.672 -1.817) (xy 0.671 -1.798) (xy 0.67 -1.784) (xy 0.668 -1.773) (xy 0.665 -1.764)
				(xy 0.661 -1.755) (xy 0.647 -1.73) (xy 0.632 -1.712) (xy 0.612 -1.698) (xy 0.601 -1.693) (xy 0.569 -1.683)
				(xy 0.535 -1.681) (xy 0.501 -1.686) (xy 0.471 -1.7) (xy 0.447 -1.719) (xy 0.434 -1.736) (xy 0.424 -1.753)
				(xy 0.417 -1.774) (xy 0.412 -1.8) (xy 0.41 -1.833) (xy 0.409 -1.873) (xy 0.409 -1.877) (xy 0.282 -1.877)
				(xy 0.283 -1.824) (xy 0.286 -1.78) (xy 0.292 -1.742) (xy 0.301 -1.711) (xy 0.313 -1.683) (xy 0.33 -1.657)
				(xy 0.35 -1.633) (xy 0.351 -1.632) (xy 0.385 -1.601) (xy 0.42 -1.578) (xy 0.46 -1.563) (xy 0.505 -1.554)
				(xy 0.555 -1.551) (xy 0.605 -1.558)
			)
			(stroke
				(width 0.01)
				(type solid)
			)
			(fill solid)
			(layer "B.Cu")
		)
		(fp_poly
			(pts
				(xy 0.004 -1.556) (xy 0.054 -1.566) (xy 0.102 -1.582) (xy 0.146 -1.605) (xy 0.154 -1.61) (xy 0.193 -1.636)
				(xy 0.178 -1.655) (xy 0.166 -1.668) (xy 0.152 -1.686) (xy 0.138 -1.7) (xy 0.114 -1.727) (xy 0.07 -1.705)
				(xy 0.032 -1.688) (xy -0.007 -1.677) (xy -0.044 -1.672) (xy -0.079 -1.672) (xy -0.11 -1.678) (xy -0.136 -1.69)
				(xy -0.154 -1.707) (xy -0.162 -1.724) (xy -0.164 -1.745) (xy -0.164 -1.761) (xy -0.159 -1.772) (xy -0.15 -1.782)
				(xy -0.149 -1.783) (xy -0.139 -1.791) (xy -0.128 -1.797) (xy -0.114 -1.802) (xy -0.095 -1.805) (xy -0.07 -1.808)
				(xy -0.037 -1.811) (xy -0.02 -1.813) (xy 0.027 -1.817) (xy 0.065 -1.823) (xy 0.096 -1.832) (xy 0.122 -1.842)
				(xy 0.14 -1.854) (xy 0.166 -1.879) (xy 0.186 -1.91) (xy 0.2 -1.947) (xy 0.206 -1.987) (xy 0.206 -2.018)
				(xy 0.198 -2.06) (xy 0.181 -2.097) (xy 0.155 -2.129) (xy 0.122 -2.156) (xy 0.08 -2.177) (xy 0.042 -2.189)
				(xy 0.005 -2.196) (xy -0.038 -2.199) (xy -0.083 -2.198) (xy -0.125 -2.194) (xy -0.153 -2.189) (xy -0.177 -2.181)
				(xy -0.204 -2.171) (xy -0.229 -2.16) (xy -0.232 -2.159) (xy -0.251 -2.148) (xy -0.272 -2.136) (xy -0.292 -2.122)
				(xy -0.309 -2.109) (xy -0.323 -2.098) (xy -0.33 -2.09) (xy -0.331 -2.088) (xy -0.327 -2.084) (xy -0.318 -2.073)
				(xy -0.304 -2.059) (xy -0.288 -2.043) (xy -0.246 -2) (xy -0.221 -2.021) (xy -0.184 -2.047) (xy -0.145 -2.065)
				(xy -0.102 -2.075) (xy -0.053 -2.079) (xy -0.049 -2.079) (xy -0.023 -2.079) (xy -0.004 -2.078) (xy 0.011 -2.074)
				(xy 0.025 -2.069) (xy 0.029 -2.068) (xy 0.054 -2.052) (xy 0.071 -2.033) (xy 0.079 -2.01) (xy 0.078 -1.986)
				(xy 0.074 -1.975) (xy 0.068 -1.964) (xy 0.06 -1.956) (xy 0.048 -1.949) (xy 0.031 -1.944) (xy 0.007 -1.939)
				(xy -0.024 -1.935) (xy -0.052 -1.932) (xy -0.089 -1.929) (xy -0.119 -1.925) (xy -0.142 -1.921) (xy -0.16 -1.917)
				(xy -0.176 -1.912) (xy -0.192 -1.906) (xy -0.201 -1.901) (xy -0.235 -1.879) (xy -0.262 -1.85) (xy -0.28 -1.816)
				(xy -0.29 -1.776) (xy -0.292 -1.75) (xy -0.291 -1.727) (xy -0.289 -1.705) (xy -0.286 -1.689) (xy -0.286 -1.688)
				(xy -0.273 -1.659) (xy -0.253 -1.63) (xy -0.229 -1.604) (xy -0.221 -1.599) (xy -0.185 -1.577) (xy -0.143 -1.562)
				(xy -0.096 -1.554) (xy -0.047 -1.552) (xy 0.004 -1.556)
			)
			(stroke
				(width 0.01)
				(type solid)
			)
			(fill solid)
			(layer "B.Cu")
		)
		(fp_poly
			(pts
				(xy 1.038 -2.556) (xy 1.091 -2.563) (xy 1.137 -2.576) (xy 1.177 -2.595) (xy 1.209 -2.62) (xy 1.234 -2.65)
				(xy 1.242 -2.665) (xy 1.247 -2.677) (xy 1.251 -2.691) (xy 1.255 -2.708) (xy 1.258 -2.727) (xy 1.26 -2.751)
				(xy 1.262 -2.78) (xy 1.263 -2.815) (xy 1.263 -2.858) (xy 1.264 -2.908) (xy 1.263 -2.967) (xy 1.263 -2.989)
				(xy 1.262 -3.197) (xy 1.135 -3.197) (xy 1.133 -3.171) (xy 1.132 -3.144) (xy 1.119 -3.159) (xy 1.096 -3.179)
				(xy 1.065 -3.193) (xy 1.026 -3.202) (xy 0.98 -3.204) (xy 0.976 -3.204) (xy 0.955 -3.204) (xy 0.937 -3.203)
				(xy 0.925 -3.202) (xy 0.924 -3.201) (xy 0.879 -3.189) (xy 0.839 -3.17) (xy 0.806 -3.144) (xy 0.781 -3.113)
				(xy 0.763 -3.077) (xy 0.753 -3.037) (xy 0.753 -3.005) (xy 0.873 -3.005) (xy 0.874 -3.023) (xy 0.878 -3.035)
				(xy 0.887 -3.047) (xy 0.89 -3.05) (xy 0.903 -3.063) (xy 0.917 -3.072) (xy 0.935 -3.078) (xy 0.957 -3.081)
				(xy 0.986 -3.082) (xy 1.013 -3.082) (xy 1.043 -3.081) (xy 1.065 -3.079) (xy 1.08 -3.077) (xy 1.091 -3.073)
				(xy 1.096 -3.071) (xy 1.112 -3.058) (xy 1.123 -3.039) (xy 1.13 -3.012) (xy 1.132 -2.977) (xy 1.132 -2.975)
				(xy 1.132 -2.931) (xy 1.035 -2.931) (xy 0.999 -2.931) (xy 0.973 -2.931) (xy 0.953 -2.932) (xy 0.939 -2.934)
				(xy 0.928 -2.936) (xy 0.919 -2.939) (xy 0.916 -2.94) (xy 0.893 -2.954) (xy 0.88 -2.971) (xy 0.874 -2.994)
				(xy 0.873 -3.005) (xy 0.753 -3.005) (xy 0.753 -2.994) (xy 0.761 -2.951) (xy 0.768 -2.931) (xy 0.776 -2.915)
				(xy 0.786 -2.901) (xy 0.802 -2.884) (xy 0.804 -2.882) (xy 0.82 -2.867) (xy 0.835 -2.854) (xy 0.85 -2.845)
				(xy 0.867 -2.838) (xy 0.887 -2.833) (xy 0.912 -2.829) (xy 0.943 -2.827) (xy 0.982 -2.826) (xy 1.015 -2.825)
				(xy 1.133 -2.823) (xy 1.132 -2.771) (xy 1.131 -2.746) (xy 1.129 -2.73) (xy 1.127 -2.719) (xy 1.123 -2.711)
				(xy 1.117 -2.705) (xy 1.098 -2.691) (xy 1.07 -2.682) (xy 1.032 -2.677) (xy 1.006 -2.677) (xy 0.972 -2.678)
				(xy 0.945 -2.682) (xy 0.924 -2.688) (xy 0.907 -2.699) (xy 0.9 -2.706) (xy 0.882 -2.723) (xy 0.834 -2.686)
				(xy 0.816 -2.672) (xy 0.801 -2.66) (xy 0.79 -2.652) (xy 0.787 -2.648) (xy 0.791 -2.639) (xy 0.801 -2.626)
				(xy 0.816 -2.612) (xy 0.832 -2.6) (xy 0.864 -2.581) (xy 0.902 -2.568) (xy 0.946 -2.559) (xy 0.98 -2.556)
				(xy 1.038 -2.556)
			)
			(stroke
				(width 0.01)
				(type solid)
			)
			(fill solid)
			(layer "B.Cu")
		)
		(fp_poly
			(pts
				(xy -1.521 -2.559) (xy -1.485 -2.562) (xy -1.454 -2.568) (xy -1.427 -2.577) (xy -1.401 -2.589) (xy -1.371 -2.61)
				(xy -1.345 -2.639) (xy -1.325 -2.67) (xy -1.321 -2.679) (xy -1.309 -2.71) (xy -1.309 -3.197) (xy -1.433 -3.2)
				(xy -1.433 -3.172) (xy -1.434 -3.157) (xy -1.435 -3.147) (xy -1.436 -3.144) (xy -1.44 -3.147) (xy -1.449 -3.156)
				(xy -1.453 -3.161) (xy -1.472 -3.178) (xy -1.496 -3.19) (xy -1.526 -3.198) (xy -1.563 -3.202) (xy -1.578 -3.203)
				(xy -1.603 -3.203) (xy -1.627 -3.203) (xy -1.647 -3.201) (xy -1.656 -3.2) (xy -1.686 -3.191) (xy -1.717 -3.176)
				(xy -1.746 -3.159) (xy -1.765 -3.143) (xy -1.79 -3.111) (xy -1.807 -3.075) (xy -1.816 -3.037) (xy -1.817 -2.998)
				(xy -1.817 -2.997) (xy -1.697 -2.997) (xy -1.696 -3.02) (xy -1.687 -3.042) (xy -1.67 -3.06) (xy -1.668 -3.062)
				(xy -1.654 -3.07) (xy -1.64 -3.076) (xy -1.624 -3.08) (xy -1.602 -3.081) (xy -1.574 -3.082) (xy -1.558 -3.082)
				(xy -1.529 -3.081) (xy -1.508 -3.08) (xy -1.494 -3.078) (xy -1.483 -3.075) (xy -1.474 -3.07) (xy -1.458 -3.058)
				(xy -1.447 -3.041) (xy -1.44 -3.017) (xy -1.435 -2.985) (xy -1.435 -2.977) (xy -1.432 -2.931) (xy -1.533 -2.931)
				(xy -1.568 -2.931) (xy -1.595 -2.931) (xy -1.615 -2.932) (xy -1.63 -2.934) (xy -1.641 -2.936) (xy -1.65 -2.938)
				(xy -1.655 -2.941) (xy -1.676 -2.955) (xy -1.69 -2.974) (xy -1.697 -2.997) (xy -1.817 -2.997) (xy -1.811 -2.96)
				(xy -1.797 -2.924) (xy -1.775 -2.892) (xy -1.747 -2.864) (xy -1.715 -2.845) (xy -1.7 -2.838) (xy -1.685 -2.833)
				(xy -1.668 -2.83) (xy -1.648 -2.827) (xy -1.623 -2.825) (xy -1.591 -2.824) (xy -1.551 -2.824) (xy -1.54 -2.824)
				(xy -1.432 -2.824) (xy -1.434 -2.776) (xy -1.436 -2.747) (xy -1.441 -2.726) (xy -1.448 -2.711) (xy -1.46 -2.699)
				(xy -1.474 -2.689) (xy -1.483 -2.685) (xy -1.492 -2.682) (xy -1.505 -2.68) (xy -1.524 -2.68) (xy -1.55 -2.679)
				(xy -1.56 -2.679) (xy -1.594 -2.68) (xy -1.62 -2.682) (xy -1.639 -2.686) (xy -1.654 -2.692) (xy -1.666 -2.701)
				(xy -1.675 -2.711) (xy -1.686 -2.724) (xy -1.735 -2.686) (xy -1.754 -2.672) (xy -1.769 -2.659) (xy -1.78 -2.65)
				(xy -1.784 -2.646) (xy -1.78 -2.64) (xy -1.77 -2.629) (xy -1.756 -2.616) (xy -1.74 -2.604) (xy -1.724 -2.592)
				(xy -1.711 -2.584) (xy -1.71 -2.583) (xy -1.688 -2.574) (xy -1.668 -2.566) (xy -1.647 -2.562) (xy -1.623 -2.559)
				(xy -1.593 -2.558) (xy -1.565 -2.558) (xy -1.521 -2.559)
			)
			(stroke
				(width 0.01)
				(type solid)
			)
			(fill solid)
			(layer "B.Cu")
		)
		(fp_poly
			(pts
				(xy 0.035 -2.777) (xy 0.047 -2.822) (xy 0.059 -2.864) (xy 0.069 -2.903) (xy 0.078 -2.936) (xy 0.086 -2.963)
				(xy 0.092 -2.984) (xy 0.095 -2.996) (xy 0.096 -2.999) (xy 0.098 -2.999) (xy 0.103 -2.991) (xy 0.109 -2.975)
				(xy 0.118 -2.95) (xy 0.129 -2.917) (xy 0.143 -2.874) (xy 0.152 -2.849) (xy 0.165 -2.807) (xy 0.179 -2.766)
				(xy 0.192 -2.726) (xy 0.204 -2.689) (xy 0.214 -2.658) (xy 0.221 -2.634) (xy 0.224 -2.627) (xy 0.244 -2.565)
				(xy 0.338 -2.565) (xy 0.406 -2.774) (xy 0.42 -2.819) (xy 0.434 -2.861) (xy 0.446 -2.899) (xy 0.457 -2.932)
				(xy 0.466 -2.96) (xy 0.473 -2.981) (xy 0.477 -2.993) (xy 0.478 -2.997) (xy 0.48 -2.998) (xy 0.482 -2.996)
				(xy 0.485 -2.99) (xy 0.49 -2.978) (xy 0.495 -2.96) (xy 0.502 -2.936) (xy 0.511 -2.905) (xy 0.523 -2.865)
				(xy 0.536 -2.817) (xy 0.543 -2.789) (xy 0.556 -2.744) (xy 0.568 -2.701) (xy 0.578 -2.663) (xy 0.587 -2.629)
				(xy 0.595 -2.602) (xy 0.601 -2.582) (xy 0.605 -2.57) (xy 0.606 -2.567) (xy 0.611 -2.566) (xy 0.625 -2.566)
				(xy 0.645 -2.566) (xy 0.669 -2.566) (xy 0.673 -2.566) (xy 0.739 -2.567) (xy 0.656 -2.827) (xy 0.64 -2.878)
				(xy 0.624 -2.928) (xy 0.609 -2.976) (xy 0.595 -3.02) (xy 0.582 -3.06) (xy 0.571 -3.094) (xy 0.563 -3.121)
				(xy 0.557 -3.139) (xy 0.556 -3.143) (xy 0.538 -3.2) (xy 0.425 -3.197) (xy 0.358 -2.975) (xy 0.341 -2.917)
				(xy 0.327 -2.87) (xy 0.315 -2.831) (xy 0.305 -2.801) (xy 0.297 -2.78) (xy 0.292 -2.766) (xy 0.289 -2.761)
				(xy 0.288 -2.761) (xy 0.286 -2.768) (xy 0.281 -2.783) (xy 0.274 -2.806) (xy 0.265 -2.836) (xy 0.254 -2.871)
				(xy 0.242 -2.911) (xy 0.23 -2.953) (xy 0.223 -2.976) (xy 0.21 -3.02) (xy 0.197 -3.062) (xy 0.186 -3.099)
				(xy 0.177 -3.132) (xy 0.169 -3.158) (xy 0.163 -3.177) (xy 0.16 -3.189) (xy 0.159 -3.191) (xy 0.157 -3.195)
				(xy 0.151 -3.198) (xy 0.141 -3.199) (xy 0.124 -3.2) (xy 0.101 -3.2) (xy 0.073 -3.199) (xy 0.055 -3.198)
				(xy 0.045 -3.196) (xy 0.043 -3.194) (xy 0.041 -3.188) (xy 0.036 -3.173) (xy 0.029 -3.15) (xy 0.019 -3.121)
				(xy 0.008 -3.084) (xy -0.006 -3.043) (xy -0.02 -2.996) (xy -0.036 -2.946) (xy -0.053 -2.893) (xy -0.057 -2.883)
				(xy -0.074 -2.83) (xy -0.09 -2.779) (xy -0.105 -2.732) (xy -0.119 -2.689) (xy -0.131 -2.652) (xy -0.141 -2.621)
				(xy -0.148 -2.596) (xy -0.154 -2.58) (xy -0.156 -2.572) (xy -0.156 -2.569) (xy -0.151 -2.567) (xy -0.14 -2.566)
				(xy -0.123 -2.565) (xy -0.096 -2.565) (xy -0.091 -2.565) (xy -0.023 -2.565) (xy 0.035 -2.777)
			)
			(stroke
				(width 0.01)
				(type solid)
			)
			(fill solid)
			(layer "B.Cu")
		)
		(fp_poly
			(pts
				(xy -2.065 -1.559) (xy -2.024 -1.576) (xy -1.986 -1.601) (xy -1.973 -1.612) (xy -1.957 -1.63) (xy -1.943 -1.649)
				(xy -1.932 -1.668) (xy -1.924 -1.69) (xy -1.918 -1.716) (xy -1.914 -1.747) (xy -1.911 -1.785) (xy -1.91 -1.831)
				(xy -1.91 -1.877) (xy -1.91 -1.93) (xy -1.912 -1.974) (xy -1.914 -2.011) (xy -1.919 -2.041) (xy -1.925 -2.067)
				(xy -1.934 -2.088) (xy -1.945 -2.107) (xy -1.959 -2.125) (xy -1.972 -2.139) (xy -1.993 -2.157) (xy -2.018 -2.173)
				(xy -2.031 -2.18) (xy -2.047 -2.188) (xy -2.06 -2.192) (xy -2.074 -2.195) (xy -2.091 -2.196) (xy -2.114 -2.197)
				(xy -2.122 -2.197) (xy -2.147 -2.196) (xy -2.165 -2.195) (xy -2.179 -2.193) (xy -2.191 -2.189) (xy -2.205 -2.183)
				(xy -2.21 -2.18) (xy -2.231 -2.169) (xy -2.251 -2.156) (xy -2.265 -2.146) (xy -2.286 -2.127) (xy -2.286 -2.627)
				(xy -2.266 -2.608) (xy -2.248 -2.595) (xy -2.227 -2.582) (xy -2.217 -2.577) (xy -2.173 -2.562) (xy -2.129 -2.556)
				(xy -2.086 -2.559) (xy -2.045 -2.57) (xy -2.007 -2.589) (xy -1.974 -2.616) (xy -1.946 -2.648) (xy -1.926 -2.687)
				(xy -1.919 -2.707) (xy -1.917 -2.715) (xy -1.915 -2.724) (xy -1.914 -2.737) (xy -1.913 -2.753) (xy -1.912 -2.774)
				(xy -1.911 -2.8) (xy -1.911 -2.833) (xy -1.911 -2.874) (xy -1.911 -2.923) (xy -1.911 -2.967) (xy -1.911 -3.2)
				(xy -2.035 -3.197) (xy -2.038 -2.984) (xy -2.038 -2.932) (xy -2.039 -2.889) (xy -2.039 -2.854) (xy -2.04 -2.826)
				(xy -2.041 -2.805) (xy -2.042 -2.788) (xy -2.043 -2.776) (xy -2.045 -2.767) (xy -2.046 -2.76) (xy -2.049 -2.755)
				(xy -2.051 -2.75) (xy -2.072 -2.721) (xy -2.098 -2.701) (xy -2.128 -2.688) (xy -2.161 -2.683) (xy -2.195 -2.687)
				(xy -2.22 -2.697) (xy -2.24 -2.71) (xy -2.259 -2.729) (xy -2.274 -2.75) (xy -2.278 -2.757) (xy -2.28 -2.765)
				(xy -2.281 -2.781) (xy -2.283 -2.806) (xy -2.284 -2.839) (xy -2.285 -2.881) (xy -2.286 -2.933) (xy -2.286 -2.984)
				(xy -2.289 -3.197) (xy -2.413 -3.2) (xy -2.413 -1.877) (xy -2.286 -1.877) (xy -2.285 -1.926) (xy -2.281 -1.966)
				(xy -2.274 -1.998) (xy -2.262 -2.024) (xy -2.247 -2.043) (xy -2.228 -2.058) (xy -2.215 -2.064) (xy -2.194 -2.07)
				(xy -2.168 -2.072) (xy -2.141 -2.071) (xy -2.117 -2.066) (xy -2.106 -2.063) (xy -2.079 -2.044) (xy -2.058 -2.019)
				(xy -2.05 -2.001) (xy -2.045 -1.984) (xy -2.042 -1.959) (xy -2.04 -1.929) (xy -2.038 -1.895) (xy -2.038 -1.861)
				(xy -2.039 -1.829) (xy -2.041 -1.8) (xy -2.044 -1.777) (xy -2.045 -1.772) (xy -2.057 -1.738) (xy -2.073 -1.712)
				(xy -2.094 -1.695) (xy -2.122 -1.684) (xy -2.156 -1.681) (xy -2.159 -1.681) (xy -2.192 -1.683) (xy -2.22 -1.691)
				(xy -2.243 -1.705) (xy -2.26 -1.725) (xy -2.273 -1.753) (xy -2.281 -1.788) (xy -2.285 -1.832) (xy -2.286 -1.877)
				(xy -2.413 -1.877) (xy -2.413 -1.559) (xy -2.286 -1.559) (xy -2.286 -1.62) (xy -2.26 -1.6) (xy -2.225 -1.577)
				(xy -2.19 -1.563) (xy -2.154 -1.554) (xy -2.109 -1.552) (xy -2.065 -1.559)
			)
			(stroke
				(width 0.01)
				(type solid)
			)
			(fill solid)
			(layer "B.Cu")
		)
		(fp_poly
			(pts
				(xy 0.063 3.201) (xy 0.118 3.201) (xy 0.164 3.201) (xy 0.202 3.2) (xy 0.233 3.2) (xy 0.258 3.2)
				(xy 0.277 3.199) (xy 0.292 3.198) (xy 0.302 3.197) (xy 0.309 3.196) (xy 0.314 3.195) (xy 0.317 3.193)
				(xy 0.319 3.192) (xy 0.321 3.189) (xy 0.324 3.183) (xy 0.327 3.174) (xy 0.33 3.161) (xy 0.334 3.144)
				(xy 0.339 3.12) (xy 0.345 3.091) (xy 0.352 3.054) (xy 0.361 3.01) (xy 0.371 2.958) (xy 0.382 2.897)
				(xy 0.385 2.878) (xy 0.395 2.824) (xy 0.405 2.772) (xy 0.414 2.724) (xy 0.423 2.68) (xy 0.43 2.642)
				(xy 0.437 2.61) (xy 0.442 2.586) (xy 0.446 2.569) (xy 0.448 2.562) (xy 0.456 2.55) (xy 0.464 2.544)
				(xy 0.476 2.539) (xy 0.495 2.53) (xy 0.521 2.519) (xy 0.552 2.506) (xy 0.587 2.492) (xy 0.624 2.477)
				(xy 0.664 2.461) (xy 0.704 2.445) (xy 0.743 2.43) (xy 0.78 2.415) (xy 0.814 2.402) (xy 0.843 2.391)
				(xy 0.868 2.382) (xy 0.885 2.376) (xy 0.895 2.373) (xy 0.896 2.373) (xy 0.911 2.376) (xy 0.931 2.386)
				(xy 0.948 2.397) (xy 0.962 2.406) (xy 0.983 2.421) (xy 1.011 2.44) (xy 1.043 2.462) (xy 1.079 2.487)
				(xy 1.118 2.513) (xy 1.158 2.541) (xy 1.198 2.568) (xy 1.238 2.595) (xy 1.275 2.621) (xy 1.309 2.644)
				(xy 1.338 2.665) (xy 1.362 2.681) (xy 1.377 2.691) (xy 1.398 2.705) (xy 1.418 2.717) (xy 1.433 2.725)
				(xy 1.442 2.728) (xy 1.443 2.728) (xy 1.448 2.726) (xy 1.456 2.72) (xy 1.468 2.71) (xy 1.486 2.694)
				(xy 1.508 2.673) (xy 1.535 2.647) (xy 1.568 2.614) (xy 1.608 2.575) (xy 1.654 2.53) (xy 1.675 2.509)
				(xy 1.721 2.462) (xy 1.761 2.422) (xy 1.794 2.388) (xy 1.822 2.36) (xy 1.844 2.337) (xy 1.862 2.318)
				(xy 1.875 2.304) (xy 1.884 2.293) (xy 1.89 2.284) (xy 1.893 2.279) (xy 1.894 2.275) (xy 1.892 2.269)
				(xy 1.886 2.257) (xy 1.875 2.239) (xy 1.86 2.215) (xy 1.839 2.183) (xy 1.814 2.145) (xy 1.783 2.1)
				(xy 1.747 2.046) (xy 1.721 2.009) (xy 1.69 1.964) (xy 1.661 1.921) (xy 1.634 1.88) (xy 1.609 1.844)
				(xy 1.588 1.811) (xy 1.57 1.785) (xy 1.557 1.764) (xy 1.549 1.75) (xy 1.546 1.743) (xy 1.547 1.735)
				(xy 1.552 1.719) (xy 1.56 1.696) (xy 1.571 1.667) (xy 1.585 1.634) (xy 1.6 1.597) (xy 1.616 1.557)
				(xy 1.633 1.516) (xy 1.651 1.476) (xy 1.668 1.436) (xy 1.685 1.398) (xy 1.701 1.363) (xy 1.715 1.333)
				(xy 1.727 1.309) (xy 1.736 1.291) (xy 1.742 1.281) (xy 1.744 1.279) (xy 1.751 1.277) (xy 1.767 1.273)
				(xy 1.791 1.268) (xy 1.822 1.261) (xy 1.86 1.254) (xy 1.903 1.245) (xy 1.951 1.236) (xy 2.002 1.226)
				(xy 2.049 1.217) (xy 2.103 1.207) (xy 2.154 1.198) (xy 2.201 1.188) (xy 2.244 1.18) (xy 2.281 1.173)
				(xy 2.311 1.166) (xy 2.335 1.161) (xy 2.35 1.157) (xy 2.355 1.156) (xy 2.367 1.148) (xy 2.367 0.834)
				(xy 2.367 0.768) (xy 2.367 0.712) (xy 2.367 0.664) (xy 2.366 0.625) (xy 2.366 0.592) (xy 2.365 0.566)
				(xy 2.364 0.546) (xy 2.363 0.531) (xy 2.361 0.52) (xy 2.358 0.512) (xy 2.355 0.507) (xy 2.352 0.504)
				(xy 2.348 0.503) (xy 2.343 0.501) (xy 2.34 0.501) (xy 2.333 0.499) (xy 2.317 0.496) (xy 2.293 0.492)
				(xy 2.261 0.486) (xy 2.224 0.479) (xy 2.181 0.471) (xy 2.134 0.462) (xy 2.084 0.453) (xy 2.054 0.448)
				(xy 2.002 0.438) (xy 1.953 0.429) (xy 1.907 0.42) (xy 1.866 0.412) (xy 1.831 0.404) (xy 1.802 0.398)
				(xy 1.78 0.394) (xy 1.767 0.391) (xy 1.764 0.39) (xy 1.76 0.387) (xy 1.757 0.384) (xy 1.753 0.379)
				(xy 1.748 0.371) (xy 1.742 0.36) (xy 1.735 0.344) (xy 1.726 0.324) (xy 1.715 0.297) (xy 1.701 0.264)
				(xy 1.685 0.223) (xy 1.665 0.174) (xy 1.653 0.145) (xy 1.63 0.086) (xy 1.61 0.037) (xy 1.594 -0.005)
				(xy 1.582 -0.038) (xy 1.572 -0.064) (xy 1.566 -0.084) (xy 1.562 -0.097) (xy 1.561 -0.104) (xy 1.562 -0.105)
				(xy 1.565 -0.111) (xy 1.574 -0.125) (xy 1.587 -0.146) (xy 1.604 -0.173) (xy 1.626 -0.205) (xy 1.65 -0.241)
				(xy 1.677 -0.281) (xy 1.706 -0.324) (xy 1.729 -0.358) (xy 1.768 -0.413) (xy 1.8 -0.461) (xy 1.827 -0.502)
				(xy 1.85 -0.535) (xy 1.867 -0.562) (xy 1.88 -0.583) (xy 1.889 -0.598) (xy 1.893 -0.608) (xy 1.894 -0.612)
				(xy 1.893 -0.616) (xy 1.89 -0.622) (xy 1.885 -0.63) (xy 1.876 -0.64) (xy 1.863 -0.655) (xy 1.846 -0.673)
				(xy 1.825 -0.695) (xy 1.798 -0.723) (xy 1.765 -0.756) (xy 1.727 -0.795) (xy 1.682 -0.839) (xy 1.635 -0.886)
				(xy 1.595 -0.926) (xy 1.561 -0.96) (xy 1.532 -0.989) (xy 1.508 -1.012) (xy 1.488 -1.03) (xy 1.473 -1.044)
				(xy 1.461 -1.054) (xy 1.452 -1.061) (xy 1.445 -1.065) (xy 1.44 -1.066) (xy 1.438 -1.066) (xy 1.433 -1.064)
				(xy 1.421 -1.055) (xy 1.401 -1.043) (xy 1.376 -1.026) (xy 1.345 -1.005) (xy 1.31 -0.981) (xy 1.27 -0.954)
				(xy 1.228 -0.925) (xy 1.193 -0.901) (xy 1.138 -0.864) (xy 1.089 -0.83) (xy 1.046 -0.802) (xy 1.01 -0.778)
				(xy 0.981 -0.759) (xy 0.96 -0.746) (xy 0.946 -0.738) (xy 0.94 -0.736) (xy 0.932 -0.738) (xy 0.917 -0.745)
				(xy 0.895 -0.755) (xy 0.869 -0.768) (xy 0.84 -0.783) (xy 0.816 -0.795) (xy 0.781 -0.814) (xy 0.753 -0.828)
				(xy 0.732 -0.838) (xy 0.717 -0.845) (xy 0.707 -0.849) (xy 0.699 -0.85) (xy 0.694 -0.849) (xy 0.691 -0.847)
				(xy 0.687 -0.84) (xy 0.682 -0.829) (xy 0.674 -0.814) (xy 0.665 -0.793) (xy 0.653 -0.767) (xy 0.639 -0.735)
				(xy 0.623 -0.696) (xy 0.604 -0.651) (xy 0.582 -0.598) (xy 0.556 -0.538) (xy 0.528 -0.469) (xy 0.496 -0.391)
				(xy 0.47 -0.329) (xy 0.436 -0.247) (xy 0.406 -0.173) (xy 0.379 -0.108) (xy 0.355 -0.05) (xy 0.335 0)
				(xy 0.317 0.043) (xy 0.303 0.079) (xy 0.291 0.11) (xy 0.281 0.135) (xy 0.273 0.155) (xy 0.268 0.171)
				(xy 0.264 0.183) (xy 0.262 0.191) (xy 0.262 0.196) (xy 0.262 0.198) (xy 0.269 0.207) (xy 0.283 0.219)
				(xy 0.302 0.233) (xy 0.303 0.234) (xy 0.354 0.268) (xy 0.398 0.3) (xy 0.435 0.331) (xy 0.469 0.363)
				(xy 0.5 0.397) (xy 0.507 0.405) (xy 0.556 0.472) (xy 0.596 0.543) (xy 0.627 0.619) (xy 0.643 0.672)
				(xy 0.651 0.718) (xy 0.657 0.77) (xy 0.66 0.824) (xy 0.659 0.878) (xy 0.654 0.927) (xy 0.652 0.936)
				(xy 0.634 1.015) (xy 0.607 1.09) (xy 0.571 1.161) (xy 0.528 1.227) (xy 0.477 1.287) (xy 0.419 1.341)
				(xy 0.355 1.387) (xy 0.285 1.426) (xy 0.21 1.456) (xy 0.205 1.458) (xy 0.131 1.477) (xy 0.054 1.487)
				(xy -0.025 1.489) (xy -0.103 1.482) (xy -0.178 1.466) (xy -0.206 1.458) (xy -0.281 1.428) (xy -0.351 1.39)
				(xy -0.416 1.344) (xy -0.474 1.29) (xy -0.526 1.23) (xy -0.571 1.164) (xy -0.607 1.093) (xy -0.63 1.034)
				(xy -0.649 0.96) (xy -0.659 0.883) (xy -0.661 0.804) (xy -0.654 0.726) (xy -0.638 0.651) (xy -0.63 0.623)
				(xy -0.618 0.591) (xy -0.602 0.554) (xy -0.584 0.518) (xy -0.566 0.485) (xy -0.553 0.463) (xy -0.509 0.407)
				(xy -0.457 0.352) (xy -0.397 0.299) (xy -0.33 0.25) (xy -0.289 0.224) (xy -0.273 0.212) (xy -0.263 0.2)
				(xy -0.262 0.197) (xy -0.263 0.19) (xy -0.268 0.175) (xy -0.277 0.151) (xy -0.288 0.121) (xy -0.302 0.084)
				(xy -0.319 0.042) (xy -0.338 -0.005) (xy -0.358 -0.056) (xy -0.381 -0.111) (xy -0.404 -0.168) (xy -0.428 -0.228)
				(xy -0.453 -0.288) (xy -0.478 -0.349) (xy -0.504 -0.41) (xy -0.529 -0.47) (xy -0.553 -0.527) (xy -0.576 -0.583)
				(xy -0.598 -0.635) (xy -0.619 -0.683) (xy -0.638 -0.727) (xy -0.655 -0.765) (xy -0.669 -0.797) (xy -0.68 -0.822)
				(xy -0.689 -0.839) (xy -0.694 -0.848) (xy -0.695 -0.849) (xy -0.699 -0.85) (xy -0.706 -0.849) (xy -0.717 -0.845)
				(xy -0.732 -0.839) (xy -0.752 -0.829) (xy -0.779 -0.815) (xy -0.814 -0.797) (xy -0.817 -0.795) (xy -0.848 -0.779)
				(xy -0.877 -0.764) (xy -0.902 -0.752) (xy -0.922 -0.743) (xy -0.936 -0.737) (xy -0.941 -0.736) (xy -0.949 -0.739)
				(xy -0.964 -0.748) (xy -0.987 -0.761) (xy -1.015 -0.78) (xy -1.05 -0.803) (xy -1.072 -0.818) (xy -1.138 -0.863)
				(xy -1.195 -0.903) (xy -1.245 -0.937) (xy -1.289 -0.966) (xy -1.325 -0.991) (xy -1.356 -1.012) (xy -1.381 -1.029)
				(xy -1.401 -1.042) (xy -1.416 -1.052) (xy -1.427 -1.059) (xy -1.435 -1.064) (xy -1.439 -1.066) (xy -1.44 -1.066)
				(xy -1.449 -1.064) (xy -1.453 -1.061) (xy -1.458 -1.057) (xy -1.47 -1.046) (xy -1.487 -1.029) (xy -1.509 -1.007)
				(xy -1.537 -0.98) (xy -1.568 -0.95) (xy -1.602 -0.915) (xy -1.639 -0.879) (xy -1.678 -0.84) (xy -1.678 -0.839)
				(xy -1.726 -0.792) (xy -1.767 -0.751) (xy -1.801 -0.716) (xy -1.829 -0.687) (xy -1.852 -0.663) (xy -1.869 -0.644)
				(xy -1.882 -0.63) (xy -1.89 -0.62) (xy -1.894 -0.613) (xy -1.895 -0.61) (xy -1.892 -0.603) (xy -1.884 -0.588)
				(xy -1.87 -0.565) (xy -1.85 -0.536) (xy -1.826 -0.499) (xy -1.797 -0.455) (xy -1.763 -0.405) (xy -1.73 -0.358)
				(xy -1.7 -0.313) (xy -1.671 -0.271) (xy -1.645 -0.232) (xy -1.621 -0.197) (xy -1.601 -0.166) (xy -1.584 -0.141)
				(xy -1.572 -0.121) (xy -1.565 -0.109) (xy -1.563 -0.105) (xy -1.563 -0.099) (xy -1.566 -0.087) (xy -1.572 -0.07)
				(xy -1.58 -0.045) (xy -1.592 -0.013) (xy -1.607 0.026) (xy -1.626 0.074) (xy -1.648 0.13) (xy -1.654 0.145)
				(xy -1.676 0.199) (xy -1.695 0.245) (xy -1.71 0.282) (xy -1.723 0.313) (xy -1.733 0.337) (xy -1.741 0.356)
				(xy -1.748 0.369) (xy -1.753 0.379) (xy -1.758 0.385) (xy -1.761 0.388) (xy -1.763 0.389) (xy -1.767 0.39)
				(xy -1.774 0.392) (xy -1.784 0.395) (xy -1.799 0.398) (xy -1.818 0.402) (xy -1.843 0.407) (xy -1.873 0.413)
				(xy -1.91 0.42) (xy -1.954 0.429) (xy -2.005 0.438) (xy -2.065 0.449) (xy -2.133 0.462) (xy -2.211 0.477)
				(xy -2.22 0.478) (xy -2.26 0.486) (xy -2.29 0.491) (xy -2.313 0.496) (xy -2.33 0.499) (xy -2.341 0.502)
				(xy -2.349 0.504) (xy -2.353 0.506) (xy -2.356 0.508) (xy -2.359 0.51) (xy -2.36 0.511) (xy -2.361 0.514)
				(xy -2.363 0.518) (xy -2.364 0.526) (xy -2.365 0.536) (xy -2.366 0.551) (xy -2.366 0.571) (xy -2.367 0.597)
				(xy -2.367 0.629) (xy -2.368 0.668) (xy -2.368 0.715) (xy -2.368 0.771) (xy -2.368 0.834) (xy -2.368 1.148)
				(xy -2.356 1.155) (xy -2.349 1.158) (xy -2.333 1.162) (xy -2.309 1.167) (xy -2.278 1.173) (xy -2.24 1.181)
				(xy -2.197 1.189) (xy -2.149 1.198) (xy -2.098 1.208) (xy -2.051 1.217) (xy -1.996 1.227) (xy -1.945 1.237)
				(xy -1.897 1.246) (xy -1.854 1.254) (xy -1.817 1.262) (xy -1.787 1.268) (xy -1.764 1.273) (xy -1.75 1.277)
				(xy -1.745 1.279) (xy -1.741 1.285) (xy -1.733 1.3) (xy -1.722 1.322) (xy -1.709 1.35) (xy -1.694 1.382)
				(xy -1.677 1.419) (xy -1.66 1.458) (xy -1.642 1.498) (xy -1.625 1.539) (xy -1.608 1.58) (xy -1.592 1.618)
				(xy -1.578 1.653) (xy -1.565 1.684) (xy -1.556 1.709) (xy -1.549 1.729) (xy -1.546 1.74) (xy -1.546 1.742)
				(xy -1.549 1.749) (xy -1.558 1.763) (xy -1.571 1.784) (xy -1.588 1.811) (xy -1.61 1.843) (xy -1.634 1.88)
				(xy -1.661 1.92) (xy -1.691 1.963) (xy -1.722 2.008) (xy -1.762 2.067) (xy -1.796 2.117) (xy -1.825 2.16)
				(xy -1.848 2.196) (xy -1.867 2.225) (xy -1.881 2.247) (xy -1.89 2.262) (xy -1.895 2.272) (xy -1.895 2.275)
				(xy -1.894 2.279) (xy -1.891 2.285) (xy -1.884 2.293) (xy -1.875 2.305) (xy -1.861 2.32) (xy -1.843 2.339)
				(xy -1.82 2.363) (xy -1.792 2.392) (xy -1.758 2.426) (xy -1.718 2.466) (xy -1.676 2.509) (xy -1.627 2.557)
				(xy -1.585 2.599) (xy -1.549 2.634) (xy -1.52 2.663) (xy -1.495 2.686) (xy -1.476 2.704) (xy -1.462 2.716)
				(xy -1.452 2.724) (xy -1.446 2.728) (xy -1.444 2.728) (xy -1.437 2.726) (xy -1.423 2.717) (xy -1.401 2.703)
				(xy -1.372 2.685) (xy -1.337 2.661) (xy -1.295 2.634) (xy -1.248 2.602) (xy -1.196 2.566) (xy -1.173 2.551)
				(xy -1.118 2.513) (xy -1.071 2.481) (xy -1.031 2.454) (xy -0.998 2.432) (xy -0.97 2.413) (xy -0.948 2.399)
				(xy -0.931 2.389) (xy -0.917 2.381) (xy -0.907 2.376) (xy -0.901 2.373) (xy -0.897 2.373) (xy -0.888 2.375)
				(xy -0.87 2.38) (xy -0.845 2.39) (xy -0.813 2.402) (xy -0.774 2.417) (xy -0.73 2.434) (xy -0.681 2.454)
				(xy -0.629 2.475) (xy -0.586 2.493) (xy -0.55 2.508) (xy -0.522 2.52) (xy -0.499 2.529) (xy -0.482 2.537)
				(xy -0.47 2.543) (xy -0.461 2.548) (xy -0.455 2.551) (xy -0.452 2.554) (xy -0.449 2.557) (xy -0.448 2.56)
				(xy -0.447 2.566) (xy -0.443 2.582) (xy -0.438 2.605) (xy -0.432 2.637) (xy -0.425 2.674) (xy -0.417 2.717)
				(xy -0.407 2.765) (xy -0.398 2.817) (xy -0.388 2.871) (xy -0.387 2.876) (xy -0.375 2.94) (xy -0.364 2.995)
				(xy -0.356 3.042) (xy -0.348 3.081) (xy -0.342 3.112) (xy -0.337 3.137) (xy -0.332 3.157) (xy -0.328 3.171)
				(xy -0.325 3.181) (xy -0.323 3.188) (xy -0.32 3.191) (xy -0.32 3.192) (xy -0.317 3.194) (xy -0.313 3.195)
				(xy -0.307 3.197) (xy -0.298 3.198) (xy -0.286 3.199) (xy -0.269 3.199) (xy -0.247 3.2) (xy -0.219 3.2)
				(xy -0.184 3.201) (xy -0.142 3.201) (xy -0.092 3.201) (xy -0.033 3.201) (xy -0.001 3.201) (xy 0.063 3.201)
			)
			(stroke
				(width 0.01)
				(type solid)
			)
			(fill solid)
			(layer "B.Cu")
		)
		(fp_poly
			(pts
				(xy -0.843 -2.558) (xy -0.815 -2.564) (xy -0.794 -2.572) (xy -0.773 -2.581) (xy -0.759 -2.589) (xy -0.738 -2.603)
				(xy -0.783 -2.658) (xy -0.8 -2.677) (xy -0.814 -2.694) (xy -0.825 -2.706) (xy -0.831 -2.712) (xy -0.832 -2.712)
				(xy -0.837 -2.71) (xy -0.847 -2.703) (xy -0.849 -2.702) (xy -0.874 -2.69) (xy -0.904 -2.684) (xy -0.935 -2.685)
				(xy -0.942 -2.686) (xy -0.975 -2.698) (xy -1.001 -2.717) (xy -1.02 -2.741) (xy -1.034 -2.766) (xy -1.039 -3.197)
				(xy -1.164 -3.2) (xy -1.164 -2.565) (xy -1.037 -2.565) (xy -1.037 -2.626) (xy -1.009 -2.604) (xy -0.972 -2.579)
				(xy -0.931 -2.563) (xy -0.887 -2.556) (xy -0.843 -2.558)
			)
			(stroke
				(width 0.01)
				(type solid)
			)
			(fill solid)
			(layer "B.Mask")
		)
		(fp_poly
			(pts
				(xy 1.889 -1.554) (xy 1.907 -1.559) (xy 1.927 -1.566) (xy 1.948 -1.574) (xy 1.966 -1.583) (xy 1.979 -1.592)
				(xy 1.984 -1.597) (xy 1.982 -1.604) (xy 1.974 -1.616) (xy 1.962 -1.633) (xy 1.946 -1.652) (xy 1.945 -1.654)
				(xy 1.929 -1.673) (xy 1.915 -1.689) (xy 1.906 -1.7) (xy 1.901 -1.706) (xy 1.896 -1.705) (xy 1.885 -1.7)
				(xy 1.873 -1.695) (xy 1.84 -1.683) (xy 1.808 -1.68) (xy 1.776 -1.685) (xy 1.747 -1.698) (xy 1.723 -1.717)
				(xy 1.704 -1.742) (xy 1.696 -1.763) (xy 1.695 -1.772) (xy 1.694 -1.79) (xy 1.693 -1.817) (xy 1.692 -1.85)
				(xy 1.692 -1.89) (xy 1.691 -1.934) (xy 1.691 -1.983) (xy 1.691 -2.194) (xy 1.559 -2.194) (xy 1.559 -1.559)
				(xy 1.691 -1.559) (xy 1.691 -1.626) (xy 1.71 -1.607) (xy 1.739 -1.585) (xy 1.775 -1.568) (xy 1.814 -1.556)
				(xy 1.855 -1.552) (xy 1.889 -1.554)
			)
			(stroke
				(width 0.01)
				(type solid)
			)
			(fill solid)
			(layer "B.Mask")
		)
		(fp_poly
			(pts
				(xy -0.837 -1.56) (xy -0.797 -1.576) (xy -0.761 -1.6) (xy -0.73 -1.63) (xy -0.706 -1.667) (xy -0.69 -1.709)
				(xy -0.687 -1.721) (xy -0.685 -1.734) (xy -0.684 -1.757) (xy -0.683 -1.79) (xy -0.682 -1.833) (xy -0.681 -1.884)
				(xy -0.681 -1.945) (xy -0.681 -1.971) (xy -0.681 -2.194) (xy -0.808 -2.194) (xy -0.809 -1.984) (xy -0.811 -1.774)
				(xy -0.826 -1.744) (xy -0.845 -1.716) (xy -0.868 -1.697) (xy -0.897 -1.686) (xy -0.925 -1.682) (xy -0.947 -1.682)
				(xy -0.967 -1.684) (xy -0.979 -1.686) (xy -1.001 -1.698) (xy -1.023 -1.716) (xy -1.041 -1.738) (xy -1.049 -1.752)
				(xy -1.052 -1.758) (xy -1.054 -1.765) (xy -1.056 -1.773) (xy -1.057 -1.783) (xy -1.058 -1.797) (xy -1.059 -1.815)
				(xy -1.06 -1.839) (xy -1.06 -1.869) (xy -1.061 -1.907) (xy -1.061 -1.953) (xy -1.061 -1.985) (xy -1.063 -2.194)
				(xy -1.189 -2.194) (xy -1.189 -1.559) (xy -1.062 -1.559) (xy -1.062 -1.625) (xy -1.033 -1.602) (xy -1.001 -1.579)
				(xy -0.969 -1.564) (xy -0.934 -1.555) (xy -0.927 -1.554) (xy -0.881 -1.553) (xy -0.837 -1.56)
			)
			(stroke
				(width 0.01)
				(type solid)
			)
			(fill solid)
			(layer "B.Mask")
		)
		(fp_poly
			(pts
				(xy 1.042 -1.769) (xy 1.043 -1.979) (xy 1.059 -2.009) (xy 1.077 -2.036) (xy 1.1 -2.056) (xy 1.129 -2.067)
				(xy 1.159 -2.071) (xy 1.193 -2.07) (xy 1.221 -2.063) (xy 1.245 -2.047) (xy 1.258 -2.034) (xy 1.266 -2.025)
				(xy 1.273 -2.016) (xy 1.278 -2.008) (xy 1.282 -1.997) (xy 1.286 -1.985) (xy 1.288 -1.969) (xy 1.29 -1.948)
				(xy 1.291 -1.922) (xy 1.292 -1.89) (xy 1.293 -1.85) (xy 1.293 -1.801) (xy 1.294 -1.766) (xy 1.295 -1.559)
				(xy 1.422 -1.559) (xy 1.422 -2.194) (xy 1.295 -2.194) (xy 1.295 -2.161) (xy 1.295 -2.144) (xy 1.293 -2.132)
				(xy 1.292 -2.128) (xy 1.287 -2.131) (xy 1.278 -2.14) (xy 1.271 -2.147) (xy 1.256 -2.159) (xy 1.236 -2.171)
				(xy 1.219 -2.181) (xy 1.202 -2.188) (xy 1.186 -2.193) (xy 1.17 -2.196) (xy 1.148 -2.197) (xy 1.135 -2.198)
				(xy 1.107 -2.198) (xy 1.087 -2.197) (xy 1.07 -2.194) (xy 1.059 -2.19) (xy 1.036 -2.181) (xy 1.019 -2.172)
				(xy 1.003 -2.161) (xy 0.985 -2.146) (xy 0.981 -2.141) (xy 0.952 -2.107) (xy 0.931 -2.068) (xy 0.92 -2.033)
				(xy 0.918 -2.019) (xy 0.917 -1.996) (xy 0.916 -1.963) (xy 0.915 -1.92) (xy 0.914 -1.869) (xy 0.914 -1.808)
				(xy 0.914 -1.782) (xy 0.914 -1.559) (xy 1.04 -1.559) (xy 1.042 -1.769)
			)
			(stroke
				(width 0.01)
				(type solid)
			)
			(fill solid)
			(layer "B.Mask")
		)
		(fp_poly
			(pts
				(xy 1.753 -2.563) (xy 1.768 -2.568) (xy 1.787 -2.577) (xy 1.804 -2.586) (xy 1.818 -2.595) (xy 1.826 -2.602)
				(xy 1.827 -2.606) (xy 1.824 -2.611) (xy 1.815 -2.621) (xy 1.803 -2.636) (xy 1.789 -2.654) (xy 1.775 -2.671)
				(xy 1.761 -2.688) (xy 1.749 -2.701) (xy 1.742 -2.71) (xy 1.739 -2.712) (xy 1.735 -2.71) (xy 1.724 -2.704)
				(xy 1.713 -2.698) (xy 1.697 -2.69) (xy 1.682 -2.686) (xy 1.664 -2.685) (xy 1.653 -2.685) (xy 1.618 -2.688)
				(xy 1.59 -2.699) (xy 1.566 -2.718) (xy 1.561 -2.723) (xy 1.554 -2.732) (xy 1.548 -2.74) (xy 1.544 -2.748)
				(xy 1.54 -2.758) (xy 1.537 -2.769) (xy 1.534 -2.785) (xy 1.533 -2.804) (xy 1.532 -2.829) (xy 1.531 -2.861)
				(xy 1.53 -2.899) (xy 1.53 -2.947) (xy 1.53 -2.988) (xy 1.528 -3.2) (xy 1.468 -3.2) (xy 1.444 -3.2)
				(xy 1.425 -3.199) (xy 1.411 -3.198) (xy 1.405 -3.197) (xy 1.404 -3.191) (xy 1.404 -3.176) (xy 1.403 -3.153)
				(xy 1.403 -3.122) (xy 1.402 -3.085) (xy 1.402 -3.042) (xy 1.402 -2.993) (xy 1.402 -2.941) (xy 1.402 -2.886)
				(xy 1.402 -2.565) (xy 1.529 -2.565) (xy 1.529 -2.595) (xy 1.529 -2.611) (xy 1.53 -2.623) (xy 1.532 -2.626)
				(xy 1.537 -2.623) (xy 1.547 -2.615) (xy 1.554 -2.608) (xy 1.588 -2.584) (xy 1.627 -2.567) (xy 1.669 -2.558)
				(xy 1.712 -2.556) (xy 1.753 -2.563)
			)
			(stroke
				(width 0.01)
				(type solid)
			)
			(fill solid)
			(layer "B.Mask")
		)
		(fp_poly
			(pts
				(xy 2.316 -1.557) (xy 2.365 -1.57) (xy 2.41 -1.593) (xy 2.453 -1.625) (xy 2.46 -1.631) (xy 2.491 -1.661)
				(xy 2.466 -1.684) (xy 2.448 -1.699) (xy 2.43 -1.715) (xy 2.419 -1.725) (xy 2.397 -1.743) (xy 2.376 -1.724)
				(xy 2.345 -1.701) (xy 2.312 -1.687) (xy 2.274 -1.681) (xy 2.265 -1.681) (xy 2.226 -1.684) (xy 2.195 -1.693)
				(xy 2.167 -1.708) (xy 2.159 -1.715) (xy 2.136 -1.741) (xy 2.118 -1.776) (xy 2.107 -1.817) (xy 2.103 -1.866)
				(xy 2.103 -1.876) (xy 2.106 -1.926) (xy 2.116 -1.97) (xy 2.132 -2.006) (xy 2.155 -2.034) (xy 2.184 -2.055)
				(xy 2.219 -2.067) (xy 2.259 -2.072) (xy 2.274 -2.071) (xy 2.309 -2.066) (xy 2.339 -2.056) (xy 2.366 -2.038)
				(xy 2.377 -2.028) (xy 2.386 -2.02) (xy 2.393 -2.016) (xy 2.4 -2.015) (xy 2.409 -2.018) (xy 2.42 -2.027)
				(xy 2.436 -2.041) (xy 2.456 -2.059) (xy 2.491 -2.092) (xy 2.476 -2.108) (xy 2.449 -2.132) (xy 2.416 -2.155)
				(xy 2.38 -2.174) (xy 2.35 -2.186) (xy 2.327 -2.193) (xy 2.306 -2.197) (xy 2.283 -2.199) (xy 2.259 -2.199)
				(xy 2.233 -2.198) (xy 2.209 -2.196) (xy 2.189 -2.193) (xy 2.182 -2.191) (xy 2.133 -2.173) (xy 2.089 -2.146)
				(xy 2.053 -2.112) (xy 2.023 -2.071) (xy 2.012 -2.051) (xy 2 -2.023) (xy 1.991 -1.999) (xy 1.984 -1.975)
				(xy 1.981 -1.948) (xy 1.979 -1.917) (xy 1.978 -1.879) (xy 1.978 -1.877) (xy 1.979 -1.838) (xy 1.98 -1.806)
				(xy 1.984 -1.78) (xy 1.99 -1.756) (xy 1.999 -1.731) (xy 2.011 -1.704) (xy 2.012 -1.701) (xy 2.039 -1.657)
				(xy 2.072 -1.62) (xy 2.111 -1.591) (xy 2.156 -1.57) (xy 2.207 -1.557) (xy 2.263 -1.552) (xy 2.316 -1.557)
			)
			(stroke
				(width 0.01)
				(type solid)
			)
			(fill solid)
			(layer "B.Mask")
		)
		(fp_poly
			(pts
				(xy -1.494 -1.56) (xy -1.447 -1.576) (xy -1.405 -1.6) (xy -1.368 -1.633) (xy -1.341 -1.668) (xy -1.326 -1.692)
				(xy -1.316 -1.716) (xy -1.308 -1.743) (xy -1.302 -1.774) (xy -1.299 -1.811) (xy -1.297 -1.845) (xy -1.294 -1.925)
				(xy -1.692 -1.925) (xy -1.692 -1.942) (xy -1.687 -1.977) (xy -1.673 -2.011) (xy -1.65 -2.039) (xy -1.626 -2.059)
				(xy -1.601 -2.071) (xy -1.572 -2.078) (xy -1.537 -2.079) (xy -1.497 -2.074) (xy -1.458 -2.06) (xy -1.422 -2.036)
				(xy -1.421 -2.036) (xy -1.402 -2.021) (xy -1.359 -2.057) (xy -1.342 -2.072) (xy -1.327 -2.085) (xy -1.317 -2.094)
				(xy -1.314 -2.098) (xy -1.316 -2.103) (xy -1.324 -2.113) (xy -1.338 -2.126) (xy -1.354 -2.139) (xy -1.372 -2.152)
				(xy -1.389 -2.163) (xy -1.399 -2.168) (xy -1.421 -2.178) (xy -1.445 -2.187) (xy -1.461 -2.191) (xy -1.488 -2.196)
				(xy -1.522 -2.199) (xy -1.557 -2.199) (xy -1.591 -2.196) (xy -1.62 -2.192) (xy -1.629 -2.19) (xy -1.677 -2.171)
				(xy -1.718 -2.146) (xy -1.752 -2.114) (xy -1.779 -2.074) (xy -1.8 -2.026) (xy -1.802 -2.02) (xy -1.81 -1.989)
				(xy -1.815 -1.951) (xy -1.818 -1.908) (xy -1.819 -1.865) (xy -1.818 -1.823) (xy -1.816 -1.804) (xy -1.692 -1.804)
				(xy -1.692 -1.818) (xy -1.428 -1.818) (xy -1.428 -1.801) (xy -1.432 -1.775) (xy -1.442 -1.748) (xy -1.457 -1.722)
				(xy -1.469 -1.707) (xy -1.495 -1.688) (xy -1.526 -1.676) (xy -1.56 -1.672) (xy -1.593 -1.676) (xy -1.619 -1.685)
				(xy -1.646 -1.704) (xy -1.668 -1.73) (xy -1.683 -1.76) (xy -1.691 -1.792) (xy -1.692 -1.804) (xy -1.816 -1.804)
				(xy -1.814 -1.786) (xy -1.812 -1.777) (xy -1.797 -1.724) (xy -1.775 -1.676) (xy -1.747 -1.636) (xy -1.713 -1.603)
				(xy -1.673 -1.578) (xy -1.629 -1.561) (xy -1.597 -1.554) (xy -1.544 -1.552) (xy -1.494 -1.56)
			)
			(stroke
				(width 0.01)
				(type solid)
			)
			(fill solid)
			(layer "B.Mask")
		)
		(fp_poly
			(pts
				(xy 2.835 -1.557) (xy 2.883 -1.57) (xy 2.926 -1.592) (xy 2.964 -1.621) (xy 2.996 -1.657) (xy 3.021 -1.699)
				(xy 3.038 -1.747) (xy 3.04 -1.757) (xy 3.043 -1.776) (xy 3.045 -1.802) (xy 3.047 -1.832) (xy 3.047 -1.858)
				(xy 3.047 -1.925) (xy 2.65 -1.925) (xy 2.653 -1.951) (xy 2.663 -1.991) (xy 2.68 -2.024) (xy 2.703 -2.049)
				(xy 2.733 -2.067) (xy 2.77 -2.077) (xy 2.801 -2.079) (xy 2.845 -2.075) (xy 2.883 -2.063) (xy 2.916 -2.042)
				(xy 2.92 -2.039) (xy 2.929 -2.031) (xy 2.935 -2.026) (xy 2.941 -2.025) (xy 2.949 -2.027) (xy 2.959 -2.034)
				(xy 2.974 -2.047) (xy 2.994 -2.064) (xy 3.01 -2.078) (xy 3.023 -2.088) (xy 3.03 -2.095) (xy 3.032 -2.096)
				(xy 3.03 -2.1) (xy 3.022 -2.11) (xy 3.01 -2.122) (xy 3.009 -2.123) (xy 2.98 -2.147) (xy 2.945 -2.169)
				(xy 2.906 -2.185) (xy 2.887 -2.191) (xy 2.861 -2.196) (xy 2.828 -2.198) (xy 2.793 -2.198) (xy 2.759 -2.197)
				(xy 2.729 -2.193) (xy 2.721 -2.191) (xy 2.675 -2.175) (xy 2.634 -2.15) (xy 2.599 -2.118) (xy 2.569 -2.077)
				(xy 2.547 -2.029) (xy 2.536 -1.996) (xy 2.532 -1.973) (xy 2.529 -1.942) (xy 2.527 -1.906) (xy 2.527 -1.869)
				(xy 2.528 -1.832) (xy 2.529 -1.818) (xy 2.65 -1.818) (xy 2.922 -1.818) (xy 2.918 -1.799) (xy 2.908 -1.758)
				(xy 2.891 -1.725) (xy 2.869 -1.7) (xy 2.84 -1.683) (xy 2.826 -1.678) (xy 2.788 -1.672) (xy 2.753 -1.675)
				(xy 2.722 -1.687) (xy 2.695 -1.706) (xy 2.674 -1.734) (xy 2.659 -1.768) (xy 2.654 -1.794) (xy 2.65 -1.818)
				(xy 2.529 -1.818) (xy 2.53 -1.798) (xy 2.534 -1.769) (xy 2.536 -1.76) (xy 2.554 -1.707) (xy 2.578 -1.662)
				(xy 2.609 -1.624) (xy 2.645 -1.593) (xy 2.687 -1.571) (xy 2.734 -1.557) (xy 2.783 -1.553) (xy 2.835 -1.557)
			)
			(stroke
				(width 0.01)
				(type solid)
			)
			(fill solid)
			(layer "B.Mask")
		)
		(fp_poly
			(pts
				(xy 2.148 -2.561) (xy 2.193 -2.574) (xy 2.235 -2.595) (xy 2.273 -2.623) (xy 2.304 -2.657) (xy 2.326 -2.691)
				(xy 2.338 -2.718) (xy 2.346 -2.745) (xy 2.352 -2.774) (xy 2.355 -2.808) (xy 2.357 -2.85) (xy 2.357 -2.858)
				(xy 2.357 -2.931) (xy 1.96 -2.931) (xy 1.963 -2.955) (xy 1.973 -2.993) (xy 1.991 -3.026) (xy 2.015 -3.053)
				(xy 2.039 -3.069) (xy 2.057 -3.076) (xy 2.08 -3.08) (xy 2.103 -3.082) (xy 2.144 -3.081) (xy 2.18 -3.071)
				(xy 2.214 -3.054) (xy 2.227 -3.045) (xy 2.24 -3.035) (xy 2.25 -3.029) (xy 2.253 -3.027) (xy 2.258 -3.03)
				(xy 2.269 -3.039) (xy 2.284 -3.05) (xy 2.3 -3.064) (xy 2.315 -3.078) (xy 2.329 -3.09) (xy 2.338 -3.099)
				(xy 2.341 -3.103) (xy 2.337 -3.11) (xy 2.327 -3.121) (xy 2.312 -3.134) (xy 2.294 -3.148) (xy 2.276 -3.161)
				(xy 2.259 -3.171) (xy 2.252 -3.175) (xy 2.204 -3.192) (xy 2.152 -3.202) (xy 2.098 -3.204) (xy 2.046 -3.198)
				(xy 2.032 -3.195) (xy 1.984 -3.178) (xy 1.943 -3.154) (xy 1.909 -3.123) (xy 1.881 -3.084) (xy 1.859 -3.037)
				(xy 1.847 -3.003) (xy 1.841 -2.972) (xy 1.838 -2.934) (xy 1.836 -2.893) (xy 1.837 -2.851) (xy 1.839 -2.824)
				(xy 1.96 -2.824) (xy 2.23 -2.824) (xy 2.23 -2.813) (xy 2.225 -2.783) (xy 2.214 -2.753) (xy 2.196 -2.725)
				(xy 2.175 -2.702) (xy 2.151 -2.686) (xy 2.128 -2.68) (xy 2.101 -2.677) (xy 2.072 -2.678) (xy 2.051 -2.683)
				(xy 2.023 -2.696) (xy 2 -2.717) (xy 1.981 -2.746) (xy 1.968 -2.779) (xy 1.963 -2.8) (xy 1.96 -2.824)
				(xy 1.839 -2.824) (xy 1.839 -2.811) (xy 1.844 -2.776) (xy 1.848 -2.76) (xy 1.866 -2.708) (xy 1.889 -2.663)
				(xy 1.919 -2.627) (xy 1.954 -2.598) (xy 1.996 -2.575) (xy 2.007 -2.571) (xy 2.054 -2.559) (xy 2.101 -2.556)
				(xy 2.148 -2.561)
			)
			(stroke
				(width 0.01)
				(type solid)
			)
			(fill solid)
			(layer "B.Mask")
		)
		(fp_poly
			(pts
				(xy -2.733 -1.557) (xy -2.685 -1.57) (xy -2.642 -1.592) (xy -2.604 -1.622) (xy -2.581 -1.649) (xy -2.562 -1.676)
				(xy -2.548 -1.706) (xy -2.537 -1.739) (xy -2.53 -1.777) (xy -2.527 -1.821) (xy -2.526 -1.873) (xy -2.527 -1.907)
				(xy -2.529 -1.956) (xy -2.534 -1.997) (xy -2.542 -2.031) (xy -2.553 -2.06) (xy -2.567 -2.086) (xy -2.587 -2.111)
				(xy -2.603 -2.129) (xy -2.637 -2.158) (xy -2.673 -2.178) (xy -2.714 -2.192) (xy -2.76 -2.198) (xy -2.789 -2.199)
				(xy -2.813 -2.198) (xy -2.835 -2.196) (xy -2.852 -2.194) (xy -2.857 -2.194) (xy -2.898 -2.179) (xy -2.937 -2.155)
				(xy -2.97 -2.126) (xy -2.993 -2.101) (xy -3.011 -2.077) (xy -3.024 -2.051) (xy -3.034 -2.022) (xy -3.041 -1.988)
				(xy -3.045 -1.947) (xy -3.047 -1.91) (xy -3.047 -1.882) (xy -2.919 -1.882) (xy -2.919 -1.968) (xy -2.903 -2.001)
				(xy -2.885 -2.031) (xy -2.863 -2.051) (xy -2.837 -2.064) (xy -2.804 -2.07) (xy -2.779 -2.07) (xy -2.755 -2.069)
				(xy -2.737 -2.065) (xy -2.722 -2.058) (xy -2.717 -2.055) (xy -2.697 -2.041) (xy -2.681 -2.025) (xy -2.67 -2.004)
				(xy -2.662 -1.978) (xy -2.657 -1.945) (xy -2.654 -1.903) (xy -2.654 -1.899) (xy -2.653 -1.848) (xy -2.656 -1.806)
				(xy -2.662 -1.772) (xy -2.673 -1.744) (xy -2.687 -1.722) (xy -2.707 -1.705) (xy -2.723 -1.695) (xy -2.755 -1.684)
				(xy -2.788 -1.68) (xy -2.821 -1.684) (xy -2.851 -1.695) (xy -2.877 -1.713) (xy -2.892 -1.729) (xy -2.901 -1.745)
				(xy -2.908 -1.76) (xy -2.913 -1.778) (xy -2.916 -1.8) (xy -2.918 -1.828) (xy -2.919 -1.864) (xy -2.919 -1.882)
				(xy -3.047 -1.882) (xy -3.048 -1.844) (xy -3.043 -1.786) (xy -3.034 -1.736) (xy -3.021 -1.695) (xy -3.004 -1.664)
				(xy -2.972 -1.624) (xy -2.935 -1.594) (xy -2.893 -1.571) (xy -2.846 -1.558) (xy -2.794 -1.553) (xy -2.787 -1.553)
				(xy -2.733 -1.557)
			)
			(stroke
				(width 0.01)
				(type solid)
			)
			(fill solid)
			(layer "B.Mask")
		)
		(fp_poly
			(pts
				(xy -0.229 -3.2) (xy -0.354 -3.197) (xy -0.355 -3.165) (xy -0.357 -3.133) (xy -0.374 -3.148) (xy -0.411 -3.175)
				(xy -0.453 -3.193) (xy -0.497 -3.203) (xy -0.542 -3.204) (xy -0.585 -3.195) (xy -0.586 -3.195) (xy -0.621 -3.181)
				(xy -0.651 -3.16) (xy -0.673 -3.141) (xy -0.689 -3.123) (xy -0.702 -3.106) (xy -0.712 -3.086) (xy -0.72 -3.064)
				(xy -0.726 -3.038) (xy -0.73 -3.007) (xy -0.732 -2.968) (xy -0.733 -2.922) (xy -0.733 -2.88) (xy -0.602 -2.88)
				(xy -0.602 -2.915) (xy -0.602 -2.942) (xy -0.601 -2.962) (xy -0.6 -2.977) (xy -0.598 -2.988) (xy -0.596 -2.998)
				(xy -0.592 -3.007) (xy -0.591 -3.01) (xy -0.574 -3.039) (xy -0.552 -3.059) (xy -0.525 -3.071) (xy -0.492 -3.076)
				(xy -0.472 -3.076) (xy -0.442 -3.072) (xy -0.418 -3.063) (xy -0.398 -3.048) (xy -0.382 -3.029) (xy -0.371 -3.004)
				(xy -0.363 -2.972) (xy -0.358 -2.933) (xy -0.356 -2.885) (xy -0.356 -2.88) (xy -0.358 -2.828) (xy -0.363 -2.785)
				(xy -0.373 -2.75) (xy -0.387 -2.724) (xy -0.406 -2.704) (xy -0.43 -2.692) (xy -0.46 -2.686) (xy -0.483 -2.685)
				(xy -0.517 -2.687) (xy -0.544 -2.696) (xy -0.565 -2.711) (xy -0.583 -2.734) (xy -0.591 -2.751) (xy -0.595 -2.76)
				(xy -0.598 -2.769) (xy -0.6 -2.779) (xy -0.601 -2.793) (xy -0.602 -2.811) (xy -0.602 -2.836) (xy -0.602 -2.869)
				(xy -0.602 -2.88) (xy -0.733 -2.88) (xy -0.733 -2.827) (xy -0.732 -2.783) (xy -0.729 -2.746) (xy -0.725 -2.716)
				(xy -0.719 -2.691) (xy -0.71 -2.67) (xy -0.699 -2.651) (xy -0.685 -2.633) (xy -0.668 -2.616) (xy -0.668 -2.615)
				(xy -0.632 -2.587) (xy -0.592 -2.567) (xy -0.55 -2.557) (xy -0.506 -2.556) (xy -0.463 -2.564) (xy -0.421 -2.582)
				(xy -0.411 -2.587) (xy -0.394 -2.598) (xy -0.377 -2.61) (xy -0.373 -2.614) (xy -0.356 -2.627) (xy -0.356 -2.306)
				(xy -0.229 -2.306) (xy -0.229 -3.2)
			)
			(stroke
				(width 0.01)
				(type solid)
			)
			(fill solid)
			(layer "B.Mask")
		)
		(fp_poly
			(pts
				(xy 0.605 -1.558) (xy 0.651 -1.574) (xy 0.694 -1.598) (xy 0.728 -1.627) (xy 0.75 -1.652) (xy 0.768 -1.678)
				(xy 0.781 -1.707) (xy 0.791 -1.739) (xy 0.797 -1.777) (xy 0.801 -1.822) (xy 0.802 -1.876) (xy 0.802 -1.877)
				(xy 0.801 -1.929) (xy 0.798 -1.973) (xy 0.792 -2.009) (xy 0.784 -2.04) (xy 0.774 -2.062) (xy 0.748 -2.103)
				(xy 0.715 -2.139) (xy 0.675 -2.167) (xy 0.632 -2.187) (xy 0.626 -2.189) (xy 0.599 -2.195) (xy 0.567 -2.198)
				(xy 0.532 -2.199) (xy 0.499 -2.197) (xy 0.471 -2.193) (xy 0.466 -2.192) (xy 0.428 -2.177) (xy 0.391 -2.155)
				(xy 0.359 -2.129) (xy 0.354 -2.123) (xy 0.332 -2.098) (xy 0.316 -2.073) (xy 0.303 -2.047) (xy 0.294 -2.017)
				(xy 0.287 -1.983) (xy 0.284 -1.943) (xy 0.282 -1.894) (xy 0.282 -1.877) (xy 0.409 -1.877) (xy 0.41 -1.918)
				(xy 0.412 -1.95) (xy 0.416 -1.976) (xy 0.423 -1.997) (xy 0.432 -2.015) (xy 0.445 -2.03) (xy 0.451 -2.037)
				(xy 0.471 -2.054) (xy 0.491 -2.064) (xy 0.514 -2.07) (xy 0.543 -2.072) (xy 0.569 -2.07) (xy 0.59 -2.065)
				(xy 0.601 -2.06) (xy 0.625 -2.047) (xy 0.642 -2.031) (xy 0.656 -2.009) (xy 0.661 -1.998) (xy 0.665 -1.989)
				(xy 0.668 -1.98) (xy 0.67 -1.969) (xy 0.671 -1.954) (xy 0.672 -1.935) (xy 0.673 -1.909) (xy 0.673 -1.877)
				(xy 0.673 -1.842) (xy 0.672 -1.817) (xy 0.671 -1.798) (xy 0.67 -1.784) (xy 0.668 -1.773) (xy 0.665 -1.764)
				(xy 0.661 -1.755) (xy 0.647 -1.73) (xy 0.632 -1.712) (xy 0.612 -1.698) (xy 0.601 -1.693) (xy 0.569 -1.683)
				(xy 0.535 -1.681) (xy 0.501 -1.686) (xy 0.471 -1.7) (xy 0.447 -1.719) (xy 0.434 -1.736) (xy 0.424 -1.753)
				(xy 0.417 -1.774) (xy 0.412 -1.8) (xy 0.41 -1.833) (xy 0.409 -1.873) (xy 0.409 -1.877) (xy 0.282 -1.877)
				(xy 0.283 -1.824) (xy 0.286 -1.78) (xy 0.292 -1.742) (xy 0.301 -1.711) (xy 0.313 -1.683) (xy 0.33 -1.657)
				(xy 0.35 -1.633) (xy 0.351 -1.632) (xy 0.385 -1.601) (xy 0.42 -1.578) (xy 0.46 -1.563) (xy 0.505 -1.554)
				(xy 0.555 -1.551) (xy 0.605 -1.558)
			)
			(stroke
				(width 0.01)
				(type solid)
			)
			(fill solid)
			(layer "B.Mask")
		)
		(fp_poly
			(pts
				(xy 0.004 -1.556) (xy 0.054 -1.566) (xy 0.102 -1.582) (xy 0.146 -1.605) (xy 0.154 -1.61) (xy 0.193 -1.636)
				(xy 0.178 -1.655) (xy 0.166 -1.668) (xy 0.152 -1.686) (xy 0.138 -1.7) (xy 0.114 -1.727) (xy 0.07 -1.705)
				(xy 0.032 -1.688) (xy -0.007 -1.677) (xy -0.044 -1.672) (xy -0.079 -1.672) (xy -0.11 -1.678) (xy -0.136 -1.69)
				(xy -0.154 -1.707) (xy -0.162 -1.724) (xy -0.164 -1.745) (xy -0.164 -1.761) (xy -0.159 -1.772) (xy -0.15 -1.782)
				(xy -0.149 -1.783) (xy -0.139 -1.791) (xy -0.128 -1.797) (xy -0.114 -1.802) (xy -0.095 -1.805) (xy -0.07 -1.808)
				(xy -0.037 -1.811) (xy -0.02 -1.813) (xy 0.027 -1.817) (xy 0.065 -1.823) (xy 0.096 -1.832) (xy 0.122 -1.842)
				(xy 0.14 -1.854) (xy 0.166 -1.879) (xy 0.186 -1.91) (xy 0.2 -1.947) (xy 0.206 -1.987) (xy 0.206 -2.018)
				(xy 0.198 -2.06) (xy 0.181 -2.097) (xy 0.155 -2.129) (xy 0.122 -2.156) (xy 0.08 -2.177) (xy 0.042 -2.189)
				(xy 0.005 -2.196) (xy -0.038 -2.199) (xy -0.083 -2.198) (xy -0.125 -2.194) (xy -0.153 -2.189) (xy -0.177 -2.181)
				(xy -0.204 -2.171) (xy -0.229 -2.16) (xy -0.232 -2.159) (xy -0.251 -2.148) (xy -0.272 -2.136) (xy -0.292 -2.122)
				(xy -0.309 -2.109) (xy -0.323 -2.098) (xy -0.33 -2.09) (xy -0.331 -2.088) (xy -0.327 -2.084) (xy -0.318 -2.073)
				(xy -0.304 -2.059) (xy -0.288 -2.043) (xy -0.246 -2) (xy -0.221 -2.021) (xy -0.184 -2.047) (xy -0.145 -2.065)
				(xy -0.102 -2.075) (xy -0.053 -2.079) (xy -0.049 -2.079) (xy -0.023 -2.079) (xy -0.004 -2.078) (xy 0.011 -2.074)
				(xy 0.025 -2.069) (xy 0.029 -2.068) (xy 0.054 -2.052) (xy 0.071 -2.033) (xy 0.079 -2.01) (xy 0.078 -1.986)
				(xy 0.074 -1.975) (xy 0.068 -1.964) (xy 0.06 -1.956) (xy 0.048 -1.949) (xy 0.031 -1.944) (xy 0.007 -1.939)
				(xy -0.024 -1.935) (xy -0.052 -1.932) (xy -0.089 -1.929) (xy -0.119 -1.925) (xy -0.142 -1.921) (xy -0.16 -1.917)
				(xy -0.176 -1.912) (xy -0.192 -1.906) (xy -0.201 -1.901) (xy -0.235 -1.879) (xy -0.262 -1.85) (xy -0.28 -1.816)
				(xy -0.29 -1.776) (xy -0.292 -1.75) (xy -0.291 -1.727) (xy -0.289 -1.705) (xy -0.286 -1.689) (xy -0.286 -1.688)
				(xy -0.273 -1.659) (xy -0.253 -1.63) (xy -0.229 -1.604) (xy -0.221 -1.599) (xy -0.185 -1.577) (xy -0.143 -1.562)
				(xy -0.096 -1.554) (xy -0.047 -1.552) (xy 0.004 -1.556)
			)
			(stroke
				(width 0.01)
				(type solid)
			)
			(fill solid)
			(layer "B.Mask")
		)
		(fp_poly
			(pts
				(xy 1.038 -2.556) (xy 1.091 -2.563) (xy 1.137 -2.576) (xy 1.177 -2.595) (xy 1.209 -2.62) (xy 1.234 -2.65)
				(xy 1.242 -2.665) (xy 1.247 -2.677) (xy 1.251 -2.691) (xy 1.255 -2.708) (xy 1.258 -2.727) (xy 1.26 -2.751)
				(xy 1.262 -2.78) (xy 1.263 -2.815) (xy 1.263 -2.858) (xy 1.264 -2.908) (xy 1.263 -2.967) (xy 1.263 -2.989)
				(xy 1.262 -3.197) (xy 1.135 -3.197) (xy 1.133 -3.171) (xy 1.132 -3.144) (xy 1.119 -3.159) (xy 1.096 -3.179)
				(xy 1.065 -3.193) (xy 1.026 -3.202) (xy 0.98 -3.204) (xy 0.976 -3.204) (xy 0.955 -3.204) (xy 0.937 -3.203)
				(xy 0.925 -3.202) (xy 0.924 -3.201) (xy 0.879 -3.189) (xy 0.839 -3.17) (xy 0.806 -3.144) (xy 0.781 -3.113)
				(xy 0.763 -3.077) (xy 0.753 -3.037) (xy 0.753 -3.005) (xy 0.873 -3.005) (xy 0.874 -3.023) (xy 0.878 -3.035)
				(xy 0.887 -3.047) (xy 0.89 -3.05) (xy 0.903 -3.063) (xy 0.917 -3.072) (xy 0.935 -3.078) (xy 0.957 -3.081)
				(xy 0.986 -3.082) (xy 1.013 -3.082) (xy 1.043 -3.081) (xy 1.065 -3.079) (xy 1.08 -3.077) (xy 1.091 -3.073)
				(xy 1.096 -3.071) (xy 1.112 -3.058) (xy 1.123 -3.039) (xy 1.13 -3.012) (xy 1.132 -2.977) (xy 1.132 -2.975)
				(xy 1.132 -2.931) (xy 1.035 -2.931) (xy 0.999 -2.931) (xy 0.973 -2.931) (xy 0.953 -2.932) (xy 0.939 -2.934)
				(xy 0.928 -2.936) (xy 0.919 -2.939) (xy 0.916 -2.94) (xy 0.893 -2.954) (xy 0.88 -2.971) (xy 0.874 -2.994)
				(xy 0.873 -3.005) (xy 0.753 -3.005) (xy 0.753 -2.994) (xy 0.761 -2.951) (xy 0.768 -2.931) (xy 0.776 -2.915)
				(xy 0.786 -2.901) (xy 0.802 -2.884) (xy 0.804 -2.882) (xy 0.82 -2.867) (xy 0.835 -2.854) (xy 0.85 -2.845)
				(xy 0.867 -2.838) (xy 0.887 -2.833) (xy 0.912 -2.829) (xy 0.943 -2.827) (xy 0.982 -2.826) (xy 1.015 -2.825)
				(xy 1.133 -2.823) (xy 1.132 -2.771) (xy 1.131 -2.746) (xy 1.129 -2.73) (xy 1.127 -2.719) (xy 1.123 -2.711)
				(xy 1.117 -2.705) (xy 1.098 -2.691) (xy 1.07 -2.682) (xy 1.032 -2.677) (xy 1.006 -2.677) (xy 0.972 -2.678)
				(xy 0.945 -2.682) (xy 0.924 -2.688) (xy 0.907 -2.699) (xy 0.9 -2.706) (xy 0.882 -2.723) (xy 0.834 -2.686)
				(xy 0.816 -2.672) (xy 0.801 -2.66) (xy 0.79 -2.652) (xy 0.787 -2.648) (xy 0.791 -2.639) (xy 0.801 -2.626)
				(xy 0.816 -2.612) (xy 0.832 -2.6) (xy 0.864 -2.581) (xy 0.902 -2.568) (xy 0.946 -2.559) (xy 0.98 -2.556)
				(xy 1.038 -2.556)
			)
			(stroke
				(width 0.01)
				(type solid)
			)
			(fill solid)
			(layer "B.Mask")
		)
		(fp_poly
			(pts
				(xy -1.521 -2.559) (xy -1.485 -2.562) (xy -1.454 -2.568) (xy -1.427 -2.577) (xy -1.401 -2.589) (xy -1.371 -2.61)
				(xy -1.345 -2.639) (xy -1.325 -2.67) (xy -1.321 -2.679) (xy -1.309 -2.71) (xy -1.309 -3.197) (xy -1.433 -3.2)
				(xy -1.433 -3.172) (xy -1.434 -3.157) (xy -1.435 -3.147) (xy -1.436 -3.144) (xy -1.44 -3.147) (xy -1.449 -3.156)
				(xy -1.453 -3.161) (xy -1.472 -3.178) (xy -1.496 -3.19) (xy -1.526 -3.198) (xy -1.563 -3.202) (xy -1.578 -3.203)
				(xy -1.603 -3.203) (xy -1.627 -3.203) (xy -1.647 -3.201) (xy -1.656 -3.2) (xy -1.686 -3.191) (xy -1.717 -3.176)
				(xy -1.746 -3.159) (xy -1.765 -3.143) (xy -1.79 -3.111) (xy -1.807 -3.075) (xy -1.816 -3.037) (xy -1.817 -2.998)
				(xy -1.817 -2.997) (xy -1.697 -2.997) (xy -1.696 -3.02) (xy -1.687 -3.042) (xy -1.67 -3.06) (xy -1.668 -3.062)
				(xy -1.654 -3.07) (xy -1.64 -3.076) (xy -1.624 -3.08) (xy -1.602 -3.081) (xy -1.574 -3.082) (xy -1.558 -3.082)
				(xy -1.529 -3.081) (xy -1.508 -3.08) (xy -1.494 -3.078) (xy -1.483 -3.075) (xy -1.474 -3.07) (xy -1.458 -3.058)
				(xy -1.447 -3.041) (xy -1.44 -3.017) (xy -1.435 -2.985) (xy -1.435 -2.977) (xy -1.432 -2.931) (xy -1.533 -2.931)
				(xy -1.568 -2.931) (xy -1.595 -2.931) (xy -1.615 -2.932) (xy -1.63 -2.934) (xy -1.641 -2.936) (xy -1.65 -2.938)
				(xy -1.655 -2.941) (xy -1.676 -2.955) (xy -1.69 -2.974) (xy -1.697 -2.997) (xy -1.817 -2.997) (xy -1.811 -2.96)
				(xy -1.797 -2.924) (xy -1.775 -2.892) (xy -1.747 -2.864) (xy -1.715 -2.845) (xy -1.7 -2.838) (xy -1.685 -2.833)
				(xy -1.668 -2.83) (xy -1.648 -2.827) (xy -1.623 -2.825) (xy -1.591 -2.824) (xy -1.551 -2.824) (xy -1.54 -2.824)
				(xy -1.432 -2.824) (xy -1.434 -2.776) (xy -1.436 -2.747) (xy -1.441 -2.726) (xy -1.448 -2.711) (xy -1.46 -2.699)
				(xy -1.474 -2.689) (xy -1.483 -2.685) (xy -1.492 -2.682) (xy -1.505 -2.68) (xy -1.524 -2.68) (xy -1.55 -2.679)
				(xy -1.56 -2.679) (xy -1.594 -2.68) (xy -1.62 -2.682) (xy -1.639 -2.686) (xy -1.654 -2.692) (xy -1.666 -2.701)
				(xy -1.675 -2.711) (xy -1.686 -2.724) (xy -1.735 -2.686) (xy -1.754 -2.672) (xy -1.769 -2.659) (xy -1.78 -2.65)
				(xy -1.784 -2.646) (xy -1.78 -2.64) (xy -1.77 -2.629) (xy -1.756 -2.616) (xy -1.74 -2.604) (xy -1.724 -2.592)
				(xy -1.711 -2.584) (xy -1.71 -2.583) (xy -1.688 -2.574) (xy -1.668 -2.566) (xy -1.647 -2.562) (xy -1.623 -2.559)
				(xy -1.593 -2.558) (xy -1.565 -2.558) (xy -1.521 -2.559)
			)
			(stroke
				(width 0.01)
				(type solid)
			)
			(fill solid)
			(layer "B.Mask")
		)
		(fp_poly
			(pts
				(xy 0.035 -2.777) (xy 0.047 -2.822) (xy 0.059 -2.864) (xy 0.069 -2.903) (xy 0.078 -2.936) (xy 0.086 -2.963)
				(xy 0.092 -2.984) (xy 0.095 -2.996) (xy 0.096 -2.999) (xy 0.098 -2.999) (xy 0.103 -2.991) (xy 0.109 -2.975)
				(xy 0.118 -2.95) (xy 0.129 -2.917) (xy 0.143 -2.874) (xy 0.152 -2.849) (xy 0.165 -2.807) (xy 0.179 -2.766)
				(xy 0.192 -2.726) (xy 0.204 -2.689) (xy 0.214 -2.658) (xy 0.221 -2.634) (xy 0.224 -2.627) (xy 0.244 -2.565)
				(xy 0.338 -2.565) (xy 0.406 -2.774) (xy 0.42 -2.819) (xy 0.434 -2.861) (xy 0.446 -2.899) (xy 0.457 -2.932)
				(xy 0.466 -2.96) (xy 0.473 -2.981) (xy 0.477 -2.993) (xy 0.478 -2.997) (xy 0.48 -2.998) (xy 0.482 -2.996)
				(xy 0.485 -2.99) (xy 0.49 -2.978) (xy 0.495 -2.96) (xy 0.502 -2.936) (xy 0.511 -2.905) (xy 0.523 -2.865)
				(xy 0.536 -2.817) (xy 0.543 -2.789) (xy 0.556 -2.744) (xy 0.568 -2.701) (xy 0.578 -2.663) (xy 0.587 -2.629)
				(xy 0.595 -2.602) (xy 0.601 -2.582) (xy 0.605 -2.57) (xy 0.606 -2.567) (xy 0.611 -2.566) (xy 0.625 -2.566)
				(xy 0.645 -2.566) (xy 0.669 -2.566) (xy 0.673 -2.566) (xy 0.739 -2.567) (xy 0.656 -2.827) (xy 0.64 -2.878)
				(xy 0.624 -2.928) (xy 0.609 -2.976) (xy 0.595 -3.02) (xy 0.582 -3.06) (xy 0.571 -3.094) (xy 0.563 -3.121)
				(xy 0.557 -3.139) (xy 0.556 -3.143) (xy 0.538 -3.2) (xy 0.425 -3.197) (xy 0.358 -2.975) (xy 0.341 -2.917)
				(xy 0.327 -2.87) (xy 0.315 -2.831) (xy 0.305 -2.801) (xy 0.297 -2.78) (xy 0.292 -2.766) (xy 0.289 -2.761)
				(xy 0.288 -2.761) (xy 0.286 -2.768) (xy 0.281 -2.783) (xy 0.274 -2.806) (xy 0.265 -2.836) (xy 0.254 -2.871)
				(xy 0.242 -2.911) (xy 0.23 -2.953) (xy 0.223 -2.976) (xy 0.21 -3.02) (xy 0.197 -3.062) (xy 0.186 -3.099)
				(xy 0.177 -3.132) (xy 0.169 -3.158) (xy 0.163 -3.177) (xy 0.16 -3.189) (xy 0.159 -3.191) (xy 0.157 -3.195)
				(xy 0.151 -3.198) (xy 0.141 -3.199) (xy 0.124 -3.2) (xy 0.101 -3.2) (xy 0.073 -3.199) (xy 0.055 -3.198)
				(xy 0.045 -3.196) (xy 0.043 -3.194) (xy 0.041 -3.188) (xy 0.036 -3.173) (xy 0.029 -3.15) (xy 0.019 -3.121)
				(xy 0.008 -3.084) (xy -0.006 -3.043) (xy -0.02 -2.996) (xy -0.036 -2.946) (xy -0.053 -2.893) (xy -0.057 -2.883)
				(xy -0.074 -2.83) (xy -0.09 -2.779) (xy -0.105 -2.732) (xy -0.119 -2.689) (xy -0.131 -2.652) (xy -0.141 -2.621)
				(xy -0.148 -2.596) (xy -0.154 -2.58) (xy -0.156 -2.572) (xy -0.156 -2.569) (xy -0.151 -2.567) (xy -0.14 -2.566)
				(xy -0.123 -2.565) (xy -0.096 -2.565) (xy -0.091 -2.565) (xy -0.023 -2.565) (xy 0.035 -2.777)
			)
			(stroke
				(width 0.01)
				(type solid)
			)
			(fill solid)
			(layer "B.Mask")
		)
		(fp_poly
			(pts
				(xy -2.065 -1.559) (xy -2.024 -1.576) (xy -1.986 -1.601) (xy -1.973 -1.612) (xy -1.957 -1.63) (xy -1.943 -1.649)
				(xy -1.932 -1.668) (xy -1.924 -1.69) (xy -1.918 -1.716) (xy -1.914 -1.747) (xy -1.911 -1.785) (xy -1.91 -1.831)
				(xy -1.91 -1.877) (xy -1.91 -1.93) (xy -1.912 -1.974) (xy -1.914 -2.011) (xy -1.919 -2.041) (xy -1.925 -2.067)
				(xy -1.934 -2.088) (xy -1.945 -2.107) (xy -1.959 -2.125) (xy -1.972 -2.139) (xy -1.993 -2.157) (xy -2.018 -2.173)
				(xy -2.031 -2.18) (xy -2.047 -2.188) (xy -2.06 -2.192) (xy -2.074 -2.195) (xy -2.091 -2.196) (xy -2.114 -2.197)
				(xy -2.122 -2.197) (xy -2.147 -2.196) (xy -2.165 -2.195) (xy -2.179 -2.193) (xy -2.191 -2.189) (xy -2.205 -2.183)
				(xy -2.21 -2.18) (xy -2.231 -2.169) (xy -2.251 -2.156) (xy -2.265 -2.146) (xy -2.286 -2.127) (xy -2.286 -2.627)
				(xy -2.266 -2.608) (xy -2.248 -2.595) (xy -2.227 -2.582) (xy -2.217 -2.577) (xy -2.173 -2.562) (xy -2.129 -2.556)
				(xy -2.086 -2.559) (xy -2.045 -2.57) (xy -2.007 -2.589) (xy -1.974 -2.616) (xy -1.946 -2.648) (xy -1.926 -2.687)
				(xy -1.919 -2.707) (xy -1.917 -2.715) (xy -1.915 -2.724) (xy -1.914 -2.737) (xy -1.913 -2.753) (xy -1.912 -2.774)
				(xy -1.911 -2.8) (xy -1.911 -2.833) (xy -1.911 -2.874) (xy -1.911 -2.923) (xy -1.911 -2.967) (xy -1.911 -3.2)
				(xy -2.035 -3.197) (xy -2.038 -2.984) (xy -2.038 -2.932) (xy -2.039 -2.889) (xy -2.039 -2.854) (xy -2.04 -2.826)
				(xy -2.041 -2.805) (xy -2.042 -2.788) (xy -2.043 -2.776) (xy -2.045 -2.767) (xy -2.046 -2.76) (xy -2.049 -2.755)
				(xy -2.051 -2.75) (xy -2.072 -2.721) (xy -2.098 -2.701) (xy -2.128 -2.688) (xy -2.161 -2.683) (xy -2.195 -2.687)
				(xy -2.22 -2.697) (xy -2.24 -2.71) (xy -2.259 -2.729) (xy -2.274 -2.75) (xy -2.278 -2.757) (xy -2.28 -2.765)
				(xy -2.281 -2.781) (xy -2.283 -2.806) (xy -2.284 -2.839) (xy -2.285 -2.881) (xy -2.286 -2.933) (xy -2.286 -2.984)
				(xy -2.289 -3.197) (xy -2.413 -3.2) (xy -2.413 -1.877) (xy -2.286 -1.877) (xy -2.285 -1.926) (xy -2.281 -1.966)
				(xy -2.274 -1.998) (xy -2.262 -2.024) (xy -2.247 -2.043) (xy -2.228 -2.058) (xy -2.215 -2.064) (xy -2.194 -2.07)
				(xy -2.168 -2.072) (xy -2.141 -2.071) (xy -2.117 -2.066) (xy -2.106 -2.063) (xy -2.079 -2.044) (xy -2.058 -2.019)
				(xy -2.05 -2.001) (xy -2.045 -1.984) (xy -2.042 -1.959) (xy -2.04 -1.929) (xy -2.038 -1.895) (xy -2.038 -1.861)
				(xy -2.039 -1.829) (xy -2.041 -1.8) (xy -2.044 -1.777) (xy -2.045 -1.772) (xy -2.057 -1.738) (xy -2.073 -1.712)
				(xy -2.094 -1.695) (xy -2.122 -1.684) (xy -2.156 -1.681) (xy -2.159 -1.681) (xy -2.192 -1.683) (xy -2.22 -1.691)
				(xy -2.243 -1.705) (xy -2.26 -1.725) (xy -2.273 -1.753) (xy -2.281 -1.788) (xy -2.285 -1.832) (xy -2.286 -1.877)
				(xy -2.413 -1.877) (xy -2.413 -1.559) (xy -2.286 -1.559) (xy -2.286 -1.62) (xy -2.26 -1.6) (xy -2.225 -1.577)
				(xy -2.19 -1.563) (xy -2.154 -1.554) (xy -2.109 -1.552) (xy -2.065 -1.559)
			)
			(stroke
				(width 0.01)
				(type solid)
			)
			(fill solid)
			(layer "B.Mask")
		)
		(fp_poly
			(pts
				(xy 0.063 3.201) (xy 0.118 3.201) (xy 0.164 3.201) (xy 0.202 3.2) (xy 0.233 3.2) (xy 0.258 3.2)
				(xy 0.277 3.199) (xy 0.292 3.198) (xy 0.302 3.197) (xy 0.309 3.196) (xy 0.314 3.195) (xy 0.317 3.193)
				(xy 0.319 3.192) (xy 0.321 3.189) (xy 0.324 3.183) (xy 0.327 3.174) (xy 0.33 3.161) (xy 0.334 3.144)
				(xy 0.339 3.12) (xy 0.345 3.091) (xy 0.352 3.054) (xy 0.361 3.01) (xy 0.371 2.958) (xy 0.382 2.897)
				(xy 0.385 2.878) (xy 0.395 2.824) (xy 0.405 2.772) (xy 0.414 2.724) (xy 0.423 2.68) (xy 0.43 2.642)
				(xy 0.437 2.61) (xy 0.442 2.586) (xy 0.446 2.569) (xy 0.448 2.562) (xy 0.456 2.55) (xy 0.464 2.544)
				(xy 0.476 2.539) (xy 0.495 2.53) (xy 0.521 2.519) (xy 0.552 2.506) (xy 0.587 2.492) (xy 0.624 2.477)
				(xy 0.664 2.461) (xy 0.704 2.445) (xy 0.743 2.43) (xy 0.78 2.415) (xy 0.814 2.402) (xy 0.843 2.391)
				(xy 0.868 2.382) (xy 0.885 2.376) (xy 0.895 2.373) (xy 0.896 2.373) (xy 0.911 2.376) (xy 0.931 2.386)
				(xy 0.948 2.397) (xy 0.962 2.406) (xy 0.983 2.421) (xy 1.011 2.44) (xy 1.043 2.462) (xy 1.079 2.487)
				(xy 1.118 2.513) (xy 1.158 2.541) (xy 1.198 2.568) (xy 1.238 2.595) (xy 1.275 2.621) (xy 1.309 2.644)
				(xy 1.338 2.665) (xy 1.362 2.681) (xy 1.377 2.691) (xy 1.398 2.705) (xy 1.418 2.717) (xy 1.433 2.725)
				(xy 1.442 2.728) (xy 1.443 2.728) (xy 1.448 2.726) (xy 1.456 2.72) (xy 1.468 2.71) (xy 1.486 2.694)
				(xy 1.508 2.673) (xy 1.535 2.647) (xy 1.568 2.614) (xy 1.608 2.575) (xy 1.654 2.53) (xy 1.675 2.509)
				(xy 1.721 2.462) (xy 1.761 2.422) (xy 1.794 2.388) (xy 1.822 2.36) (xy 1.844 2.337) (xy 1.862 2.318)
				(xy 1.875 2.304) (xy 1.884 2.293) (xy 1.89 2.284) (xy 1.893 2.279) (xy 1.894 2.275) (xy 1.892 2.269)
				(xy 1.886 2.257) (xy 1.875 2.239) (xy 1.86 2.215) (xy 1.839 2.183) (xy 1.814 2.145) (xy 1.783 2.1)
				(xy 1.747 2.046) (xy 1.721 2.009) (xy 1.69 1.964) (xy 1.661 1.921) (xy 1.634 1.88) (xy 1.609 1.844)
				(xy 1.588 1.811) (xy 1.57 1.785) (xy 1.557 1.764) (xy 1.549 1.75) (xy 1.546 1.743) (xy 1.547 1.735)
				(xy 1.552 1.719) (xy 1.56 1.696) (xy 1.571 1.667) (xy 1.585 1.634) (xy 1.6 1.597) (xy 1.616 1.557)
				(xy 1.633 1.516) (xy 1.651 1.476) (xy 1.668 1.436) (xy 1.685 1.398) (xy 1.701 1.363) (xy 1.715 1.333)
				(xy 1.727 1.309) (xy 1.736 1.291) (xy 1.742 1.281) (xy 1.744 1.279) (xy 1.751 1.277) (xy 1.767 1.273)
				(xy 1.791 1.268) (xy 1.822 1.261) (xy 1.86 1.254) (xy 1.903 1.245) (xy 1.951 1.236) (xy 2.002 1.226)
				(xy 2.049 1.217) (xy 2.103 1.207) (xy 2.154 1.198) (xy 2.201 1.188) (xy 2.244 1.18) (xy 2.281 1.173)
				(xy 2.311 1.166) (xy 2.335 1.161) (xy 2.35 1.157) (xy 2.355 1.156) (xy 2.367 1.148) (xy 2.367 0.834)
				(xy 2.367 0.768) (xy 2.367 0.712) (xy 2.367 0.664) (xy 2.366 0.625) (xy 2.366 0.592) (xy 2.365 0.566)
				(xy 2.364 0.546) (xy 2.363 0.531) (xy 2.361 0.52) (xy 2.358 0.512) (xy 2.355 0.507) (xy 2.352 0.504)
				(xy 2.348 0.503) (xy 2.343 0.501) (xy 2.34 0.501) (xy 2.333 0.499) (xy 2.317 0.496) (xy 2.293 0.492)
				(xy 2.261 0.486) (xy 2.224 0.479) (xy 2.181 0.471) (xy 2.134 0.462) (xy 2.084 0.453) (xy 2.054 0.448)
				(xy 2.002 0.438) (xy 1.953 0.429) (xy 1.907 0.42) (xy 1.866 0.412) (xy 1.831 0.404) (xy 1.802 0.398)
				(xy 1.78 0.394) (xy 1.767 0.391) (xy 1.764 0.39) (xy 1.76 0.387) (xy 1.757 0.384) (xy 1.753 0.379)
				(xy 1.748 0.371) (xy 1.742 0.36) (xy 1.735 0.344) (xy 1.726 0.324) (xy 1.715 0.297) (xy 1.701 0.264)
				(xy 1.685 0.223) (xy 1.665 0.174) (xy 1.653 0.145) (xy 1.63 0.086) (xy 1.61 0.037) (xy 1.594 -0.005)
				(xy 1.582 -0.038) (xy 1.572 -0.064) (xy 1.566 -0.084) (xy 1.562 -0.097) (xy 1.561 -0.104) (xy 1.562 -0.105)
				(xy 1.565 -0.111) (xy 1.574 -0.125) (xy 1.587 -0.146) (xy 1.604 -0.173) (xy 1.626 -0.205) (xy 1.65 -0.241)
				(xy 1.677 -0.281) (xy 1.706 -0.324) (xy 1.729 -0.358) (xy 1.768 -0.413) (xy 1.8 -0.461) (xy 1.827 -0.502)
				(xy 1.85 -0.535) (xy 1.867 -0.562) (xy 1.88 -0.583) (xy 1.889 -0.598) (xy 1.893 -0.608) (xy 1.894 -0.612)
				(xy 1.893 -0.616) (xy 1.89 -0.622) (xy 1.885 -0.63) (xy 1.876 -0.64) (xy 1.863 -0.655) (xy 1.846 -0.673)
				(xy 1.825 -0.695) (xy 1.798 -0.723) (xy 1.765 -0.756) (xy 1.727 -0.795) (xy 1.682 -0.839) (xy 1.635 -0.886)
				(xy 1.595 -0.926) (xy 1.561 -0.96) (xy 1.532 -0.989) (xy 1.508 -1.012) (xy 1.488 -1.03) (xy 1.473 -1.044)
				(xy 1.461 -1.054) (xy 1.452 -1.061) (xy 1.445 -1.065) (xy 1.44 -1.066) (xy 1.438 -1.066) (xy 1.433 -1.064)
				(xy 1.421 -1.055) (xy 1.401 -1.043) (xy 1.376 -1.026) (xy 1.345 -1.005) (xy 1.31 -0.981) (xy 1.27 -0.954)
				(xy 1.228 -0.925) (xy 1.193 -0.901) (xy 1.138 -0.864) (xy 1.089 -0.83) (xy 1.046 -0.802) (xy 1.01 -0.778)
				(xy 0.981 -0.759) (xy 0.96 -0.746) (xy 0.946 -0.738) (xy 0.94 -0.736) (xy 0.932 -0.738) (xy 0.917 -0.745)
				(xy 0.895 -0.755) (xy 0.869 -0.768) (xy 0.84 -0.783) (xy 0.816 -0.795) (xy 0.781 -0.814) (xy 0.753 -0.828)
				(xy 0.732 -0.838) (xy 0.717 -0.845) (xy 0.707 -0.849) (xy 0.699 -0.85) (xy 0.694 -0.849) (xy 0.691 -0.847)
				(xy 0.687 -0.84) (xy 0.682 -0.829) (xy 0.674 -0.814) (xy 0.665 -0.793) (xy 0.653 -0.767) (xy 0.639 -0.735)
				(xy 0.623 -0.696) (xy 0.604 -0.651) (xy 0.582 -0.598) (xy 0.556 -0.538) (xy 0.528 -0.469) (xy 0.496 -0.391)
				(xy 0.47 -0.329) (xy 0.436 -0.247) (xy 0.406 -0.173) (xy 0.379 -0.108) (xy 0.355 -0.05) (xy 0.335 0)
				(xy 0.317 0.043) (xy 0.303 0.079) (xy 0.291 0.11) (xy 0.281 0.135) (xy 0.273 0.155) (xy 0.268 0.171)
				(xy 0.264 0.183) (xy 0.262 0.191) (xy 0.262 0.196) (xy 0.262 0.198) (xy 0.269 0.207) (xy 0.283 0.219)
				(xy 0.302 0.233) (xy 0.303 0.234) (xy 0.354 0.268) (xy 0.398 0.3) (xy 0.435 0.331) (xy 0.469 0.363)
				(xy 0.5 0.397) (xy 0.507 0.405) (xy 0.556 0.472) (xy 0.596 0.543) (xy 0.627 0.619) (xy 0.643 0.672)
				(xy 0.651 0.718) (xy 0.657 0.77) (xy 0.66 0.824) (xy 0.659 0.878) (xy 0.654 0.927) (xy 0.652 0.936)
				(xy 0.634 1.015) (xy 0.607 1.09) (xy 0.571 1.161) (xy 0.528 1.227) (xy 0.477 1.287) (xy 0.419 1.341)
				(xy 0.355 1.387) (xy 0.285 1.426) (xy 0.21 1.456) (xy 0.205 1.458) (xy 0.131 1.477) (xy 0.054 1.487)
				(xy -0.025 1.489) (xy -0.103 1.482) (xy -0.178 1.466) (xy -0.206 1.458) (xy -0.281 1.428) (xy -0.351 1.39)
				(xy -0.416 1.344) (xy -0.474 1.29) (xy -0.526 1.23) (xy -0.571 1.164) (xy -0.607 1.093) (xy -0.63 1.034)
				(xy -0.649 0.96) (xy -0.659 0.883) (xy -0.661 0.804) (xy -0.654 0.726) (xy -0.638 0.651) (xy -0.63 0.623)
				(xy -0.618 0.591) (xy -0.602 0.554) (xy -0.584 0.518) (xy -0.566 0.485) (xy -0.553 0.463) (xy -0.509 0.407)
				(xy -0.457 0.352) (xy -0.397 0.299) (xy -0.33 0.25) (xy -0.289 0.224) (xy -0.273 0.212) (xy -0.263 0.2)
				(xy -0.262 0.197) (xy -0.263 0.19) (xy -0.268 0.175) (xy -0.277 0.151) (xy -0.288 0.121) (xy -0.302 0.084)
				(xy -0.319 0.042) (xy -0.338 -0.005) (xy -0.358 -0.056) (xy -0.381 -0.111) (xy -0.404 -0.168) (xy -0.428 -0.228)
				(xy -0.453 -0.288) (xy -0.478 -0.349) (xy -0.504 -0.41) (xy -0.529 -0.47) (xy -0.553 -0.527) (xy -0.576 -0.583)
				(xy -0.598 -0.635) (xy -0.619 -0.683) (xy -0.638 -0.727) (xy -0.655 -0.765) (xy -0.669 -0.797) (xy -0.68 -0.822)
				(xy -0.689 -0.839) (xy -0.694 -0.848) (xy -0.695 -0.849) (xy -0.699 -0.85) (xy -0.706 -0.849) (xy -0.717 -0.845)
				(xy -0.732 -0.839) (xy -0.752 -0.829) (xy -0.779 -0.815) (xy -0.814 -0.797) (xy -0.817 -0.795) (xy -0.848 -0.779)
				(xy -0.877 -0.764) (xy -0.902 -0.752) (xy -0.922 -0.743) (xy -0.936 -0.737) (xy -0.941 -0.736) (xy -0.949 -0.739)
				(xy -0.964 -0.748) (xy -0.987 -0.761) (xy -1.015 -0.78) (xy -1.05 -0.803) (xy -1.072 -0.818) (xy -1.138 -0.863)
				(xy -1.195 -0.903) (xy -1.245 -0.937) (xy -1.289 -0.966) (xy -1.325 -0.991) (xy -1.356 -1.012) (xy -1.381 -1.029)
				(xy -1.401 -1.042) (xy -1.416 -1.052) (xy -1.427 -1.059) (xy -1.435 -1.064) (xy -1.439 -1.066) (xy -1.44 -1.066)
				(xy -1.449 -1.064) (xy -1.453 -1.061) (xy -1.458 -1.057) (xy -1.47 -1.046) (xy -1.487 -1.029) (xy -1.509 -1.007)
				(xy -1.537 -0.98) (xy -1.568 -0.95) (xy -1.602 -0.915) (xy -1.639 -0.879) (xy -1.678 -0.84) (xy -1.678 -0.839)
				(xy -1.726 -0.792) (xy -1.767 -0.751) (xy -1.801 -0.716) (xy -1.829 -0.687) (xy -1.852 -0.663) (xy -1.869 -0.644)
				(xy -1.882 -0.63) (xy -1.89 -0.62) (xy -1.894 -0.613) (xy -1.895 -0.61) (xy -1.892 -0.603) (xy -1.884 -0.588)
				(xy -1.87 -0.565) (xy -1.85 -0.536) (xy -1.826 -0.499) (xy -1.797 -0.455) (xy -1.763 -0.405) (xy -1.73 -0.358)
				(xy -1.7 -0.313) (xy -1.671 -0.271) (xy -1.645 -0.232) (xy -1.621 -0.197) (xy -1.601 -0.166) (xy -1.584 -0.141)
				(xy -1.572 -0.121) (xy -1.565 -0.109) (xy -1.563 -0.105) (xy -1.563 -0.099) (xy -1.566 -0.087) (xy -1.572 -0.07)
				(xy -1.58 -0.045) (xy -1.592 -0.013) (xy -1.607 0.026) (xy -1.626 0.074) (xy -1.648 0.13) (xy -1.654 0.145)
				(xy -1.676 0.199) (xy -1.695 0.245) (xy -1.71 0.282) (xy -1.723 0.313) (xy -1.733 0.337) (xy -1.741 0.356)
				(xy -1.748 0.369) (xy -1.753 0.379) (xy -1.758 0.385) (xy -1.761 0.388) (xy -1.763 0.389) (xy -1.767 0.39)
				(xy -1.774 0.392) (xy -1.784 0.395) (xy -1.799 0.398) (xy -1.818 0.402) (xy -1.843 0.407) (xy -1.873 0.413)
				(xy -1.91 0.42) (xy -1.954 0.429) (xy -2.005 0.438) (xy -2.065 0.449) (xy -2.133 0.462) (xy -2.211 0.477)
				(xy -2.22 0.478) (xy -2.26 0.486) (xy -2.29 0.491) (xy -2.313 0.496) (xy -2.33 0.499) (xy -2.341 0.502)
				(xy -2.349 0.504) (xy -2.353 0.506) (xy -2.356 0.508) (xy -2.359 0.51) (xy -2.36 0.511) (xy -2.361 0.514)
				(xy -2.363 0.518) (xy -2.364 0.526) (xy -2.365 0.536) (xy -2.366 0.551) (xy -2.366 0.571) (xy -2.367 0.597)
				(xy -2.367 0.629) (xy -2.368 0.668) (xy -2.368 0.715) (xy -2.368 0.771) (xy -2.368 0.834) (xy -2.368 1.148)
				(xy -2.356 1.155) (xy -2.349 1.158) (xy -2.333 1.162) (xy -2.309 1.167) (xy -2.278 1.173) (xy -2.24 1.181)
				(xy -2.197 1.189) (xy -2.149 1.198) (xy -2.098 1.208) (xy -2.051 1.217) (xy -1.996 1.227) (xy -1.945 1.237)
				(xy -1.897 1.246) (xy -1.854 1.254) (xy -1.817 1.262) (xy -1.787 1.268) (xy -1.764 1.273) (xy -1.75 1.277)
				(xy -1.745 1.279) (xy -1.741 1.285) (xy -1.733 1.3) (xy -1.722 1.322) (xy -1.709 1.35) (xy -1.694 1.382)
				(xy -1.677 1.419) (xy -1.66 1.458) (xy -1.642 1.498) (xy -1.625 1.539) (xy -1.608 1.58) (xy -1.592 1.618)
				(xy -1.578 1.653) (xy -1.565 1.684) (xy -1.556 1.709) (xy -1.549 1.729) (xy -1.546 1.74) (xy -1.546 1.742)
				(xy -1.549 1.749) (xy -1.558 1.763) (xy -1.571 1.784) (xy -1.588 1.811) (xy -1.61 1.843) (xy -1.634 1.88)
				(xy -1.661 1.92) (xy -1.691 1.963) (xy -1.722 2.008) (xy -1.762 2.067) (xy -1.796 2.117) (xy -1.825 2.16)
				(xy -1.848 2.196) (xy -1.867 2.225) (xy -1.881 2.247) (xy -1.89 2.262) (xy -1.895 2.272) (xy -1.895 2.275)
				(xy -1.894 2.279) (xy -1.891 2.285) (xy -1.884 2.293) (xy -1.875 2.305) (xy -1.861 2.32) (xy -1.843 2.339)
				(xy -1.82 2.363) (xy -1.792 2.392) (xy -1.758 2.426) (xy -1.718 2.466) (xy -1.676 2.509) (xy -1.627 2.557)
				(xy -1.585 2.599) (xy -1.549 2.634) (xy -1.52 2.663) (xy -1.495 2.686) (xy -1.476 2.704) (xy -1.462 2.716)
				(xy -1.452 2.724) (xy -1.446 2.728) (xy -1.444 2.728) (xy -1.437 2.726) (xy -1.423 2.717) (xy -1.401 2.703)
				(xy -1.372 2.685) (xy -1.337 2.661) (xy -1.295 2.634) (xy -1.248 2.602) (xy -1.196 2.566) (xy -1.173 2.551)
				(xy -1.118 2.513) (xy -1.071 2.481) (xy -1.031 2.454) (xy -0.998 2.432) (xy -0.97 2.413) (xy -0.948 2.399)
				(xy -0.931 2.389) (xy -0.917 2.381) (xy -0.907 2.376) (xy -0.901 2.373) (xy -0.897 2.373) (xy -0.888 2.375)
				(xy -0.87 2.38) (xy -0.845 2.39) (xy -0.813 2.402) (xy -0.774 2.417) (xy -0.73 2.434) (xy -0.681 2.454)
				(xy -0.629 2.475) (xy -0.586 2.493) (xy -0.55 2.508) (xy -0.522 2.52) (xy -0.499 2.529) (xy -0.482 2.537)
				(xy -0.47 2.543) (xy -0.461 2.548) (xy -0.455 2.551) (xy -0.452 2.554) (xy -0.449 2.557) (xy -0.448 2.56)
				(xy -0.447 2.566) (xy -0.443 2.582) (xy -0.438 2.605) (xy -0.432 2.637) (xy -0.425 2.674) (xy -0.417 2.717)
				(xy -0.407 2.765) (xy -0.398 2.817) (xy -0.388 2.871) (xy -0.387 2.876) (xy -0.375 2.94) (xy -0.364 2.995)
				(xy -0.356 3.042) (xy -0.348 3.081) (xy -0.342 3.112) (xy -0.337 3.137) (xy -0.332 3.157) (xy -0.328 3.171)
				(xy -0.325 3.181) (xy -0.323 3.188) (xy -0.32 3.191) (xy -0.32 3.192) (xy -0.317 3.194) (xy -0.313 3.195)
				(xy -0.307 3.197) (xy -0.298 3.198) (xy -0.286 3.199) (xy -0.269 3.199) (xy -0.247 3.2) (xy -0.219 3.2)
				(xy -0.184 3.201) (xy -0.142 3.201) (xy -0.092 3.201) (xy -0.033 3.201) (xy -0.001 3.201) (xy 0.063 3.201)
			)
			(stroke
				(width 0.01)
				(type solid)
			)
			(fill solid)
			(layer "B.Mask")
		)
		(fp_rect
			(start -4.05 4.21)
			(end 4.06 -4.21)
			(stroke
				(width 0.05)
				(type default)
			)
			(fill none)
			(layer "B.CrtYd")
		)
		(fp_text user "Author: Antmicro"
			(at -3.081 -6.404 0)
			(layer "B.Fab")
			(hide yes)
			(effects
				(font
					(size 0.7 0.7)
					(thickness 0.15)
				)
				(justify left bottom mirror)
			)
		)
		(fp_text user "License: Apache-2.0"
			(at -3.081 -7.604 0)
			(layer "B.Fab")
			(hide yes)
			(effects
				(font
					(size 0.7 0.7)
					(thickness 0.15)
				)
				(justify left bottom mirror)
			)
		)
		(fp_text user "${REFERENCE}"
			(at -3.081 -5.204 0)
			(layer "B.Fab")
			(hide yes)
			(effects
				(font
					(size 0.7 0.7)
					(thickness 0.15)
				)
				(justify left bottom mirror)
			)
		)
	)
	(footprint "antmicro-footprints:R_0402_1005Metric"
		(layer "B.Cu")
		(at 118.325 113.973751 180)
		(descr "Resistor SMD 0402")
		(tags "resistor SMD 0402")
		(property "Reference" "R4"
			(at -2.588333 -0.47725 0)
			(layer "B.SilkS")
			(effects
				(font
					(size 0.7 0.7)
					(thickness 0.15)
				)
				(justify left bottom mirror)
			)
		)
		(property "Value" "R_1k_0402"
			(at -1.011843 -1.772047 0)
			(layer "B.Fab")
			(effects
				(font
					(size 0.7 0.7)
					(thickness 0.15)
				)
				(justify left bottom mirror)
			)
		)
		(property "Footprint" "antmicro-footprints:R_0402_1005Metric"
			(at 0 0 0)
			(layer "B.Fab")
			(hide yes)
			(effects
				(font
					(size 1.27 1.27)
					(thickness 0.15)
				)
				(justify mirror)
			)
		)
		(property "Datasheet" "https://www.bourns.com/docs/product-datasheets/cr.pdf"
			(at 0 0 0)
			(layer "B.Fab")
			(hide yes)
			(effects
				(font
					(size 1.27 1.27)
					(thickness 0.15)
				)
				(justify mirror)
			)
		)
		(property "Description" "SMD Chip Resistor, 1 kohm, ± 1%, 63 mW, 0402 [1005 Metric], Thick Film, General Purpose"
			(at 0 0 0)
			(layer "B.Fab")
			(hide yes)
			(effects
				(font
					(size 1.27 1.27)
					(thickness 0.15)
				)
				(justify mirror)
			)
		)
		(property "MPN" "CR0402-FX-1001GLF"
			(at 0 0 0)
			(unlocked yes)
			(layer "B.Fab")
			(hide yes)
			(effects
				(font
					(size 1 1)
					(thickness 0.15)
				)
				(justify mirror)
			)
		)
		(property "Manufacturer" "Bourns"
			(at 0 0 0)
			(unlocked yes)
			(layer "B.Fab")
			(hide yes)
			(effects
				(font
					(size 1 1)
					(thickness 0.15)
				)
				(justify mirror)
			)
		)
		(property "License" "Apache-2.0"
			(at 0 0 0)
			(unlocked yes)
			(layer "B.Fab")
			(hide yes)
			(effects
				(font
					(size 1 1)
					(thickness 0.15)
				)
				(justify mirror)
			)
		)
		(property "Author" "Antmicro"
			(at 0 0 0)
			(unlocked yes)
			(layer "B.Fab")
			(hide yes)
			(effects
				(font
					(size 1 1)
					(thickness 0.15)
				)
				(justify mirror)
			)
		)
		(property "Val" "1k"
			(at 0 0 0)
			(unlocked yes)
			(layer "B.Fab")
			(hide yes)
			(effects
				(font
					(size 1 1)
					(thickness 0.15)
				)
				(justify mirror)
			)
		)
		(property "Tolerance" "1%"
			(at 0 0 0)
			(unlocked yes)
			(layer "B.Fab")
			(hide yes)
			(effects
				(font
					(size 1 1)
					(thickness 0.15)
				)
				(justify mirror)
			)
		)
		(property "Public" "False"
			(at 0 0 0)
			(unlocked yes)
			(layer "B.Fab")
			(hide yes)
			(effects
				(font
					(size 1 1)
					(thickness 0.15)
				)
				(justify mirror)
			)
		)
		(sheetname "Root")
		(sheetfile "jetson-orin-baseboard-oculink-expansion.kicad_sch")
		(attr smd dnp)
		(fp_rect
			(start -0.925 0.47)
			(end 0.925 -0.47)
			(stroke
				(width 0.05)
				(type default)
			)
			(fill none)
			(layer "B.CrtYd")
		)
		(fp_rect
			(start -0.5 0.25)
			(end 0.5 -0.25)
			(stroke
				(width 0.15)
				(type solid)
			)
			(fill none)
			(layer "B.Fab")
		)
		(fp_text user "${REFERENCE}"
			(at -0.95 -3.168 0)
			(layer "B.Fab")
			(hide yes)
			(effects
				(font
					(size 0.7 0.7)
					(thickness 0.15)
				)
				(justify left bottom mirror)
			)
		)
		(fp_text user "Author: Antmicro"
			(at -0.95 -4.169 0)
			(layer "B.Fab")
			(hide yes)
			(effects
				(font
					(size 0.7 0.7)
					(thickness 0.15)
				)
				(justify left bottom mirror)
			)
		)
		(fp_text user "License: Apache-2.0"
			(at -0.95 -5.169 0)
			(layer "B.Fab")
			(hide yes)
			(effects
				(font
					(size 0.7 0.7)
					(thickness 0.15)
				)
				(justify left bottom mirror)
			)
		)
		(pad "1" smd roundrect
			(at -0.48 0 180)
			(size 0.59 0.64)
			(layers "B.Cu" "B.Paste" "B.Mask")
			(roundrect_rratio 0.25)
			(net 23 "+3V3")
			(pintype "passive")
		)
		(pad "2" smd roundrect
			(at 0.48 0 180)
			(size 0.59 0.64)
			(layers "B.Cu" "B.Paste" "B.Mask")
			(roundrect_rratio 0.25)
			(net 89 "/RX_EQ0")
			(pintype "passive")
		)
	)
	(footprint "antmicro-footprints:C_0402_1005Metric"
		(layer "B.Cu")
		(at 126.505 114.569251 90)
		(descr "Capacitor SMD 0402")
		(tags "capacitor SMD 0402")
		(property "Reference" "C9"
			(at 1.779251 -0.415 90)
			(layer "B.SilkS")
			(effects
				(font
					(size 0.7 0.7)
					(thickness 0.15)
				)
				(justify right top mirror)
			)
		)
		(property "Value" "C_100n_0402"
			(at -1.022927 -2.155213 90)
			(layer "B.Fab")
			(effects
				(font
					(size 0.7 0.7)
					(thickness 0.15)
				)
				(justify right top mirror)
			)
		)
		(property "Footprint" "antmicro-footprints:C_0402_1005Metric"
			(at 0 0 90)
			(layer "B.Fab")
			(hide yes)
			(effects
				(font
					(size 1.27 1.27)
					(thickness 0.15)
				)
				(justify mirror)
			)
		)
		(property "Datasheet" "https://www.murata.com/products/productdetail?partno=GRM155R61H104KE14%23"
			(at 0 0 90)
			(layer "B.Fab")
			(hide yes)
			(effects
				(font
					(size 1.27 1.27)
					(thickness 0.15)
				)
				(justify mirror)
			)
		)
		(property "Description" "SMD Multilayer Ceramic Capacitor, 0.1 µF, 50 V, 0402 [1005 Metric], ± 10%, X5R, GRM Series"
			(at 0 0 90)
			(layer "B.Fab")
			(hide yes)
			(effects
				(font
					(size 1.27 1.27)
					(thickness 0.15)
				)
				(justify mirror)
			)
		)
		(property "MPN" "GRM155R61H104KE14D"
			(at 0 0 -90)
			(unlocked yes)
			(layer "B.Fab")
			(hide yes)
			(effects
				(font
					(size 1 1)
					(thickness 0.15)
				)
				(justify mirror)
			)
		)
		(property "Manufacturer" "Murata"
			(at 0 0 -90)
			(unlocked yes)
			(layer "B.Fab")
			(hide yes)
			(effects
				(font
					(size 1 1)
					(thickness 0.15)
				)
				(justify mirror)
			)
		)
		(property "License" "Apache-2.0"
			(at 0 0 -90)
			(unlocked yes)
			(layer "B.Fab")
			(hide yes)
			(effects
				(font
					(size 1 1)
					(thickness 0.15)
				)
				(justify mirror)
			)
		)
		(property "Author" "Antmicro"
			(at 0 0 -90)
			(unlocked yes)
			(layer "B.Fab")
			(hide yes)
			(effects
				(font
					(size 1 1)
					(thickness 0.15)
				)
				(justify mirror)
			)
		)
		(property "Val" "100n"
			(at 0 0 -90)
			(unlocked yes)
			(layer "B.Fab")
			(hide yes)
			(effects
				(font
					(size 1 1)
					(thickness 0.15)
				)
				(justify mirror)
			)
		)
		(property "Voltage" "50V"
			(at 0 0 -90)
			(unlocked yes)
			(layer "B.Fab")
			(hide yes)
			(effects
				(font
					(size 1 1)
					(thickness 0.15)
				)
				(justify mirror)
			)
		)
		(property "Dielectric" "X5R"
			(at 0 0 -90)
			(unlocked yes)
			(layer "B.Fab")
			(hide yes)
			(effects
				(font
					(size 1 1)
					(thickness 0.15)
				)
				(justify mirror)
			)
		)
		(property "Public" "False"
			(at 0 0 -90)
			(unlocked yes)
			(layer "B.Fab")
			(hide yes)
			(effects
				(font
					(size 1 1)
					(thickness 0.15)
				)
				(justify mirror)
			)
		)
		(sheetname "Root")
		(sheetfile "jetson-orin-baseboard-oculink-expansion.kicad_sch")
		(attr smd)
		(fp_rect
			(start -0.925 0.47)
			(end 0.925 -0.47)
			(stroke
				(width 0.05)
				(type default)
			)
			(fill none)
			(layer "B.CrtYd")
		)
		(fp_line
			(start 0.504 -0.248)
			(end 0.504 0.25)
			(stroke
				(width 0.15)
				(type solid)
			)
			(layer "B.Fab")
		)
		(fp_line
			(start -0.494 -0.248)
			(end 0.504 -0.248)
			(stroke
				(width 0.15)
				(type solid)
			)
			(layer "B.Fab")
		)
		(fp_line
			(start 0.504 0.25)
			(end -0.494 0.25)
			(stroke
				(width 0.15)
				(type solid)
			)
			(layer "B.Fab")
		)
		(fp_line
			(start -0.494 0.25)
			(end -0.494 -0.248)
			(stroke
				(width 0.15)
				(type solid)
			)
			(layer "B.Fab")
		)
		(fp_text user "License: Apache-2.0"
			(at -0.939 -5.799 90)
			(layer "B.Fab")
			(hide yes)
			(effects
				(font
					(size 0.7 0.7)
					(thickness 0.15)
				)
				(justify right top mirror)
			)
		)
		(fp_text user "${REFERENCE}"
			(at -0.939 -4.599 90)
			(layer "B.Fab")
			(hide yes)
			(effects
				(font
					(size 0.7 0.7)
					(thickness 0.15)
				)
				(justify right top mirror)
			)
		)
		(fp_text user "Author: Antmicro"
			(at -0.939 -3.399 90)
			(layer "B.Fab")
			(hide yes)
			(effects
				(font
					(size 0.7 0.7)
					(thickness 0.15)
				)
				(justify right top mirror)
			)
		)
		(pad "1" smd roundrect
			(at -0.48 0 90)
			(size 0.59 0.64)
			(layers "B.Cu" "B.Paste" "B.Mask")
			(roundrect_rratio 0.25)
			(net 51 "GND")
			(pintype "passive")
		)
		(pad "2" smd roundrect
			(at 0.48 0 90)
			(size 0.59 0.64)
			(layers "B.Cu" "B.Paste" "B.Mask")
			(roundrect_rratio 0.25)
			(net 23 "+3V3")
			(pintype "passive")
		)
	)
	(footprint "antmicro-footprints:R_0402_1005Metric"
		(layer "B.Cu")
		(at 118.324 118.193751 180)
		(descr "Resistor SMD 0402")
		(tags "resistor SMD 0402")
		(property "Reference" "R14"
			(at -3.256 -0.47725 0)
			(layer "B.SilkS")
			(effects
				(font
					(size 0.7 0.7)
					(thickness 0.15)
				)
				(justify left bottom mirror)
			)
		)
		(property "Value" "R_1k_0402"
			(at -1.011843 -1.772047 0)
			(layer "B.Fab")
			(effects
				(font
					(size 0.7 0.7)
					(thickness 0.15)
				)
				(justify left bottom mirror)
			)
		)
		(property "Footprint" "antmicro-footprints:R_0402_1005Metric"
			(at 0 0 0)
			(layer "B.Fab")
			(hide yes)
			(effects
				(font
					(size 1.27 1.27)
					(thickness 0.15)
				)
				(justify mirror)
			)
		)
		(property "Datasheet" "https://www.bourns.com/docs/product-datasheets/cr.pdf"
			(at 0 0 0)
			(layer "B.Fab")
			(hide yes)
			(effects
				(font
					(size 1.27 1.27)
					(thickness 0.15)
				)
				(justify mirror)
			)
		)
		(property "Description" "SMD Chip Resistor, 1 kohm, ± 1%, 63 mW, 0402 [1005 Metric], Thick Film, General Purpose"
			(at 0 0 0)
			(layer "B.Fab")
			(hide yes)
			(effects
				(font
					(size 1.27 1.27)
					(thickness 0.15)
				)
				(justify mirror)
			)
		)
		(property "MPN" "CR0402-FX-1001GLF"
			(at 0 0 0)
			(unlocked yes)
			(layer "B.Fab")
			(hide yes)
			(effects
				(font
					(size 1 1)
					(thickness 0.15)
				)
				(justify mirror)
			)
		)
		(property "Manufacturer" "Bourns"
			(at 0 0 0)
			(unlocked yes)
			(layer "B.Fab")
			(hide yes)
			(effects
				(font
					(size 1 1)
					(thickness 0.15)
				)
				(justify mirror)
			)
		)
		(property "License" "Apache-2.0"
			(at 0 0 0)
			(unlocked yes)
			(layer "B.Fab")
			(hide yes)
			(effects
				(font
					(size 1 1)
					(thickness 0.15)
				)
				(justify mirror)
			)
		)
		(property "Author" "Antmicro"
			(at 0 0 0)
			(unlocked yes)
			(layer "B.Fab")
			(hide yes)
			(effects
				(font
					(size 1 1)
					(thickness 0.15)
				)
				(justify mirror)
			)
		)
		(property "Val" "1k"
			(at 0 0 0)
			(unlocked yes)
			(layer "B.Fab")
			(hide yes)
			(effects
				(font
					(size 1 1)
					(thickness 0.15)
				)
				(justify mirror)
			)
		)
		(property "Tolerance" "1%"
			(at 0 0 0)
			(unlocked yes)
			(layer "B.Fab")
			(hide yes)
			(effects
				(font
					(size 1 1)
					(thickness 0.15)
				)
				(justify mirror)
			)
		)
		(property "Public" "False"
			(at 0 0 0)
			(unlocked yes)
			(layer "B.Fab")
			(hide yes)
			(effects
				(font
					(size 1 1)
					(thickness 0.15)
				)
				(justify mirror)
			)
		)
		(sheetname "Root")
		(sheetfile "jetson-orin-baseboard-oculink-expansion.kicad_sch")
		(attr smd)
		(fp_rect
			(start -0.925 0.47)
			(end 0.925 -0.47)
			(stroke
				(width 0.05)
				(type default)
			)
			(fill none)
			(layer "B.CrtYd")
		)
		(fp_rect
			(start -0.5 0.25)
			(end 0.5 -0.25)
			(stroke
				(width 0.15)
				(type solid)
			)
			(fill none)
			(layer "B.Fab")
		)
		(fp_text user "License: Apache-2.0"
			(at -0.95 -5.169 0)
			(layer "B.Fab")
			(hide yes)
			(effects
				(font
					(size 0.7 0.7)
					(thickness 0.15)
				)
				(justify left bottom mirror)
			)
		)
		(fp_text user "${REFERENCE}"
			(at -0.95 -3.168 0)
			(layer "B.Fab")
			(hide yes)
			(effects
				(font
					(size 0.7 0.7)
					(thickness 0.15)
				)
				(justify left bottom mirror)
			)
		)
		(fp_text user "Author: Antmicro"
			(at -0.95 -4.169 0)
			(layer "B.Fab")
			(hide yes)
			(effects
				(font
					(size 0.7 0.7)
					(thickness 0.15)
				)
				(justify left bottom mirror)
			)
		)
		(pad "1" smd roundrect
			(at -0.48 0 180)
			(size 0.59 0.64)
			(layers "B.Cu" "B.Paste" "B.Mask")
			(roundrect_rratio 0.25)
			(net 23 "+3V3")
			(pintype "passive")
		)
		(pad "2" smd roundrect
			(at 0.48 0 180)
			(size 0.59 0.64)
			(layers "B.Cu" "B.Paste" "B.Mask")
			(roundrect_rratio 0.25)
			(net 94 "/RX_SW")
			(pintype "passive")
		)
	)
	(footprint "antmicro-footprints:R_0402_1005Metric"
		(layer "B.Cu")
		(at 129.794 128.00775 180)
		(descr "Resistor SMD 0402")
		(tags "resistor SMD 0402")
		(property "Reference" "R19"
			(at -3.336 -0.42225 0)
			(layer "B.SilkS")
			(effects
				(font
					(size 0.7 0.7)
					(thickness 0.15)
				)
				(justify left bottom mirror)
			)
		)
		(property "Value" "R_1k_0402"
			(at -1.011843 -1.772047 0)
			(layer "B.Fab")
			(effects
				(font
					(size 0.7 0.7)
					(thickness 0.15)
				)
				(justify left bottom mirror)
			)
		)
		(property "Footprint" "antmicro-footprints:R_0402_1005Metric"
			(at 0 0 0)
			(layer "B.Fab")
			(hide yes)
			(effects
				(font
					(size 1.27 1.27)
					(thickness 0.15)
				)
				(justify mirror)
			)
		)
		(property "Datasheet" "https://www.bourns.com/docs/product-datasheets/cr.pdf"
			(at 0 0 0)
			(layer "B.Fab")
			(hide yes)
			(effects
				(font
					(size 1.27 1.27)
					(thickness 0.15)
				)
				(justify mirror)
			)
		)
		(property "Description" "SMD Chip Resistor, 1 kohm, ± 1%, 63 mW, 0402 [1005 Metric], Thick Film, General Purpose"
			(at 0 0 0)
			(layer "B.Fab")
			(hide yes)
			(effects
				(font
					(size 1.27 1.27)
					(thickness 0.15)
				)
				(justify mirror)
			)
		)
		(property "MPN" "CR0402-FX-1001GLF"
			(at 0 0 0)
			(unlocked yes)
			(layer "B.Fab")
			(hide yes)
			(effects
				(font
					(size 1 1)
					(thickness 0.15)
				)
				(justify mirror)
			)
		)
		(property "Manufacturer" "Bourns"
			(at 0 0 0)
			(unlocked yes)
			(layer "B.Fab")
			(hide yes)
			(effects
				(font
					(size 1 1)
					(thickness 0.15)
				)
				(justify mirror)
			)
		)
		(property "License" "Apache-2.0"
			(at 0 0 0)
			(unlocked yes)
			(layer "B.Fab")
			(hide yes)
			(effects
				(font
					(size 1 1)
					(thickness 0.15)
				)
				(justify mirror)
			)
		)
		(property "Author" "Antmicro"
			(at 0 0 0)
			(unlocked yes)
			(layer "B.Fab")
			(hide yes)
			(effects
				(font
					(size 1 1)
					(thickness 0.15)
				)
				(justify mirror)
			)
		)
		(property "Val" "1k"
			(at 0 0 0)
			(unlocked yes)
			(layer "B.Fab")
			(hide yes)
			(effects
				(font
					(size 1 1)
					(thickness 0.15)
				)
				(justify mirror)
			)
		)
		(property "Tolerance" "1%"
			(at 0 0 0)
			(unlocked yes)
			(layer "B.Fab")
			(hide yes)
			(effects
				(font
					(size 1 1)
					(thickness 0.15)
				)
				(justify mirror)
			)
		)
		(property "Public" "False"
			(at 0 0 0)
			(unlocked yes)
			(layer "B.Fab")
			(hide yes)
			(effects
				(font
					(size 1 1)
					(thickness 0.15)
				)
				(justify mirror)
			)
		)
		(sheetname "Root")
		(sheetfile "jetson-orin-baseboard-oculink-expansion.kicad_sch")
		(attr smd)
		(fp_rect
			(start -0.925 0.47)
			(end 0.925 -0.47)
			(stroke
				(width 0.05)
				(type default)
			)
			(fill none)
			(layer "B.CrtYd")
		)
		(fp_rect
			(start -0.5 0.25)
			(end 0.5 -0.25)
			(stroke
				(width 0.15)
				(type solid)
			)
			(fill none)
			(layer "B.Fab")
		)
		(fp_text user "Author: Antmicro"
			(at -0.95 -4.169 0)
			(layer "B.Fab")
			(hide yes)
			(effects
				(font
					(size 0.7 0.7)
					(thickness 0.15)
				)
				(justify left bottom mirror)
			)
		)
		(fp_text user "License: Apache-2.0"
			(at -0.95 -5.169 0)
			(layer "B.Fab")
			(hide yes)
			(effects
				(font
					(size 0.7 0.7)
					(thickness 0.15)
				)
				(justify left bottom mirror)
			)
		)
		(fp_text user "${REFERENCE}"
			(at -0.95 -3.168 0)
			(layer "B.Fab")
			(hide yes)
			(effects
				(font
					(size 0.7 0.7)
					(thickness 0.15)
				)
				(justify left bottom mirror)
			)
		)
		(pad "1" smd roundrect
			(at -0.48 0 180)
			(size 0.59 0.64)
			(layers "B.Cu" "B.Paste" "B.Mask")
			(roundrect_rratio 0.25)
			(net 51 "GND")
			(pintype "passive")
		)
		(pad "2" smd roundrect
			(at 0.48 0 180)
			(size 0.59 0.64)
			(layers "B.Cu" "B.Paste" "B.Mask")
			(roundrect_rratio 0.25)
			(net 96 "/TX_EQ0")
			(pintype "passive")
		)
	)
	(footprint "antmicro-footprints:R_0402_1005Metric"
		(layer "B.Cu")
		(at 130.5 116.23 180)
		(descr "Resistor SMD 0402")
		(tags "resistor SMD 0402")
		(property "Reference" "R41"
			(at -2.946 -0.391749 0)
			(layer "B.SilkS")
			(effects
				(font
					(size 0.7 0.7)
					(thickness 0.15)
				)
				(justify left bottom mirror)
			)
		)
		(property "Value" "R_10k_0402"
			(at -1.011843 -1.772047 0)
			(layer "B.Fab")
			(effects
				(font
					(size 0.7 0.7)
					(thickness 0.15)
				)
				(justify left bottom mirror)
			)
		)
		(property "Footprint" "antmicro-footprints:R_0402_1005Metric"
			(at 0 0 0)
			(layer "B.Fab")
			(hide yes)
			(effects
				(font
					(size 1.27 1.27)
					(thickness 0.15)
				)
				(justify mirror)
			)
		)
		(property "Datasheet" "https://www.bourns.com/docs/product-datasheets/cr.pdf"
			(at 0 0 0)
			(layer "B.Fab")
			(hide yes)
			(effects
				(font
					(size 1.27 1.27)
					(thickness 0.15)
				)
				(justify mirror)
			)
		)
		(property "Description" "SMD Chip Resistor, 10 kohm, ± 1%, 62.5 mW, 0402 [1005 Metric], Thick Film, General Purpose"
			(at 0 0 0)
			(layer "B.Fab")
			(hide yes)
			(effects
				(font
					(size 1.27 1.27)
					(thickness 0.15)
				)
				(justify mirror)
			)
		)
		(property "MPN" "CR0402-FX-1002GLF"
			(at 0 0 0)
			(unlocked yes)
			(layer "B.Fab")
			(hide yes)
			(effects
				(font
					(size 1 1)
					(thickness 0.15)
				)
				(justify mirror)
			)
		)
		(property "Manufacturer" "Bourns"
			(at 0 0 0)
			(unlocked yes)
			(layer "B.Fab")
			(hide yes)
			(effects
				(font
					(size 1 1)
					(thickness 0.15)
				)
				(justify mirror)
			)
		)
		(property "License" "Apache-2.0"
			(at 0 0 0)
			(unlocked yes)
			(layer "B.Fab")
			(hide yes)
			(effects
				(font
					(size 1 1)
					(thickness 0.15)
				)
				(justify mirror)
			)
		)
		(property "Author" "Antmicro"
			(at 0 0 0)
			(unlocked yes)
			(layer "B.Fab")
			(hide yes)
			(effects
				(font
					(size 1 1)
					(thickness 0.15)
				)
				(justify mirror)
			)
		)
		(property "Val" "10k"
			(at 0 0 0)
			(unlocked yes)
			(layer "B.Fab")
			(hide yes)
			(effects
				(font
					(size 1 1)
					(thickness 0.15)
				)
				(justify mirror)
			)
		)
		(property "Tolerance" "1%"
			(at 0 0 0)
			(unlocked yes)
			(layer "B.Fab")
			(hide yes)
			(effects
				(font
					(size 1 1)
					(thickness 0.15)
				)
				(justify mirror)
			)
		)
		(sheetname "Root")
		(sheetfile "jetson-orin-baseboard-oculink-expansion.kicad_sch")
		(attr smd)
		(fp_rect
			(start -0.925 0.47)
			(end 0.925 -0.47)
			(stroke
				(width 0.05)
				(type default)
			)
			(fill none)
			(layer "B.CrtYd")
		)
		(fp_rect
			(start -0.5 0.25)
			(end 0.5 -0.25)
			(stroke
				(width 0.15)
				(type solid)
			)
			(fill none)
			(layer "B.Fab")
		)
		(fp_text user "License: Apache-2.0"
			(at -0.95 -5.169 0)
			(layer "B.Fab")
			(hide yes)
			(effects
				(font
					(size 0.7 0.7)
					(thickness 0.15)
				)
				(justify left bottom mirror)
			)
		)
		(fp_text user "Author: Antmicro"
			(at -0.95 -4.169 0)
			(layer "B.Fab")
			(hide yes)
			(effects
				(font
					(size 0.7 0.7)
					(thickness 0.15)
				)
				(justify left bottom mirror)
			)
		)
		(fp_text user "${REFERENCE}"
			(at -0.95 -3.168 0)
			(layer "B.Fab")
			(hide yes)
			(effects
				(font
					(size 0.7 0.7)
					(thickness 0.15)
				)
				(justify left bottom mirror)
			)
		)
		(pad "1" smd roundrect
			(at -0.48 0 180)
			(size 0.59 0.64)
			(layers "B.Cu" "B.Paste" "B.Mask")
			(roundrect_rratio 0.25)
			(net 106 "Net-(U2-SCL)")
			(pintype "passive")
		)
		(pad "2" smd roundrect
			(at 0.48 0 180)
			(size 0.59 0.64)
			(layers "B.Cu" "B.Paste" "B.Mask")
			(roundrect_rratio 0.25)
			(net 23 "+3V3")
			(pintype "passive")
		)
	)
	(footprint "antmicro-footprints:C_0402_1005Metric"
		(layer "B.Cu")
		(at 121.275 125.795 90)
		(descr "Capacitor SMD 0402")
		(tags "capacitor SMD 0402")
		(property "Reference" "C22"
			(at 1.605 -0.385 90)
			(layer "B.SilkS")
			(effects
				(font
					(size 0.7 0.7)
					(thickness 0.15)
				)
				(justify right top mirror)
			)
		)
		(property "Value" "C_100n_0402"
			(at -1.022927 -2.155213 90)
			(layer "B.Fab")
			(effects
				(font
					(size 0.7 0.7)
					(thickness 0.15)
				)
				(justify right top mirror)
			)
		)
		(property "Footprint" "antmicro-footprints:C_0402_1005Metric"
			(at 0 0 90)
			(layer "B.Fab")
			(hide yes)
			(effects
				(font
					(size 1.27 1.27)
					(thickness 0.15)
				)
				(justify mirror)
			)
		)
		(property "Datasheet" "https://www.murata.com/products/productdetail?partno=GRM155R61H104KE14%23"
			(at 0 0 90)
			(layer "B.Fab")
			(hide yes)
			(effects
				(font
					(size 1.27 1.27)
					(thickness 0.15)
				)
				(justify mirror)
			)
		)
		(property "Description" "SMD Multilayer Ceramic Capacitor, 0.1 µF, 50 V, 0402 [1005 Metric], ± 10%, X5R, GRM Series"
			(at 0 0 90)
			(layer "B.Fab")
			(hide yes)
			(effects
				(font
					(size 1.27 1.27)
					(thickness 0.15)
				)
				(justify mirror)
			)
		)
		(property "MPN" "GRM155R61H104KE14D"
			(at 0 0 -90)
			(unlocked yes)
			(layer "B.Fab")
			(hide yes)
			(effects
				(font
					(size 1 1)
					(thickness 0.15)
				)
				(justify mirror)
			)
		)
		(property "Manufacturer" "Murata"
			(at 0 0 -90)
			(unlocked yes)
			(layer "B.Fab")
			(hide yes)
			(effects
				(font
					(size 1 1)
					(thickness 0.15)
				)
				(justify mirror)
			)
		)
		(property "License" "Apache-2.0"
			(at 0 0 -90)
			(unlocked yes)
			(layer "B.Fab")
			(hide yes)
			(effects
				(font
					(size 1 1)
					(thickness 0.15)
				)
				(justify mirror)
			)
		)
		(property "Author" "Antmicro"
			(at 0 0 -90)
			(unlocked yes)
			(layer "B.Fab")
			(hide yes)
			(effects
				(font
					(size 1 1)
					(thickness 0.15)
				)
				(justify mirror)
			)
		)
		(property "Val" "100n"
			(at 0 0 -90)
			(unlocked yes)
			(layer "B.Fab")
			(hide yes)
			(effects
				(font
					(size 1 1)
					(thickness 0.15)
				)
				(justify mirror)
			)
		)
		(property "Voltage" "50V"
			(at 0 0 -90)
			(unlocked yes)
			(layer "B.Fab")
			(hide yes)
			(effects
				(font
					(size 1 1)
					(thickness 0.15)
				)
				(justify mirror)
			)
		)
		(property "Dielectric" "X5R"
			(at 0 0 -90)
			(unlocked yes)
			(layer "B.Fab")
			(hide yes)
			(effects
				(font
					(size 1 1)
					(thickness 0.15)
				)
				(justify mirror)
			)
		)
		(property "Public" "False"
			(at 0 0 -90)
			(unlocked yes)
			(layer "B.Fab")
			(hide yes)
			(effects
				(font
					(size 1 1)
					(thickness 0.15)
				)
				(justify mirror)
			)
		)
		(sheetname "Root")
		(sheetfile "jetson-orin-baseboard-oculink-expansion.kicad_sch")
		(attr smd)
		(fp_rect
			(start -0.925 0.47)
			(end 0.925 -0.47)
			(stroke
				(width 0.05)
				(type default)
			)
			(fill none)
			(layer "B.CrtYd")
		)
		(fp_line
			(start 0.504 -0.248)
			(end 0.504 0.25)
			(stroke
				(width 0.15)
				(type solid)
			)
			(layer "B.Fab")
		)
		(fp_line
			(start -0.494 -0.248)
			(end 0.504 -0.248)
			(stroke
				(width 0.15)
				(type solid)
			)
			(layer "B.Fab")
		)
		(fp_line
			(start 0.504 0.25)
			(end -0.494 0.25)
			(stroke
				(width 0.15)
				(type solid)
			)
			(layer "B.Fab")
		)
		(fp_line
			(start -0.494 0.25)
			(end -0.494 -0.248)
			(stroke
				(width 0.15)
				(type solid)
			)
			(layer "B.Fab")
		)
		(fp_text user "Author: Antmicro"
			(at -0.939 -3.399 90)
			(layer "B.Fab")
			(hide yes)
			(effects
				(font
					(size 0.7 0.7)
					(thickness 0.15)
				)
				(justify right top mirror)
			)
		)
		(fp_text user "${REFERENCE}"
			(at -0.939 -4.599 90)
			(layer "B.Fab")
			(hide yes)
			(effects
				(font
					(size 0.7 0.7)
					(thickness 0.15)
				)
				(justify right top mirror)
			)
		)
		(fp_text user "License: Apache-2.0"
			(at -0.939 -5.799 90)
			(layer "B.Fab")
			(hide yes)
			(effects
				(font
					(size 0.7 0.7)
					(thickness 0.15)
				)
				(justify right top mirror)
			)
		)
		(pad "1" smd roundrect
			(at -0.48 0 90)
			(size 0.59 0.64)
			(layers "B.Cu" "B.Paste" "B.Mask")
			(roundrect_rratio 0.25)
			(net 51 "GND")
			(pintype "passive")
		)
		(pad "2" smd roundrect
			(at 0.48 0 90)
			(size 0.59 0.64)
			(layers "B.Cu" "B.Paste" "B.Mask")
			(roundrect_rratio 0.25)
			(net 23 "+3V3")
			(pintype "passive")
		)
	)
	(footprint "antmicro-footprints:C_0402_1005Metric"
		(layer "B.Cu")
		(at 122.775 127.913 -90)
		(descr "Capacitor SMD 0402")
		(tags "capacitor SMD 0402")
		(property "Reference" "C19"
			(at 1.627 -0.445 90)
			(layer "B.SilkS")
			(effects
				(font
					(size 0.7 0.7)
					(thickness 0.15)
				)
				(justify left bottom mirror)
			)
		)
		(property "Value" "C_100n_0402"
			(at -1.022927 -2.155213 90)
			(layer "B.Fab")
			(effects
				(font
					(size 0.7 0.7)
					(thickness 0.15)
				)
				(justify left bottom mirror)
			)
		)
		(property "Footprint" "antmicro-footprints:C_0402_1005Metric"
			(at 0 0 90)
			(layer "B.Fab")
			(hide yes)
			(effects
				(font
					(size 1.27 1.27)
					(thickness 0.15)
				)
				(justify mirror)
			)
		)
		(property "Datasheet" "https://www.murata.com/products/productdetail?partno=GRM155R61H104KE14%23"
			(at 0 0 90)
			(layer "B.Fab")
			(hide yes)
			(effects
				(font
					(size 1.27 1.27)
					(thickness 0.15)
				)
				(justify mirror)
			)
		)
		(property "Description" "SMD Multilayer Ceramic Capacitor, 0.1 µF, 50 V, 0402 [1005 Metric], ± 10%, X5R, GRM Series"
			(at 0 0 90)
			(layer "B.Fab")
			(hide yes)
			(effects
				(font
					(size 1.27 1.27)
					(thickness 0.15)
				)
				(justify mirror)
			)
		)
		(property "MPN" "GRM155R61H104KE14D"
			(at 0 0 90)
			(unlocked yes)
			(layer "B.Fab")
			(hide yes)
			(effects
				(font
					(size 1 1)
					(thickness 0.15)
				)
				(justify mirror)
			)
		)
		(property "Manufacturer" "Murata"
			(at 0 0 90)
			(unlocked yes)
			(layer "B.Fab")
			(hide yes)
			(effects
				(font
					(size 1 1)
					(thickness 0.15)
				)
				(justify mirror)
			)
		)
		(property "License" "Apache-2.0"
			(at 0 0 90)
			(unlocked yes)
			(layer "B.Fab")
			(hide yes)
			(effects
				(font
					(size 1 1)
					(thickness 0.15)
				)
				(justify mirror)
			)
		)
		(property "Author" "Antmicro"
			(at 0 0 90)
			(unlocked yes)
			(layer "B.Fab")
			(hide yes)
			(effects
				(font
					(size 1 1)
					(thickness 0.15)
				)
				(justify mirror)
			)
		)
		(property "Val" "100n"
			(at 0 0 90)
			(unlocked yes)
			(layer "B.Fab")
			(hide yes)
			(effects
				(font
					(size 1 1)
					(thickness 0.15)
				)
				(justify mirror)
			)
		)
		(property "Voltage" "50V"
			(at 0 0 90)
			(unlocked yes)
			(layer "B.Fab")
			(hide yes)
			(effects
				(font
					(size 1 1)
					(thickness 0.15)
				)
				(justify mirror)
			)
		)
		(property "Dielectric" "X5R"
			(at 0 0 90)
			(unlocked yes)
			(layer "B.Fab")
			(hide yes)
			(effects
				(font
					(size 1 1)
					(thickness 0.15)
				)
				(justify mirror)
			)
		)
		(property "Public" "False"
			(at 0 0 90)
			(unlocked yes)
			(layer "B.Fab")
			(hide yes)
			(effects
				(font
					(size 1 1)
					(thickness 0.15)
				)
				(justify mirror)
			)
		)
		(sheetname "Root")
		(sheetfile "jetson-orin-baseboard-oculink-expansion.kicad_sch")
		(attr smd)
		(fp_rect
			(start -0.925 0.47)
			(end 0.925 -0.47)
			(stroke
				(width 0.05)
				(type default)
			)
			(fill none)
			(layer "B.CrtYd")
		)
		(fp_line
			(start -0.494 0.25)
			(end -0.494 -0.248)
			(stroke
				(width 0.15)
				(type solid)
			)
			(layer "B.Fab")
		)
		(fp_line
			(start 0.504 0.25)
			(end -0.494 0.25)
			(stroke
				(width 0.15)
				(type solid)
			)
			(layer "B.Fab")
		)
		(fp_line
			(start -0.494 -0.248)
			(end 0.504 -0.248)
			(stroke
				(width 0.15)
				(type solid)
			)
			(layer "B.Fab")
		)
		(fp_line
			(start 0.504 -0.248)
			(end 0.504 0.25)
			(stroke
				(width 0.15)
				(type solid)
			)
			(layer "B.Fab")
		)
		(fp_text user "Author: Antmicro"
			(at -0.939 -3.399 90)
			(layer "B.Fab")
			(hide yes)
			(effects
				(font
					(size 0.7 0.7)
					(thickness 0.15)
				)
				(justify left bottom mirror)
			)
		)
		(fp_text user "License: Apache-2.0"
			(at -0.939 -5.799 90)
			(layer "B.Fab")
			(hide yes)
			(effects
				(font
					(size 0.7 0.7)
					(thickness 0.15)
				)
				(justify left bottom mirror)
			)
		)
		(fp_text user "${REFERENCE}"
			(at -0.939 -4.599 90)
			(layer "B.Fab")
			(hide yes)
			(effects
				(font
					(size 0.7 0.7)
					(thickness 0.15)
				)
				(justify left bottom mirror)
			)
		)
		(pad "1" smd roundrect
			(at -0.48 0 270)
			(size 0.59 0.64)
			(layers "B.Cu" "B.Paste" "B.Mask")
			(roundrect_rratio 0.25)
			(net 51 "GND")
			(pintype "passive")
		)
		(pad "2" smd roundrect
			(at 0.48 0 270)
			(size 0.59 0.64)
			(layers "B.Cu" "B.Paste" "B.Mask")
			(roundrect_rratio 0.25)
			(net 23 "+3V3")
			(pintype "passive")
		)
	)
	(footprint "antmicro-footprints:R_0402_1005Metric"
		(layer "B.Cu")
		(at 127.944 125.32775)
		(descr "Resistor SMD 0402")
		(tags "resistor SMD 0402")
		(property "Reference" "R23"
			(at -3.274 -0.37775 0)
			(layer "B.SilkS")
			(effects
				(font
					(size 0.7 0.7)
					(thickness 0.15)
				)
				(justify right top mirror)
			)
		)
		(property "Value" "R_1k_0402"
			(at -1.011843 -1.772047 0)
			(layer "B.Fab")
			(effects
				(font
					(size 0.7 0.7)
					(thickness 0.15)
				)
				(justify right top mirror)
			)
		)
		(property "Footprint" "antmicro-footprints:R_0402_1005Metric"
			(at 0 0 0)
			(layer "B.Fab")
			(hide yes)
			(effects
				(font
					(size 1.27 1.27)
					(thickness 0.15)
				)
				(justify mirror)
			)
		)
		(property "Datasheet" "https://www.bourns.com/docs/product-datasheets/cr.pdf"
			(at 0 0 0)
			(layer "B.Fab")
			(hide yes)
			(effects
				(font
					(size 1.27 1.27)
					(thickness 0.15)
				)
				(justify mirror)
			)
		)
		(property "Description" "SMD Chip Resistor, 1 kohm, ± 1%, 63 mW, 0402 [1005 Metric], Thick Film, General Purpose"
			(at 0 0 0)
			(layer "B.Fab")
			(hide yes)
			(effects
				(font
					(size 1.27 1.27)
					(thickness 0.15)
				)
				(justify mirror)
			)
		)
		(property "MPN" "CR0402-FX-1001GLF"
			(at 0 0 180)
			(unlocked yes)
			(layer "B.Fab")
			(hide yes)
			(effects
				(font
					(size 1 1)
					(thickness 0.15)
				)
				(justify mirror)
			)
		)
		(property "Manufacturer" "Bourns"
			(at 0 0 180)
			(unlocked yes)
			(layer "B.Fab")
			(hide yes)
			(effects
				(font
					(size 1 1)
					(thickness 0.15)
				)
				(justify mirror)
			)
		)
		(property "License" "Apache-2.0"
			(at 0 0 180)
			(unlocked yes)
			(layer "B.Fab")
			(hide yes)
			(effects
				(font
					(size 1 1)
					(thickness 0.15)
				)
				(justify mirror)
			)
		)
		(property "Author" "Antmicro"
			(at 0 0 180)
			(unlocked yes)
			(layer "B.Fab")
			(hide yes)
			(effects
				(font
					(size 1 1)
					(thickness 0.15)
				)
				(justify mirror)
			)
		)
		(property "Val" "1k"
			(at 0 0 180)
			(unlocked yes)
			(layer "B.Fab")
			(hide yes)
			(effects
				(font
					(size 1 1)
					(thickness 0.15)
				)
				(justify mirror)
			)
		)
		(property "Tolerance" "1%"
			(at 0 0 180)
			(unlocked yes)
			(layer "B.Fab")
			(hide yes)
			(effects
				(font
					(size 1 1)
					(thickness 0.15)
				)
				(justify mirror)
			)
		)
		(property "Public" "False"
			(at 0 0 180)
			(unlocked yes)
			(layer "B.Fab")
			(hide yes)
			(effects
				(font
					(size 1 1)
					(thickness 0.15)
				)
				(justify mirror)
			)
		)
		(sheetname "Root")
		(sheetfile "jetson-orin-baseboard-oculink-expansion.kicad_sch")
		(attr smd dnp)
		(fp_rect
			(start -0.925 0.47)
			(end 0.925 -0.47)
			(stroke
				(width 0.05)
				(type default)
			)
			(fill none)
			(layer "B.CrtYd")
		)
		(fp_rect
			(start -0.5 0.25)
			(end 0.5 -0.25)
			(stroke
				(width 0.15)
				(type solid)
			)
			(fill none)
			(layer "B.Fab")
		)
		(fp_text user "Author: Antmicro"
			(at -0.95 -4.169 0)
			(layer "B.Fab")
			(hide yes)
			(effects
				(font
					(size 0.7 0.7)
					(thickness 0.15)
				)
				(justify right top mirror)
			)
		)
		(fp_text user "${REFERENCE}"
			(at -0.95 -3.168 0)
			(layer "B.Fab")
			(hide yes)
			(effects
				(font
					(size 0.7 0.7)
					(thickness 0.15)
				)
				(justify right top mirror)
			)
		)
		(fp_text user "License: Apache-2.0"
			(at -0.95 -5.169 0)
			(layer "B.Fab")
			(hide yes)
			(effects
				(font
					(size 0.7 0.7)
					(thickness 0.15)
				)
				(justify right top mirror)
			)
		)
		(pad "1" smd roundrect
			(at -0.48 0)
			(size 0.59 0.64)
			(layers "B.Cu" "B.Paste" "B.Mask")
			(roundrect_rratio 0.25)
			(net 23 "+3V3")
			(pintype "passive")
		)
		(pad "2" smd roundrect
			(at 0.48 0)
			(size 0.59 0.64)
			(layers "B.Cu" "B.Paste" "B.Mask")
			(roundrect_rratio 0.25)
			(net 99 "/TX_EQ2")
			(pintype "passive")
		)
	)
	(footprint "antmicro-footprints:R_0402_1005Metric"
		(layer "B.Cu")
		(at 116.475 113.973751)
		(descr "Resistor SMD 0402")
		(tags "resistor SMD 0402")
		(property "Reference" "R5"
			(at -2.585 -0.383751 0)
			(layer "B.SilkS")
			(effects
				(font
					(size 0.7 0.7)
					(thickness 0.15)
				)
				(justify right top mirror)
			)
		)
		(property "Value" "R_1k_0402"
			(at -1.011843 -1.772047 0)
			(layer "B.Fab")
			(effects
				(font
					(size 0.7 0.7)
					(thickness 0.15)
				)
				(justify right top mirror)
			)
		)
		(property "Footprint" "antmicro-footprints:R_0402_1005Metric"
			(at 0 0 0)
			(layer "B.Fab")
			(hide yes)
			(effects
				(font
					(size 1.27 1.27)
					(thickness 0.15)
				)
				(justify mirror)
			)
		)
		(property "Datasheet" "https://www.bourns.com/docs/product-datasheets/cr.pdf"
			(at 0 0 0)
			(layer "B.Fab")
			(hide yes)
			(effects
				(font
					(size 1.27 1.27)
					(thickness 0.15)
				)
				(justify mirror)
			)
		)
		(property "Description" "SMD Chip Resistor, 1 kohm, ± 1%, 63 mW, 0402 [1005 Metric], Thick Film, General Purpose"
			(at 0 0 0)
			(layer "B.Fab")
			(hide yes)
			(effects
				(font
					(size 1.27 1.27)
					(thickness 0.15)
				)
				(justify mirror)
			)
		)
		(property "MPN" "CR0402-FX-1001GLF"
			(at 0 0 180)
			(unlocked yes)
			(layer "B.Fab")
			(hide yes)
			(effects
				(font
					(size 1 1)
					(thickness 0.15)
				)
				(justify mirror)
			)
		)
		(property "Manufacturer" "Bourns"
			(at 0 0 180)
			(unlocked yes)
			(layer "B.Fab")
			(hide yes)
			(effects
				(font
					(size 1 1)
					(thickness 0.15)
				)
				(justify mirror)
			)
		)
		(property "License" "Apache-2.0"
			(at 0 0 180)
			(unlocked yes)
			(layer "B.Fab")
			(hide yes)
			(effects
				(font
					(size 1 1)
					(thickness 0.15)
				)
				(justify mirror)
			)
		)
		(property "Author" "Antmicro"
			(at 0 0 180)
			(unlocked yes)
			(layer "B.Fab")
			(hide yes)
			(effects
				(font
					(size 1 1)
					(thickness 0.15)
				)
				(justify mirror)
			)
		)
		(property "Val" "1k"
			(at 0 0 180)
			(unlocked yes)
			(layer "B.Fab")
			(hide yes)
			(effects
				(font
					(size 1 1)
					(thickness 0.15)
				)
				(justify mirror)
			)
		)
		(property "Tolerance" "1%"
			(at 0 0 180)
			(unlocked yes)
			(layer "B.Fab")
			(hide yes)
			(effects
				(font
					(size 1 1)
					(thickness 0.15)
				)
				(justify mirror)
			)
		)
		(property "Public" "False"
			(at 0 0 180)
			(unlocked yes)
			(layer "B.Fab")
			(hide yes)
			(effects
				(font
					(size 1 1)
					(thickness 0.15)
				)
				(justify mirror)
			)
		)
		(sheetname "Root")
		(sheetfile "jetson-orin-baseboard-oculink-expansion.kicad_sch")
		(attr smd)
		(fp_rect
			(start -0.925 0.47)
			(end 0.925 -0.47)
			(stroke
				(width 0.05)
				(type default)
			)
			(fill none)
			(layer "B.CrtYd")
		)
		(fp_rect
			(start -0.5 0.25)
			(end 0.5 -0.25)
			(stroke
				(width 0.15)
				(type solid)
			)
			(fill none)
			(layer "B.Fab")
		)
		(fp_text user "Author: Antmicro"
			(at -0.95 -4.169 0)
			(layer "B.Fab")
			(hide yes)
			(effects
				(font
					(size 0.7 0.7)
					(thickness 0.15)
				)
				(justify right top mirror)
			)
		)
		(fp_text user "${REFERENCE}"
			(at -0.95 -3.168 0)
			(layer "B.Fab")
			(hide yes)
			(effects
				(font
					(size 0.7 0.7)
					(thickness 0.15)
				)
				(justify right top mirror)
			)
		)
		(fp_text user "License: Apache-2.0"
			(at -0.95 -5.169 0)
			(layer "B.Fab")
			(hide yes)
			(effects
				(font
					(size 0.7 0.7)
					(thickness 0.15)
				)
				(justify right top mirror)
			)
		)
		(pad "1" smd roundrect
			(at -0.48 0)
			(size 0.59 0.64)
			(layers "B.Cu" "B.Paste" "B.Mask")
			(roundrect_rratio 0.25)
			(net 51 "GND")
			(pintype "passive")
		)
		(pad "2" smd roundrect
			(at 0.48 0)
			(size 0.59 0.64)
			(layers "B.Cu" "B.Paste" "B.Mask")
			(roundrect_rratio 0.25)
			(net 89 "/RX_EQ0")
			(pintype "passive")
		)
	)
	(footprint "antmicro-footprints:TP_SMD_1.5mm"
		(layer "B.Cu")
		(at 142.3 141.324 180)
		(property "Reference" "TP5"
			(at -0.9 -8.12036 0)
			(layer "B.SilkS")
			(hide yes)
			(effects
				(font
					(size 0.7 0.7)
					(thickness 0.15)
				)
				(justify left bottom mirror)
			)
		)
		(property "Value" "TP_1.5mm_SMD"
			(at 1.522222 -0.978488 0)
			(layer "B.Fab")
			(effects
				(font
					(size 0.7 0.7)
					(thickness 0.15)
				)
				(justify left bottom mirror)
			)
		)
		(property "Footprint" "antmicro-footprints:TP_SMD_1.5mm"
			(at 0 0 0)
			(layer "B.Fab")
			(hide yes)
			(effects
				(font
					(size 1.27 1.27)
					(thickness 0.15)
				)
				(justify mirror)
			)
		)
		(property "Description" "test point, SMT"
			(at 0 0 0)
			(layer "B.Fab")
			(hide yes)
			(effects
				(font
					(size 1.27 1.27)
					(thickness 0.15)
				)
				(justify mirror)
			)
		)
		(property "MPN" ""
			(at 0 0 0)
			(unlocked yes)
			(layer "B.Fab")
			(hide yes)
			(effects
				(font
					(size 1 1)
					(thickness 0.15)
				)
				(justify mirror)
			)
		)
		(property "Manufacturer" ""
			(at 0 0 0)
			(unlocked yes)
			(layer "B.Fab")
			(hide yes)
			(effects
				(font
					(size 1 1)
					(thickness 0.15)
				)
				(justify mirror)
			)
		)
		(property "Author" "Antmicro"
			(at 0 0 0)
			(unlocked yes)
			(layer "B.Fab")
			(hide yes)
			(effects
				(font
					(size 1 1)
					(thickness 0.15)
				)
				(justify mirror)
			)
		)
		(property "License" "Apache-2.0"
			(at 0 0 0)
			(unlocked yes)
			(layer "B.Fab")
			(hide yes)
			(effects
				(font
					(size 1 1)
					(thickness 0.15)
				)
				(justify mirror)
			)
		)
		(sheetname "Root")
		(sheetfile "jetson-orin-baseboard-oculink-expansion.kicad_sch")
		(attr exclude_from_pos_files exclude_from_bom)
		(fp_circle
			(center 0 0)
			(end 0.85 0)
			(stroke
				(width 0.05)
				(type default)
			)
			(fill none)
			(layer "B.CrtYd")
		)
		(fp_text user "Author: Antmicro"
			(at -0.7 -4.101 0)
			(layer "B.Fab")
			(hide yes)
			(effects
				(font
					(size 0.7 0.7)
					(thickness 0.15)
				)
				(justify left bottom mirror)
			)
		)
		(fp_text user "License: Apache-2.0"
			(at -0.7 -5.301 0)
			(layer "B.Fab")
			(hide yes)
			(effects
				(font
					(size 0.7 0.7)
					(thickness 0.15)
				)
				(justify left bottom mirror)
			)
		)
		(fp_text user "${REFERENCE}"
			(at -0.7 -2.9 0)
			(layer "B.Fab")
			(hide yes)
			(effects
				(font
					(size 0.7 0.7)
					(thickness 0.15)
				)
				(justify left bottom mirror)
			)
		)
		(pad "1" smd circle
			(at 0 0 270)
			(size 1.5 1.5)
			(layers "B.Cu" "B.Mask")
			(net 67 "/JOB_GPIO07")
			(pinfunction "1")
			(pintype "passive")
		)
	)
	(footprint "antmicro-footprints:R_0402_1005Metric"
		(layer "B.Cu")
		(at 129.794 129.54775 180)
		(descr "Resistor SMD 0402")
		(tags "resistor SMD 0402")
		(property "Reference" "R28"
			(at -3.336 -0.42225 0)
			(layer "B.SilkS")
			(effects
				(font
					(size 0.7 0.7)
					(thickness 0.15)
				)
				(justify left bottom mirror)
			)
		)
		(property "Value" "R_1k_0402"
			(at -1.011843 -1.772047 0)
			(layer "B.Fab")
			(effects
				(font
					(size 0.7 0.7)
					(thickness 0.15)
				)
				(justify left bottom mirror)
			)
		)
		(property "Footprint" "antmicro-footprints:R_0402_1005Metric"
			(at 0 0 0)
			(layer "B.Fab")
			(hide yes)
			(effects
				(font
					(size 1.27 1.27)
					(thickness 0.15)
				)
				(justify mirror)
			)
		)
		(property "Datasheet" "https://www.bourns.com/docs/product-datasheets/cr.pdf"
			(at 0 0 0)
			(layer "B.Fab")
			(hide yes)
			(effects
				(font
					(size 1.27 1.27)
					(thickness 0.15)
				)
				(justify mirror)
			)
		)
		(property "Description" "SMD Chip Resistor, 1 kohm, ± 1%, 63 mW, 0402 [1005 Metric], Thick Film, General Purpose"
			(at 0 0 0)
			(layer "B.Fab")
			(hide yes)
			(effects
				(font
					(size 1.27 1.27)
					(thickness 0.15)
				)
				(justify mirror)
			)
		)
		(property "MPN" "CR0402-FX-1001GLF"
			(at 0 0 0)
			(unlocked yes)
			(layer "B.Fab")
			(hide yes)
			(effects
				(font
					(size 1 1)
					(thickness 0.15)
				)
				(justify mirror)
			)
		)
		(property "Manufacturer" "Bourns"
			(at 0 0 0)
			(unlocked yes)
			(layer "B.Fab")
			(hide yes)
			(effects
				(font
					(size 1 1)
					(thickness 0.15)
				)
				(justify mirror)
			)
		)
		(property "License" "Apache-2.0"
			(at 0 0 0)
			(unlocked yes)
			(layer "B.Fab")
			(hide yes)
			(effects
				(font
					(size 1 1)
					(thickness 0.15)
				)
				(justify mirror)
			)
		)
		(property "Author" "Antmicro"
			(at 0 0 0)
			(unlocked yes)
			(layer "B.Fab")
			(hide yes)
			(effects
				(font
					(size 1 1)
					(thickness 0.15)
				)
				(justify mirror)
			)
		)
		(property "Val" "1k"
			(at 0 0 0)
			(unlocked yes)
			(layer "B.Fab")
			(hide yes)
			(effects
				(font
					(size 1 1)
					(thickness 0.15)
				)
				(justify mirror)
			)
		)
		(property "Tolerance" "1%"
			(at 0 0 0)
			(unlocked yes)
			(layer "B.Fab")
			(hide yes)
			(effects
				(font
					(size 1 1)
					(thickness 0.15)
				)
				(justify mirror)
			)
		)
		(property "Public" "False"
			(at 0 0 0)
			(unlocked yes)
			(layer "B.Fab")
			(hide yes)
			(effects
				(font
					(size 1 1)
					(thickness 0.15)
				)
				(justify mirror)
			)
		)
		(sheetname "Root")
		(sheetfile "jetson-orin-baseboard-oculink-expansion.kicad_sch")
		(attr smd dnp)
		(fp_rect
			(start -0.925 0.47)
			(end 0.925 -0.47)
			(stroke
				(width 0.05)
				(type default)
			)
			(fill none)
			(layer "B.CrtYd")
		)
		(fp_rect
			(start -0.5 0.25)
			(end 0.5 -0.25)
			(stroke
				(width 0.15)
				(type solid)
			)
			(fill none)
			(layer "B.Fab")
		)
		(fp_text user "Author: Antmicro"
			(at -0.95 -4.169 0)
			(layer "B.Fab")
			(hide yes)
			(effects
				(font
					(size 0.7 0.7)
					(thickness 0.15)
				)
				(justify left bottom mirror)
			)
		)
		(fp_text user "${REFERENCE}"
			(at -0.95 -3.168 0)
			(layer "B.Fab")
			(hide yes)
			(effects
				(font
					(size 0.7 0.7)
					(thickness 0.15)
				)
				(justify left bottom mirror)
			)
		)
		(fp_text user "License: Apache-2.0"
			(at -0.95 -5.169 0)
			(layer "B.Fab")
			(hide yes)
			(effects
				(font
					(size 0.7 0.7)
					(thickness 0.15)
				)
				(justify left bottom mirror)
			)
		)
		(pad "1" smd roundrect
			(at -0.48 0 180)
			(size 0.59 0.64)
			(layers "B.Cu" "B.Paste" "B.Mask")
			(roundrect_rratio 0.25)
			(net 51 "GND")
			(pintype "passive")
		)
		(pad "2" smd roundrect
			(at 0.48 0 180)
			(size 0.59 0.64)
			(layers "B.Cu" "B.Paste" "B.Mask")
			(roundrect_rratio 0.25)
			(net 101 "/TX_FG1")
			(pintype "passive")
		)
	)
	(footprint "antmicro-footprints:TP_SMD_1.5mm"
		(layer "B.Cu")
		(at 142.4 135.268938 180)
		(property "Reference" "TP9"
			(at -0.8 -10.770882 0)
			(layer "B.SilkS")
			(hide yes)
			(effects
				(font
					(size 0.7 0.7)
					(thickness 0.15)
				)
				(justify left bottom mirror)
			)
		)
		(property "Value" "TP_1.5mm_SMD"
			(at 1.438222 -0.427869 0)
			(layer "B.Fab")
			(effects
				(font
					(size 0.7 0.7)
					(thickness 0.15)
				)
				(justify left bottom mirror)
			)
		)
		(property "Footprint" "antmicro-footprints:TP_SMD_1.5mm"
			(at 0 0 0)
			(layer "B.Fab")
			(hide yes)
			(effects
				(font
					(size 1.27 1.27)
					(thickness 0.15)
				)
				(justify mirror)
			)
		)
		(property "Description" "test point, SMT"
			(at 0 0 0)
			(layer "B.Fab")
			(hide yes)
			(effects
				(font
					(size 1.27 1.27)
					(thickness 0.15)
				)
				(justify mirror)
			)
		)
		(property "MPN" ""
			(at 0 0 0)
			(unlocked yes)
			(layer "B.Fab")
			(hide yes)
			(effects
				(font
					(size 1 1)
					(thickness 0.15)
				)
				(justify mirror)
			)
		)
		(property "Manufacturer" ""
			(at 0 0 0)
			(unlocked yes)
			(layer "B.Fab")
			(hide yes)
			(effects
				(font
					(size 1 1)
					(thickness 0.15)
				)
				(justify mirror)
			)
		)
		(property "Author" "Antmicro"
			(at 0 0 0)
			(unlocked yes)
			(layer "B.Fab")
			(hide yes)
			(effects
				(font
					(size 1 1)
					(thickness 0.15)
				)
				(justify mirror)
			)
		)
		(property "License" "Apache-2.0"
			(at 0 0 0)
			(unlocked yes)
			(layer "B.Fab")
			(hide yes)
			(effects
				(font
					(size 1 1)
					(thickness 0.15)
				)
				(justify mirror)
			)
		)
		(sheetname "Root")
		(sheetfile "jetson-orin-baseboard-oculink-expansion.kicad_sch")
		(attr exclude_from_pos_files exclude_from_bom)
		(fp_circle
			(center 0 0)
			(end 0.85 0)
			(stroke
				(width 0.05)
				(type default)
			)
			(fill none)
			(layer "B.CrtYd")
		)
		(fp_text user "Author: Antmicro"
			(at -0.7 -4.101 0)
			(layer "B.Fab")
			(hide yes)
			(effects
				(font
					(size 0.7 0.7)
					(thickness 0.15)
				)
				(justify left bottom mirror)
			)
		)
		(fp_text user "License: Apache-2.0"
			(at -0.7 -5.301 0)
			(layer "B.Fab")
			(hide yes)
			(effects
				(font
					(size 0.7 0.7)
					(thickness 0.15)
				)
				(justify left bottom mirror)
			)
		)
		(fp_text user "${REFERENCE}"
			(at -0.7 -2.9 0)
			(layer "B.Fab")
			(hide yes)
			(effects
				(font
					(size 0.7 0.7)
					(thickness 0.15)
				)
				(justify left bottom mirror)
			)
		)
		(pad "1" smd circle
			(at 0 0 270)
			(size 1.5 1.5)
			(layers "B.Cu" "B.Mask")
			(net 52 "+5V")
			(pinfunction "1")
			(pintype "passive")
		)
	)
	(footprint "antmicro-footprints:R_0402_1005Metric"
		(layer "B.Cu")
		(at 115.77 125.874)
		(descr "Resistor SMD 0402")
		(tags "resistor SMD 0402")
		(property "Reference" "R42"
			(at -2.916 -0.344 0)
			(layer "B.SilkS")
			(effects
				(font
					(size 0.7 0.7)
					(thickness 0.15)
				)
				(justify right top mirror)
			)
		)
		(property "Value" "R_10k_0402"
			(at -1.011843 -1.772047 0)
			(layer "B.Fab")
			(effects
				(font
					(size 0.7 0.7)
					(thickness 0.15)
				)
				(justify right top mirror)
			)
		)
		(property "Footprint" "antmicro-footprints:R_0402_1005Metric"
			(at 0 0 0)
			(layer "B.Fab")
			(hide yes)
			(effects
				(font
					(size 1.27 1.27)
					(thickness 0.15)
				)
				(justify mirror)
			)
		)
		(property "Datasheet" "https://www.bourns.com/docs/product-datasheets/cr.pdf"
			(at 0 0 0)
			(layer "B.Fab")
			(hide yes)
			(effects
				(font
					(size 1.27 1.27)
					(thickness 0.15)
				)
				(justify mirror)
			)
		)
		(property "Description" "SMD Chip Resistor, 10 kohm, ± 1%, 62.5 mW, 0402 [1005 Metric], Thick Film, General Purpose"
			(at 0 0 0)
			(layer "B.Fab")
			(hide yes)
			(effects
				(font
					(size 1.27 1.27)
					(thickness 0.15)
				)
				(justify mirror)
			)
		)
		(property "MPN" "CR0402-FX-1002GLF"
			(at 0 0 180)
			(unlocked yes)
			(layer "B.Fab")
			(hide yes)
			(effects
				(font
					(size 1 1)
					(thickness 0.15)
				)
				(justify mirror)
			)
		)
		(property "Manufacturer" "Bourns"
			(at 0 0 180)
			(unlocked yes)
			(layer "B.Fab")
			(hide yes)
			(effects
				(font
					(size 1 1)
					(thickness 0.15)
				)
				(justify mirror)
			)
		)
		(property "License" "Apache-2.0"
			(at 0 0 180)
			(unlocked yes)
			(layer "B.Fab")
			(hide yes)
			(effects
				(font
					(size 1 1)
					(thickness 0.15)
				)
				(justify mirror)
			)
		)
		(property "Author" "Antmicro"
			(at 0 0 180)
			(unlocked yes)
			(layer "B.Fab")
			(hide yes)
			(effects
				(font
					(size 1 1)
					(thickness 0.15)
				)
				(justify mirror)
			)
		)
		(property "Val" "10k"
			(at 0 0 180)
			(unlocked yes)
			(layer "B.Fab")
			(hide yes)
			(effects
				(font
					(size 1 1)
					(thickness 0.15)
				)
				(justify mirror)
			)
		)
		(property "Tolerance" "1%"
			(at 0 0 180)
			(unlocked yes)
			(layer "B.Fab")
			(hide yes)
			(effects
				(font
					(size 1 1)
					(thickness 0.15)
				)
				(justify mirror)
			)
		)
		(sheetname "Root")
		(sheetfile "jetson-orin-baseboard-oculink-expansion.kicad_sch")
		(attr smd)
		(fp_rect
			(start -0.925 0.47)
			(end 0.925 -0.47)
			(stroke
				(width 0.05)
				(type default)
			)
			(fill none)
			(layer "B.CrtYd")
		)
		(fp_rect
			(start -0.5 0.25)
			(end 0.5 -0.25)
			(stroke
				(width 0.15)
				(type solid)
			)
			(fill none)
			(layer "B.Fab")
		)
		(fp_text user "${REFERENCE}"
			(at -0.95 -3.168 0)
			(layer "B.Fab")
			(hide yes)
			(effects
				(font
					(size 0.7 0.7)
					(thickness 0.15)
				)
				(justify right top mirror)
			)
		)
		(fp_text user "Author: Antmicro"
			(at -0.95 -4.169 0)
			(layer "B.Fab")
			(hide yes)
			(effects
				(font
					(size 0.7 0.7)
					(thickness 0.15)
				)
				(justify right top mirror)
			)
		)
		(fp_text user "License: Apache-2.0"
			(at -0.95 -5.169 0)
			(layer "B.Fab")
			(hide yes)
			(effects
				(font
					(size 0.7 0.7)
					(thickness 0.15)
				)
				(justify right top mirror)
			)
		)
		(pad "1" smd roundrect
			(at -0.48 0)
			(size 0.59 0.64)
			(layers "B.Cu" "B.Paste" "B.Mask")
			(roundrect_rratio 0.25)
			(net 107 "Net-(U3-SDA)")
			(pintype "passive")
		)
		(pad "2" smd roundrect
			(at 0.48 0)
			(size 0.59 0.64)
			(layers "B.Cu" "B.Paste" "B.Mask")
			(roundrect_rratio 0.25)
			(net 23 "+3V3")
			(pintype "passive")
		)
	)
	(footprint "antmicro-footprints:TP_SMD_1.5mm"
		(layer "B.Cu")
		(at 142.4 137.287876 180)
		(property "Reference" "TP7"
			(at -0.8 -9.862124 0)
			(layer "B.SilkS")
			(hide yes)
			(effects
				(font
					(size 0.7 0.7)
					(thickness 0.15)
				)
				(justify left bottom mirror)
			)
		)
		(property "Value" "TP_1.5mm_SMD"
			(at 1.522222 -1.162028 0)
			(layer "B.Fab")
			(effects
				(font
					(size 0.7 0.7)
					(thickness 0.15)
				)
				(justify left bottom mirror)
			)
		)
		(property "Footprint" "antmicro-footprints:TP_SMD_1.5mm"
			(at 0 0 0)
			(layer "B.Fab")
			(hide yes)
			(effects
				(font
					(size 1.27 1.27)
					(thickness 0.15)
				)
				(justify mirror)
			)
		)
		(property "Description" "test point, SMT"
			(at 0 0 0)
			(layer "B.Fab")
			(hide yes)
			(effects
				(font
					(size 1.27 1.27)
					(thickness 0.15)
				)
				(justify mirror)
			)
		)
		(property "MPN" ""
			(at 0 0 0)
			(unlocked yes)
			(layer "B.Fab")
			(hide yes)
			(effects
				(font
					(size 1 1)
					(thickness 0.15)
				)
				(justify mirror)
			)
		)
		(property "Manufacturer" ""
			(at 0 0 0)
			(unlocked yes)
			(layer "B.Fab")
			(hide yes)
			(effects
				(font
					(size 1 1)
					(thickness 0.15)
				)
				(justify mirror)
			)
		)
		(property "Author" "Antmicro"
			(at 0 0 0)
			(unlocked yes)
			(layer "B.Fab")
			(hide yes)
			(effects
				(font
					(size 1 1)
					(thickness 0.15)
				)
				(justify mirror)
			)
		)
		(property "License" "Apache-2.0"
			(at 0 0 0)
			(unlocked yes)
			(layer "B.Fab")
			(hide yes)
			(effects
				(font
					(size 1 1)
					(thickness 0.15)
				)
				(justify mirror)
			)
		)
		(sheetname "Root")
		(sheetfile "jetson-orin-baseboard-oculink-expansion.kicad_sch")
		(attr exclude_from_pos_files exclude_from_bom)
		(fp_circle
			(center 0 0)
			(end 0.85 0)
			(stroke
				(width 0.05)
				(type default)
			)
			(fill none)
			(layer "B.CrtYd")
		)
		(fp_text user "Author: Antmicro"
			(at -0.7 -4.101 0)
			(layer "B.Fab")
			(hide yes)
			(effects
				(font
					(size 0.7 0.7)
					(thickness 0.15)
				)
				(justify left bottom mirror)
			)
		)
		(fp_text user "${REFERENCE}"
			(at -0.7 -2.9 0)
			(layer "B.Fab")
			(hide yes)
			(effects
				(font
					(size 0.7 0.7)
					(thickness 0.15)
				)
				(justify left bottom mirror)
			)
		)
		(fp_text user "License: Apache-2.0"
			(at -0.7 -5.301 0)
			(layer "B.Fab")
			(hide yes)
			(effects
				(font
					(size 0.7 0.7)
					(thickness 0.15)
				)
				(justify left bottom mirror)
			)
		)
		(pad "1" smd circle
			(at 0 0 270)
			(size 1.5 1.5)
			(layers "B.Cu" "B.Mask")
			(net 59 "/~{PCIE_RST}")
			(pinfunction "1")
			(pintype "passive")
		)
	)
	(footprint "antmicro-footprints:C_0402_1005Metric"
		(layer "B.Cu")
		(at 128.005 116.687251 -90)
		(descr "Capacitor SMD 0402")
		(tags "capacitor SMD 0402")
		(property "Reference" "C8"
			(at 1.782749 -0.49 90)
			(layer "B.SilkS")
			(effects
				(font
					(size 0.7 0.7)
					(thickness 0.15)
				)
				(justify left bottom mirror)
			)
		)
		(property "Value" "C_100n_0402"
			(at -1.022927 -2.155213 90)
			(layer "B.Fab")
			(effects
				(font
					(size 0.7 0.7)
					(thickness 0.15)
				)
				(justify left bottom mirror)
			)
		)
		(property "Footprint" "antmicro-footprints:C_0402_1005Metric"
			(at 0 0 90)
			(layer "B.Fab")
			(hide yes)
			(effects
				(font
					(size 1.27 1.27)
					(thickness 0.15)
				)
				(justify mirror)
			)
		)
		(property "Datasheet" "https://www.murata.com/products/productdetail?partno=GRM155R61H104KE14%23"
			(at 0 0 90)
			(layer "B.Fab")
			(hide yes)
			(effects
				(font
					(size 1.27 1.27)
					(thickness 0.15)
				)
				(justify mirror)
			)
		)
		(property "Description" "SMD Multilayer Ceramic Capacitor, 0.1 µF, 50 V, 0402 [1005 Metric], ± 10%, X5R, GRM Series"
			(at 0 0 90)
			(layer "B.Fab")
			(hide yes)
			(effects
				(font
					(size 1.27 1.27)
					(thickness 0.15)
				)
				(justify mirror)
			)
		)
		(property "MPN" "GRM155R61H104KE14D"
			(at 0 0 90)
			(unlocked yes)
			(layer "B.Fab")
			(hide yes)
			(effects
				(font
					(size 1 1)
					(thickness 0.15)
				)
				(justify mirror)
			)
		)
		(property "Manufacturer" "Murata"
			(at 0 0 90)
			(unlocked yes)
			(layer "B.Fab")
			(hide yes)
			(effects
				(font
					(size 1 1)
					(thickness 0.15)
				)
				(justify mirror)
			)
		)
		(property "License" "Apache-2.0"
			(at 0 0 90)
			(unlocked yes)
			(layer "B.Fab")
			(hide yes)
			(effects
				(font
					(size 1 1)
					(thickness 0.15)
				)
				(justify mirror)
			)
		)
		(property "Author" "Antmicro"
			(at 0 0 90)
			(unlocked yes)
			(layer "B.Fab")
			(hide yes)
			(effects
				(font
					(size 1 1)
					(thickness 0.15)
				)
				(justify mirror)
			)
		)
		(property "Val" "100n"
			(at 0 0 90)
			(unlocked yes)
			(layer "B.Fab")
			(hide yes)
			(effects
				(font
					(size 1 1)
					(thickness 0.15)
				)
				(justify mirror)
			)
		)
		(property "Voltage" "50V"
			(at 0 0 90)
			(unlocked yes)
			(layer "B.Fab")
			(hide yes)
			(effects
				(font
					(size 1 1)
					(thickness 0.15)
				)
				(justify mirror)
			)
		)
		(property "Dielectric" "X5R"
			(at 0 0 90)
			(unlocked yes)
			(layer "B.Fab")
			(hide yes)
			(effects
				(font
					(size 1 1)
					(thickness 0.15)
				)
				(justify mirror)
			)
		)
		(property "Public" "False"
			(at 0 0 90)
			(unlocked yes)
			(layer "B.Fab")
			(hide yes)
			(effects
				(font
					(size 1 1)
					(thickness 0.15)
				)
				(justify mirror)
			)
		)
		(sheetname "Root")
		(sheetfile "jetson-orin-baseboard-oculink-expansion.kicad_sch")
		(attr smd)
		(fp_rect
			(start -0.925 0.47)
			(end 0.925 -0.47)
			(stroke
				(width 0.05)
				(type default)
			)
			(fill none)
			(layer "B.CrtYd")
		)
		(fp_line
			(start -0.494 0.25)
			(end -0.494 -0.248)
			(stroke
				(width 0.15)
				(type solid)
			)
			(layer "B.Fab")
		)
		(fp_line
			(start 0.504 0.25)
			(end -0.494 0.25)
			(stroke
				(width 0.15)
				(type solid)
			)
			(layer "B.Fab")
		)
		(fp_line
			(start -0.494 -0.248)
			(end 0.504 -0.248)
			(stroke
				(width 0.15)
				(type solid)
			)
			(layer "B.Fab")
		)
		(fp_line
			(start 0.504 -0.248)
			(end 0.504 0.25)
			(stroke
				(width 0.15)
				(type solid)
			)
			(layer "B.Fab")
		)
		(fp_text user "License: Apache-2.0"
			(at -0.939 -5.799 90)
			(layer "B.Fab")
			(hide yes)
			(effects
				(font
					(size 0.7 0.7)
					(thickness 0.15)
				)
				(justify left bottom mirror)
			)
		)
		(fp_text user "${REFERENCE}"
			(at -0.939 -4.599 90)
			(layer "B.Fab")
			(hide yes)
			(effects
				(font
					(size 0.7 0.7)
					(thickness 0.15)
				)
				(justify left bottom mirror)
			)
		)
		(fp_text user "Author: Antmicro"
			(at -0.939 -3.399 90)
			(layer "B.Fab")
			(hide yes)
			(effects
				(font
					(size 0.7 0.7)
					(thickness 0.15)
				)
				(justify left bottom mirror)
			)
		)
		(pad "1" smd roundrect
			(at -0.48 0 270)
			(size 0.59 0.64)
			(layers "B.Cu" "B.Paste" "B.Mask")
			(roundrect_rratio 0.25)
			(net 51 "GND")
			(pintype "passive")
		)
		(pad "2" smd roundrect
			(at 0.48 0 270)
			(size 0.59 0.64)
			(layers "B.Cu" "B.Paste" "B.Mask")
			(roundrect_rratio 0.25)
			(net 23 "+3V3")
			(pintype "passive")
		)
	)
	(footprint "antmicro-footprints:TP_SMD_1.5mm"
		(layer "B.Cu")
		(at 142.4 133.2 180)
		(property "Reference" "TP10"
			(at -0.8 -11.67964 0)
			(layer "B.SilkS")
			(hide yes)
			(effects
				(font
					(size 0.7 0.7)
					(thickness 0.15)
				)
				(justify left bottom mirror)
			)
		)
		(property "Value" "TP_1.5mm_SMD"
			(at 1.438222 -0.611409 0)
			(layer "B.Fab")
			(effects
				(font
					(size 0.7 0.7)
					(thickness 0.15)
				)
				(justify left bottom mirror)
			)
		)
		(property "Footprint" "antmicro-footprints:TP_SMD_1.5mm"
			(at 0 0 0)
			(layer "B.Fab")
			(hide yes)
			(effects
				(font
					(size 1.27 1.27)
					(thickness 0.15)
				)
				(justify mirror)
			)
		)
		(property "Description" "test point, SMT"
			(at 0 0 0)
			(layer "B.Fab")
			(hide yes)
			(effects
				(font
					(size 1.27 1.27)
					(thickness 0.15)
				)
				(justify mirror)
			)
		)
		(property "MPN" ""
			(at 0 0 0)
			(unlocked yes)
			(layer "B.Fab")
			(hide yes)
			(effects
				(font
					(size 1 1)
					(thickness 0.15)
				)
				(justify mirror)
			)
		)
		(property "Manufacturer" ""
			(at 0 0 0)
			(unlocked yes)
			(layer "B.Fab")
			(hide yes)
			(effects
				(font
					(size 1 1)
					(thickness 0.15)
				)
				(justify mirror)
			)
		)
		(property "Author" "Antmicro"
			(at 0 0 0)
			(unlocked yes)
			(layer "B.Fab")
			(hide yes)
			(effects
				(font
					(size 1 1)
					(thickness 0.15)
				)
				(justify mirror)
			)
		)
		(property "License" "Apache-2.0"
			(at 0 0 0)
			(unlocked yes)
			(layer "B.Fab")
			(hide yes)
			(effects
				(font
					(size 1 1)
					(thickness 0.15)
				)
				(justify mirror)
			)
		)
		(sheetname "Root")
		(sheetfile "jetson-orin-baseboard-oculink-expansion.kicad_sch")
		(attr exclude_from_pos_files exclude_from_bom)
		(fp_circle
			(center 0 0)
			(end 0.85 0)
			(stroke
				(width 0.05)
				(type default)
			)
			(fill none)
			(layer "B.CrtYd")
		)
		(fp_text user "Author: Antmicro"
			(at -0.7 -4.101 0)
			(layer "B.Fab")
			(hide yes)
			(effects
				(font
					(size 0.7 0.7)
					(thickness 0.15)
				)
				(justify left bottom mirror)
			)
		)
		(fp_text user "License: Apache-2.0"
			(at -0.7 -5.301 0)
			(layer "B.Fab")
			(hide yes)
			(effects
				(font
					(size 0.7 0.7)
					(thickness 0.15)
				)
				(justify left bottom mirror)
			)
		)
		(fp_text user "${REFERENCE}"
			(at -0.7 -2.9 0)
			(layer "B.Fab")
			(hide yes)
			(effects
				(font
					(size 0.7 0.7)
					(thickness 0.15)
				)
				(justify left bottom mirror)
			)
		)
		(pad "1" smd circle
			(at 0 0 270)
			(size 1.5 1.5)
			(layers "B.Cu" "B.Mask")
			(net 20 "+1V8")
			(pinfunction "1")
			(pintype "passive")
		)
	)
	(footprint "antmicro-footprints:C_0402_1005Metric"
		(layer "B.Cu")
		(at 122.775 125.795 90)
		(descr "Capacitor SMD 0402")
		(tags "capacitor SMD 0402")
		(property "Reference" "C20"
			(at 1.605 -0.365 90)
			(layer "B.SilkS")
			(effects
				(font
					(size 0.7 0.7)
					(thickness 0.15)
				)
				(justify right top mirror)
			)
		)
		(property "Value" "C_100n_0402"
			(at -1.022927 -2.155213 90)
			(layer "B.Fab")
			(effects
				(font
					(size 0.7 0.7)
					(thickness 0.15)
				)
				(justify right top mirror)
			)
		)
		(property "Footprint" "antmicro-footprints:C_0402_1005Metric"
			(at 0 0 90)
			(layer "B.Fab")
			(hide yes)
			(effects
				(font
					(size 1.27 1.27)
					(thickness 0.15)
				)
				(justify mirror)
			)
		)
		(property "Datasheet" "https://www.murata.com/products/productdetail?partno=GRM155R61H104KE14%23"
			(at 0 0 90)
			(layer "B.Fab")
			(hide yes)
			(effects
				(font
					(size 1.27 1.27)
					(thickness 0.15)
				)
				(justify mirror)
			)
		)
		(property "Description" "SMD Multilayer Ceramic Capacitor, 0.1 µF, 50 V, 0402 [1005 Metric], ± 10%, X5R, GRM Series"
			(at 0 0 90)
			(layer "B.Fab")
			(hide yes)
			(effects
				(font
					(size 1.27 1.27)
					(thickness 0.15)
				)
				(justify mirror)
			)
		)
		(property "MPN" "GRM155R61H104KE14D"
			(at 0 0 -90)
			(unlocked yes)
			(layer "B.Fab")
			(hide yes)
			(effects
				(font
					(size 1 1)
					(thickness 0.15)
				)
				(justify mirror)
			)
		)
		(property "Manufacturer" "Murata"
			(at 0 0 -90)
			(unlocked yes)
			(layer "B.Fab")
			(hide yes)
			(effects
				(font
					(size 1 1)
					(thickness 0.15)
				)
				(justify mirror)
			)
		)
		(property "License" "Apache-2.0"
			(at 0 0 -90)
			(unlocked yes)
			(layer "B.Fab")
			(hide yes)
			(effects
				(font
					(size 1 1)
					(thickness 0.15)
				)
				(justify mirror)
			)
		)
		(property "Author" "Antmicro"
			(at 0 0 -90)
			(unlocked yes)
			(layer "B.Fab")
			(hide yes)
			(effects
				(font
					(size 1 1)
					(thickness 0.15)
				)
				(justify mirror)
			)
		)
		(property "Val" "100n"
			(at 0 0 -90)
			(unlocked yes)
			(layer "B.Fab")
			(hide yes)
			(effects
				(font
					(size 1 1)
					(thickness 0.15)
				)
				(justify mirror)
			)
		)
		(property "Voltage" "50V"
			(at 0 0 -90)
			(unlocked yes)
			(layer "B.Fab")
			(hide yes)
			(effects
				(font
					(size 1 1)
					(thickness 0.15)
				)
				(justify mirror)
			)
		)
		(property "Dielectric" "X5R"
			(at 0 0 -90)
			(unlocked yes)
			(layer "B.Fab")
			(hide yes)
			(effects
				(font
					(size 1 1)
					(thickness 0.15)
				)
				(justify mirror)
			)
		)
		(property "Public" "False"
			(at 0 0 -90)
			(unlocked yes)
			(layer "B.Fab")
			(hide yes)
			(effects
				(font
					(size 1 1)
					(thickness 0.15)
				)
				(justify mirror)
			)
		)
		(sheetname "Root")
		(sheetfile "jetson-orin-baseboard-oculink-expansion.kicad_sch")
		(attr smd)
		(fp_rect
			(start -0.925 0.47)
			(end 0.925 -0.47)
			(stroke
				(width 0.05)
				(type default)
			)
			(fill none)
			(layer "B.CrtYd")
		)
		(fp_line
			(start 0.504 -0.248)
			(end 0.504 0.25)
			(stroke
				(width 0.15)
				(type solid)
			)
			(layer "B.Fab")
		)
		(fp_line
			(start -0.494 -0.248)
			(end 0.504 -0.248)
			(stroke
				(width 0.15)
				(type solid)
			)
			(layer "B.Fab")
		)
		(fp_line
			(start 0.504 0.25)
			(end -0.494 0.25)
			(stroke
				(width 0.15)
				(type solid)
			)
			(layer "B.Fab")
		)
		(fp_line
			(start -0.494 0.25)
			(end -0.494 -0.248)
			(stroke
				(width 0.15)
				(type solid)
			)
			(layer "B.Fab")
		)
		(fp_text user "Author: Antmicro"
			(at -0.939 -3.399 90)
			(layer "B.Fab")
			(hide yes)
			(effects
				(font
					(size 0.7 0.7)
					(thickness 0.15)
				)
				(justify right top mirror)
			)
		)
		(fp_text user "License: Apache-2.0"
			(at -0.939 -5.799 90)
			(layer "B.Fab")
			(hide yes)
			(effects
				(font
					(size 0.7 0.7)
					(thickness 0.15)
				)
				(justify right top mirror)
			)
		)
		(fp_text user "${REFERENCE}"
			(at -0.939 -4.599 90)
			(layer "B.Fab")
			(hide yes)
			(effects
				(font
					(size 0.7 0.7)
					(thickness 0.15)
				)
				(justify right top mirror)
			)
		)
		(pad "1" smd roundrect
			(at -0.48 0 90)
			(size 0.59 0.64)
			(layers "B.Cu" "B.Paste" "B.Mask")
			(roundrect_rratio 0.25)
			(net 51 "GND")
			(pintype "passive")
		)
		(pad "2" smd roundrect
			(at 0.48 0 90)
			(size 0.59 0.64)
			(layers "B.Cu" "B.Paste" "B.Mask")
			(roundrect_rratio 0.25)
			(net 23 "+3V3")
			(pintype "passive")
		)
	)
	(footprint "antmicro-footprints:R_0402_1005Metric"
		(layer "B.Cu")
		(at 127.944 128.00775)
		(descr "Resistor SMD 0402")
		(tags "resistor SMD 0402")
		(property "Reference" "R17"
			(at -3.274 -0.37775 0)
			(layer "B.SilkS")
			(effects
				(font
					(size 0.7 0.7)
					(thickness 0.15)
				)
				(justify right top mirror)
			)
		)
		(property "Value" "R_1k_0402"
			(at -1.011843 -1.772047 0)
			(layer "B.Fab")
			(effects
				(font
					(size 0.7 0.7)
					(thickness 0.15)
				)
				(justify right top mirror)
			)
		)
		(property "Footprint" "antmicro-footprints:R_0402_1005Metric"
			(at 0 0 0)
			(layer "B.Fab")
			(hide yes)
			(effects
				(font
					(size 1.27 1.27)
					(thickness 0.15)
				)
				(justify mirror)
			)
		)
		(property "Datasheet" "https://www.bourns.com/docs/product-datasheets/cr.pdf"
			(at 0 0 0)
			(layer "B.Fab")
			(hide yes)
			(effects
				(font
					(size 1.27 1.27)
					(thickness 0.15)
				)
				(justify mirror)
			)
		)
		(property "Description" "SMD Chip Resistor, 1 kohm, ± 1%, 63 mW, 0402 [1005 Metric], Thick Film, General Purpose"
			(at 0 0 0)
			(layer "B.Fab")
			(hide yes)
			(effects
				(font
					(size 1.27 1.27)
					(thickness 0.15)
				)
				(justify mirror)
			)
		)
		(property "MPN" "CR0402-FX-1001GLF"
			(at 0 0 180)
			(unlocked yes)
			(layer "B.Fab")
			(hide yes)
			(effects
				(font
					(size 1 1)
					(thickness 0.15)
				)
				(justify mirror)
			)
		)
		(property "Manufacturer" "Bourns"
			(at 0 0 180)
			(unlocked yes)
			(layer "B.Fab")
			(hide yes)
			(effects
				(font
					(size 1 1)
					(thickness 0.15)
				)
				(justify mirror)
			)
		)
		(property "License" "Apache-2.0"
			(at 0 0 180)
			(unlocked yes)
			(layer "B.Fab")
			(hide yes)
			(effects
				(font
					(size 1 1)
					(thickness 0.15)
				)
				(justify mirror)
			)
		)
		(property "Author" "Antmicro"
			(at 0 0 180)
			(unlocked yes)
			(layer "B.Fab")
			(hide yes)
			(effects
				(font
					(size 1 1)
					(thickness 0.15)
				)
				(justify mirror)
			)
		)
		(property "Val" "1k"
			(at 0 0 180)
			(unlocked yes)
			(layer "B.Fab")
			(hide yes)
			(effects
				(font
					(size 1 1)
					(thickness 0.15)
				)
				(justify mirror)
			)
		)
		(property "Tolerance" "1%"
			(at 0 0 180)
			(unlocked yes)
			(layer "B.Fab")
			(hide yes)
			(effects
				(font
					(size 1 1)
					(thickness 0.15)
				)
				(justify mirror)
			)
		)
		(property "Public" "False"
			(at 0 0 180)
			(unlocked yes)
			(layer "B.Fab")
			(hide yes)
			(effects
				(font
					(size 1 1)
					(thickness 0.15)
				)
				(justify mirror)
			)
		)
		(sheetname "Root")
		(sheetfile "jetson-orin-baseboard-oculink-expansion.kicad_sch")
		(attr smd dnp)
		(fp_rect
			(start -0.925 0.47)
			(end 0.925 -0.47)
			(stroke
				(width 0.05)
				(type default)
			)
			(fill none)
			(layer "B.CrtYd")
		)
		(fp_rect
			(start -0.5 0.25)
			(end 0.5 -0.25)
			(stroke
				(width 0.15)
				(type solid)
			)
			(fill none)
			(layer "B.Fab")
		)
		(fp_text user "${REFERENCE}"
			(at -0.95 -3.168 0)
			(layer "B.Fab")
			(hide yes)
			(effects
				(font
					(size 0.7 0.7)
					(thickness 0.15)
				)
				(justify right top mirror)
			)
		)
		(fp_text user "License: Apache-2.0"
			(at -0.95 -5.169 0)
			(layer "B.Fab")
			(hide yes)
			(effects
				(font
					(size 0.7 0.7)
					(thickness 0.15)
				)
				(justify right top mirror)
			)
		)
		(fp_text user "Author: Antmicro"
			(at -0.95 -4.169 0)
			(layer "B.Fab")
			(hide yes)
			(effects
				(font
					(size 0.7 0.7)
					(thickness 0.15)
				)
				(justify right top mirror)
			)
		)
		(pad "1" smd roundrect
			(at -0.48 0)
			(size 0.59 0.64)
			(layers "B.Cu" "B.Paste" "B.Mask")
			(roundrect_rratio 0.25)
			(net 23 "+3V3")
			(pintype "passive")
		)
		(pad "2" smd roundrect
			(at 0.48 0)
			(size 0.59 0.64)
			(layers "B.Cu" "B.Paste" "B.Mask")
			(roundrect_rratio 0.25)
			(net 96 "/TX_EQ0")
			(pintype "passive")
		)
	)
	(footprint "antmicro-footprints:C_0402_1005Metric"
		(layer "B.Cu")
		(at 123.505 114.569251 90)
		(descr "Capacitor SMD 0402")
		(tags "capacitor SMD 0402")
		(property "Reference" "C23"
			(at 1.779251 -0.355 90)
			(layer "B.SilkS")
			(effects
				(font
					(size 0.7 0.7)
					(thickness 0.15)
				)
				(justify right top mirror)
			)
		)
		(property "Value" "C_100n_0402"
			(at -1.022927 -2.155213 90)
			(layer "B.Fab")
			(effects
				(font
					(size 0.7 0.7)
					(thickness 0.15)
				)
				(justify right top mirror)
			)
		)
		(property "Footprint" "antmicro-footprints:C_0402_1005Metric"
			(at 0 0 90)
			(layer "B.Fab")
			(hide yes)
			(effects
				(font
					(size 1.27 1.27)
					(thickness 0.15)
				)
				(justify mirror)
			)
		)
		(property "Datasheet" "https://www.murata.com/products/productdetail?partno=GRM155R61H104KE14%23"
			(at 0 0 90)
			(layer "B.Fab")
			(hide yes)
			(effects
				(font
					(size 1.27 1.27)
					(thickness 0.15)
				)
				(justify mirror)
			)
		)
		(property "Description" "SMD Multilayer Ceramic Capacitor, 0.1 µF, 50 V, 0402 [1005 Metric], ± 10%, X5R, GRM Series"
			(at 0 0 90)
			(layer "B.Fab")
			(hide yes)
			(effects
				(font
					(size 1.27 1.27)
					(thickness 0.15)
				)
				(justify mirror)
			)
		)
		(property "MPN" "GRM155R61H104KE14D"
			(at 0 0 -90)
			(unlocked yes)
			(layer "B.Fab")
			(hide yes)
			(effects
				(font
					(size 1 1)
					(thickness 0.15)
				)
				(justify mirror)
			)
		)
		(property "Manufacturer" "Murata"
			(at 0 0 -90)
			(unlocked yes)
			(layer "B.Fab")
			(hide yes)
			(effects
				(font
					(size 1 1)
					(thickness 0.15)
				)
				(justify mirror)
			)
		)
		(property "License" "Apache-2.0"
			(at 0 0 -90)
			(unlocked yes)
			(layer "B.Fab")
			(hide yes)
			(effects
				(font
					(size 1 1)
					(thickness 0.15)
				)
				(justify mirror)
			)
		)
		(property "Author" "Antmicro"
			(at 0 0 -90)
			(unlocked yes)
			(layer "B.Fab")
			(hide yes)
			(effects
				(font
					(size 1 1)
					(thickness 0.15)
				)
				(justify mirror)
			)
		)
		(property "Val" "100n"
			(at 0 0 -90)
			(unlocked yes)
			(layer "B.Fab")
			(hide yes)
			(effects
				(font
					(size 1 1)
					(thickness 0.15)
				)
				(justify mirror)
			)
		)
		(property "Voltage" "50V"
			(at 0 0 -90)
			(unlocked yes)
			(layer "B.Fab")
			(hide yes)
			(effects
				(font
					(size 1 1)
					(thickness 0.15)
				)
				(justify mirror)
			)
		)
		(property "Dielectric" "X5R"
			(at 0 0 -90)
			(unlocked yes)
			(layer "B.Fab")
			(hide yes)
			(effects
				(font
					(size 1 1)
					(thickness 0.15)
				)
				(justify mirror)
			)
		)
		(property "Public" "False"
			(at 0 0 -90)
			(unlocked yes)
			(layer "B.Fab")
			(hide yes)
			(effects
				(font
					(size 1 1)
					(thickness 0.15)
				)
				(justify mirror)
			)
		)
		(sheetname "Root")
		(sheetfile "jetson-orin-baseboard-oculink-expansion.kicad_sch")
		(attr smd)
		(fp_rect
			(start -0.925 0.47)
			(end 0.925 -0.47)
			(stroke
				(width 0.05)
				(type default)
			)
			(fill none)
			(layer "B.CrtYd")
		)
		(fp_line
			(start 0.504 -0.248)
			(end 0.504 0.25)
			(stroke
				(width 0.15)
				(type solid)
			)
			(layer "B.Fab")
		)
		(fp_line
			(start -0.494 -0.248)
			(end 0.504 -0.248)
			(stroke
				(width 0.15)
				(type solid)
			)
			(layer "B.Fab")
		)
		(fp_line
			(start 0.504 0.25)
			(end -0.494 0.25)
			(stroke
				(width 0.15)
				(type solid)
			)
			(layer "B.Fab")
		)
		(fp_line
			(start -0.494 0.25)
			(end -0.494 -0.248)
			(stroke
				(width 0.15)
				(type solid)
			)
			(layer "B.Fab")
		)
		(fp_text user "${REFERENCE}"
			(at -0.939 -4.599 90)
			(layer "B.Fab")
			(hide yes)
			(effects
				(font
					(size 0.7 0.7)
					(thickness 0.15)
				)
				(justify right top mirror)
			)
		)
		(fp_text user "Author: Antmicro"
			(at -0.939 -3.399 90)
			(layer "B.Fab")
			(hide yes)
			(effects
				(font
					(size 0.7 0.7)
					(thickness 0.15)
				)
				(justify right top mirror)
			)
		)
		(fp_text user "License: Apache-2.0"
			(at -0.939 -5.799 90)
			(layer "B.Fab")
			(hide yes)
			(effects
				(font
					(size 0.7 0.7)
					(thickness 0.15)
				)
				(justify right top mirror)
			)
		)
		(pad "1" smd roundrect
			(at -0.48 0 90)
			(size 0.59 0.64)
			(layers "B.Cu" "B.Paste" "B.Mask")
			(roundrect_rratio 0.25)
			(net 51 "GND")
			(pintype "passive")
		)
		(pad "2" smd roundrect
			(at 0.48 0 90)
			(size 0.59 0.64)
			(layers "B.Cu" "B.Paste" "B.Mask")
			(roundrect_rratio 0.25)
			(net 23 "+3V3")
			(pintype "passive")
		)
	)
	(footprint "antmicro-footprints:R_0402_1005Metric"
		(layer "B.Cu")
		(at 129.794 130.88775 180)
		(descr "Resistor SMD 0402")
		(tags "resistor SMD 0402")
		(property "Reference" "R26"
			(at -3.336 -0.42225 0)
			(layer "B.SilkS")
			(effects
				(font
					(size 0.7 0.7)
					(thickness 0.15)
				)
				(justify left bottom mirror)
			)
		)
		(property "Value" "R_1k_0402"
			(at -1.011843 -1.772047 0)
			(layer "B.Fab")
			(effects
				(font
					(size 0.7 0.7)
					(thickness 0.15)
				)
				(justify left bottom mirror)
			)
		)
		(property "Footprint" "antmicro-footprints:R_0402_1005Metric"
			(at 0 0 0)
			(layer "B.Fab")
			(hide yes)
			(effects
				(font
					(size 1.27 1.27)
					(thickness 0.15)
				)
				(justify mirror)
			)
		)
		(property "Datasheet" "https://www.bourns.com/docs/product-datasheets/cr.pdf"
			(at 0 0 0)
			(layer "B.Fab")
			(hide yes)
			(effects
				(font
					(size 1.27 1.27)
					(thickness 0.15)
				)
				(justify mirror)
			)
		)
		(property "Description" "SMD Chip Resistor, 1 kohm, ± 1%, 63 mW, 0402 [1005 Metric], Thick Film, General Purpose"
			(at 0 0 0)
			(layer "B.Fab")
			(hide yes)
			(effects
				(font
					(size 1.27 1.27)
					(thickness 0.15)
				)
				(justify mirror)
			)
		)
		(property "MPN" "CR0402-FX-1001GLF"
			(at 0 0 0)
			(unlocked yes)
			(layer "B.Fab")
			(hide yes)
			(effects
				(font
					(size 1 1)
					(thickness 0.15)
				)
				(justify mirror)
			)
		)
		(property "Manufacturer" "Bourns"
			(at 0 0 0)
			(unlocked yes)
			(layer "B.Fab")
			(hide yes)
			(effects
				(font
					(size 1 1)
					(thickness 0.15)
				)
				(justify mirror)
			)
		)
		(property "License" "Apache-2.0"
			(at 0 0 0)
			(unlocked yes)
			(layer "B.Fab")
			(hide yes)
			(effects
				(font
					(size 1 1)
					(thickness 0.15)
				)
				(justify mirror)
			)
		)
		(property "Author" "Antmicro"
			(at 0 0 0)
			(unlocked yes)
			(layer "B.Fab")
			(hide yes)
			(effects
				(font
					(size 1 1)
					(thickness 0.15)
				)
				(justify mirror)
			)
		)
		(property "Val" "1k"
			(at 0 0 0)
			(unlocked yes)
			(layer "B.Fab")
			(hide yes)
			(effects
				(font
					(size 1 1)
					(thickness 0.15)
				)
				(justify mirror)
			)
		)
		(property "Tolerance" "1%"
			(at 0 0 0)
			(unlocked yes)
			(layer "B.Fab")
			(hide yes)
			(effects
				(font
					(size 1 1)
					(thickness 0.15)
				)
				(justify mirror)
			)
		)
		(property "Public" "False"
			(at 0 0 0)
			(unlocked yes)
			(layer "B.Fab")
			(hide yes)
			(effects
				(font
					(size 1 1)
					(thickness 0.15)
				)
				(justify mirror)
			)
		)
		(sheetname "Root")
		(sheetfile "jetson-orin-baseboard-oculink-expansion.kicad_sch")
		(attr smd)
		(fp_rect
			(start -0.925 0.47)
			(end 0.925 -0.47)
			(stroke
				(width 0.05)
				(type default)
			)
			(fill none)
			(layer "B.CrtYd")
		)
		(fp_rect
			(start -0.5 0.25)
			(end 0.5 -0.25)
			(stroke
				(width 0.15)
				(type solid)
			)
			(fill none)
			(layer "B.Fab")
		)
		(fp_text user "License: Apache-2.0"
			(at -0.95 -5.169 0)
			(layer "B.Fab")
			(hide yes)
			(effects
				(font
					(size 0.7 0.7)
					(thickness 0.15)
				)
				(justify left bottom mirror)
			)
		)
		(fp_text user "Author: Antmicro"
			(at -0.95 -4.169 0)
			(layer "B.Fab")
			(hide yes)
			(effects
				(font
					(size 0.7 0.7)
					(thickness 0.15)
				)
				(justify left bottom mirror)
			)
		)
		(fp_text user "${REFERENCE}"
			(at -0.95 -3.168 0)
			(layer "B.Fab")
			(hide yes)
			(effects
				(font
					(size 0.7 0.7)
					(thickness 0.15)
				)
				(justify left bottom mirror)
			)
		)
		(pad "1" smd roundrect
			(at -0.48 0 180)
			(size 0.59 0.64)
			(layers "B.Cu" "B.Paste" "B.Mask")
			(roundrect_rratio 0.25)
			(net 51 "GND")
			(pintype "passive")
		)
		(pad "2" smd roundrect
			(at 0.48 0 180)
			(size 0.59 0.64)
			(layers "B.Cu" "B.Paste" "B.Mask")
			(roundrect_rratio 0.25)
			(net 100 "/TX_FG0")
			(pintype "passive")
		)
	)
	(footprint "antmicro-footprints:C_0402_1005Metric"
		(layer "B.Cu")
		(at 124.275 127.914 -90)
		(descr "Capacitor SMD 0402")
		(tags "capacitor SMD 0402")
		(property "Reference" "C17"
			(at 1.626 -0.435 90)
			(layer "B.SilkS")
			(effects
				(font
					(size 0.7 0.7)
					(thickness 0.15)
				)
				(justify left bottom mirror)
			)
		)
		(property "Value" "C_100n_0402"
			(at -1.022927 -2.155213 90)
			(layer "B.Fab")
			(effects
				(font
					(size 0.7 0.7)
					(thickness 0.15)
				)
				(justify left bottom mirror)
			)
		)
		(property "Footprint" "antmicro-footprints:C_0402_1005Metric"
			(at 0 0 90)
			(layer "B.Fab")
			(hide yes)
			(effects
				(font
					(size 1.27 1.27)
					(thickness 0.15)
				)
				(justify mirror)
			)
		)
		(property "Datasheet" "https://www.murata.com/products/productdetail?partno=GRM155R61H104KE14%23"
			(at 0 0 90)
			(layer "B.Fab")
			(hide yes)
			(effects
				(font
					(size 1.27 1.27)
					(thickness 0.15)
				)
				(justify mirror)
			)
		)
		(property "Description" "SMD Multilayer Ceramic Capacitor, 0.1 µF, 50 V, 0402 [1005 Metric], ± 10%, X5R, GRM Series"
			(at 0 0 90)
			(layer "B.Fab")
			(hide yes)
			(effects
				(font
					(size 1.27 1.27)
					(thickness 0.15)
				)
				(justify mirror)
			)
		)
		(property "MPN" "GRM155R61H104KE14D"
			(at 0 0 90)
			(unlocked yes)
			(layer "B.Fab")
			(hide yes)
			(effects
				(font
					(size 1 1)
					(thickness 0.15)
				)
				(justify mirror)
			)
		)
		(property "Manufacturer" "Murata"
			(at 0 0 90)
			(unlocked yes)
			(layer "B.Fab")
			(hide yes)
			(effects
				(font
					(size 1 1)
					(thickness 0.15)
				)
				(justify mirror)
			)
		)
		(property "License" "Apache-2.0"
			(at 0 0 90)
			(unlocked yes)
			(layer "B.Fab")
			(hide yes)
			(effects
				(font
					(size 1 1)
					(thickness 0.15)
				)
				(justify mirror)
			)
		)
		(property "Author" "Antmicro"
			(at 0 0 90)
			(unlocked yes)
			(layer "B.Fab")
			(hide yes)
			(effects
				(font
					(size 1 1)
					(thickness 0.15)
				)
				(justify mirror)
			)
		)
		(property "Val" "100n"
			(at 0 0 90)
			(unlocked yes)
			(layer "B.Fab")
			(hide yes)
			(effects
				(font
					(size 1 1)
					(thickness 0.15)
				)
				(justify mirror)
			)
		)
		(property "Voltage" "50V"
			(at 0 0 90)
			(unlocked yes)
			(layer "B.Fab")
			(hide yes)
			(effects
				(font
					(size 1 1)
					(thickness 0.15)
				)
				(justify mirror)
			)
		)
		(property "Dielectric" "X5R"
			(at 0 0 90)
			(unlocked yes)
			(layer "B.Fab")
			(hide yes)
			(effects
				(font
					(size 1 1)
					(thickness 0.15)
				)
				(justify mirror)
			)
		)
		(property "Public" "False"
			(at 0 0 90)
			(unlocked yes)
			(layer "B.Fab")
			(hide yes)
			(effects
				(font
					(size 1 1)
					(thickness 0.15)
				)
				(justify mirror)
			)
		)
		(sheetname "Root")
		(sheetfile "jetson-orin-baseboard-oculink-expansion.kicad_sch")
		(attr smd)
		(fp_rect
			(start -0.925 0.47)
			(end 0.925 -0.47)
			(stroke
				(width 0.05)
				(type default)
			)
			(fill none)
			(layer "B.CrtYd")
		)
		(fp_line
			(start -0.494 0.25)
			(end -0.494 -0.248)
			(stroke
				(width 0.15)
				(type solid)
			)
			(layer "B.Fab")
		)
		(fp_line
			(start 0.504 0.25)
			(end -0.494 0.25)
			(stroke
				(width 0.15)
				(type solid)
			)
			(layer "B.Fab")
		)
		(fp_line
			(start -0.494 -0.248)
			(end 0.504 -0.248)
			(stroke
				(width 0.15)
				(type solid)
			)
			(layer "B.Fab")
		)
		(fp_line
			(start 0.504 -0.248)
			(end 0.504 0.25)
			(stroke
				(width 0.15)
				(type solid)
			)
			(layer "B.Fab")
		)
		(fp_text user "${REFERENCE}"
			(at -0.939 -4.599 90)
			(layer "B.Fab")
			(hide yes)
			(effects
				(font
					(size 0.7 0.7)
					(thickness 0.15)
				)
				(justify left bottom mirror)
			)
		)
		(fp_text user "License: Apache-2.0"
			(at -0.939 -5.799 90)
			(layer "B.Fab")
			(hide yes)
			(effects
				(font
					(size 0.7 0.7)
					(thickness 0.15)
				)
				(justify left bottom mirror)
			)
		)
		(fp_text user "Author: Antmicro"
			(at -0.939 -3.399 90)
			(layer "B.Fab")
			(hide yes)
			(effects
				(font
					(size 0.7 0.7)
					(thickness 0.15)
				)
				(justify left bottom mirror)
			)
		)
		(pad "1" smd roundrect
			(at -0.48 0 270)
			(size 0.59 0.64)
			(layers "B.Cu" "B.Paste" "B.Mask")
			(roundrect_rratio 0.25)
			(net 51 "GND")
			(pintype "passive")
		)
		(pad "2" smd roundrect
			(at 0.48 0 270)
			(size 0.59 0.64)
			(layers "B.Cu" "B.Paste" "B.Mask")
			(roundrect_rratio 0.25)
			(net 23 "+3V3")
			(pintype "passive")
		)
	)
	(footprint "antmicro-footprints:R_0402_1005Metric"
		(layer "B.Cu")
		(at 127.945 129.54775)
		(descr "Resistor SMD 0402")
		(tags "resistor SMD 0402")
		(property "Reference" "R27"
			(at -3.275 -0.37775 0)
			(layer "B.SilkS")
			(effects
				(font
					(size 0.7 0.7)
					(thickness 0.15)
				)
				(justify right top mirror)
			)
		)
		(property "Value" "R_1k_0402"
			(at -1.011843 -1.772047 0)
			(layer "B.Fab")
			(effects
				(font
					(size 0.7 0.7)
					(thickness 0.15)
				)
				(justify right top mirror)
			)
		)
		(property "Footprint" "antmicro-footprints:R_0402_1005Metric"
			(at 0 0 0)
			(layer "B.Fab")
			(hide yes)
			(effects
				(font
					(size 1.27 1.27)
					(thickness 0.15)
				)
				(justify mirror)
			)
		)
		(property "Datasheet" "https://www.bourns.com/docs/product-datasheets/cr.pdf"
			(at 0 0 0)
			(layer "B.Fab")
			(hide yes)
			(effects
				(font
					(size 1.27 1.27)
					(thickness 0.15)
				)
				(justify mirror)
			)
		)
		(property "Description" "SMD Chip Resistor, 1 kohm, ± 1%, 63 mW, 0402 [1005 Metric], Thick Film, General Purpose"
			(at 0 0 0)
			(layer "B.Fab")
			(hide yes)
			(effects
				(font
					(size 1.27 1.27)
					(thickness 0.15)
				)
				(justify mirror)
			)
		)
		(property "MPN" "CR0402-FX-1001GLF"
			(at 0 0 180)
			(unlocked yes)
			(layer "B.Fab")
			(hide yes)
			(effects
				(font
					(size 1 1)
					(thickness 0.15)
				)
				(justify mirror)
			)
		)
		(property "Manufacturer" "Bourns"
			(at 0 0 180)
			(unlocked yes)
			(layer "B.Fab")
			(hide yes)
			(effects
				(font
					(size 1 1)
					(thickness 0.15)
				)
				(justify mirror)
			)
		)
		(property "License" "Apache-2.0"
			(at 0 0 180)
			(unlocked yes)
			(layer "B.Fab")
			(hide yes)
			(effects
				(font
					(size 1 1)
					(thickness 0.15)
				)
				(justify mirror)
			)
		)
		(property "Author" "Antmicro"
			(at 0 0 180)
			(unlocked yes)
			(layer "B.Fab")
			(hide yes)
			(effects
				(font
					(size 1 1)
					(thickness 0.15)
				)
				(justify mirror)
			)
		)
		(property "Val" "1k"
			(at 0 0 180)
			(unlocked yes)
			(layer "B.Fab")
			(hide yes)
			(effects
				(font
					(size 1 1)
					(thickness 0.15)
				)
				(justify mirror)
			)
		)
		(property "Tolerance" "1%"
			(at 0 0 180)
			(unlocked yes)
			(layer "B.Fab")
			(hide yes)
			(effects
				(font
					(size 1 1)
					(thickness 0.15)
				)
				(justify mirror)
			)
		)
		(property "Public" "False"
			(at 0 0 180)
			(unlocked yes)
			(layer "B.Fab")
			(hide yes)
			(effects
				(font
					(size 1 1)
					(thickness 0.15)
				)
				(justify mirror)
			)
		)
		(sheetname "Root")
		(sheetfile "jetson-orin-baseboard-oculink-expansion.kicad_sch")
		(attr smd)
		(fp_rect
			(start -0.925 0.47)
			(end 0.925 -0.47)
			(stroke
				(width 0.05)
				(type default)
			)
			(fill none)
			(layer "B.CrtYd")
		)
		(fp_rect
			(start -0.5 0.25)
			(end 0.5 -0.25)
			(stroke
				(width 0.15)
				(type solid)
			)
			(fill none)
			(layer "B.Fab")
		)
		(fp_text user "License: Apache-2.0"
			(at -0.95 -5.169 0)
			(layer "B.Fab")
			(hide yes)
			(effects
				(font
					(size 0.7 0.7)
					(thickness 0.15)
				)
				(justify right top mirror)
			)
		)
		(fp_text user "Author: Antmicro"
			(at -0.95 -4.169 0)
			(layer "B.Fab")
			(hide yes)
			(effects
				(font
					(size 0.7 0.7)
					(thickness 0.15)
				)
				(justify right top mirror)
			)
		)
		(fp_text user "${REFERENCE}"
			(at -0.95 -3.168 0)
			(layer "B.Fab")
			(hide yes)
			(effects
				(font
					(size 0.7 0.7)
					(thickness 0.15)
				)
				(justify right top mirror)
			)
		)
		(pad "1" smd roundrect
			(at -0.48 0)
			(size 0.59 0.64)
			(layers "B.Cu" "B.Paste" "B.Mask")
			(roundrect_rratio 0.25)
			(net 23 "+3V3")
			(pintype "passive")
		)
		(pad "2" smd roundrect
			(at 0.48 0)
			(size 0.59 0.64)
			(layers "B.Cu" "B.Paste" "B.Mask")
			(roundrect_rratio 0.25)
			(net 101 "/TX_FG1")
			(pintype "passive")
		)
	)
	(footprint "antmicro-footprints:C_0402_1005Metric"
		(layer "B.Cu")
		(at 128.005 114.569251 90)
		(descr "Capacitor SMD 0402")
		(tags "capacitor SMD 0402")
		(property "Reference" "C7"
			(at 1.779251 -0.355 90)
			(layer "B.SilkS")
			(effects
				(font
					(size 0.7 0.7)
					(thickness 0.15)
				)
				(justify right top mirror)
			)
		)
		(property "Value" "C_100n_0402"
			(at -1.022927 -2.155213 90)
			(layer "B.Fab")
			(effects
				(font
					(size 0.7 0.7)
					(thickness 0.15)
				)
				(justify right top mirror)
			)
		)
		(property "Footprint" "antmicro-footprints:C_0402_1005Metric"
			(at 0 0 90)
			(layer "B.Fab")
			(hide yes)
			(effects
				(font
					(size 1.27 1.27)
					(thickness 0.15)
				)
				(justify mirror)
			)
		)
		(property "Datasheet" "https://www.murata.com/products/productdetail?partno=GRM155R61H104KE14%23"
			(at 0 0 90)
			(layer "B.Fab")
			(hide yes)
			(effects
				(font
					(size 1.27 1.27)
					(thickness 0.15)
				)
				(justify mirror)
			)
		)
		(property "Description" "SMD Multilayer Ceramic Capacitor, 0.1 µF, 50 V, 0402 [1005 Metric], ± 10%, X5R, GRM Series"
			(at 0 0 90)
			(layer "B.Fab")
			(hide yes)
			(effects
				(font
					(size 1.27 1.27)
					(thickness 0.15)
				)
				(justify mirror)
			)
		)
		(property "MPN" "GRM155R61H104KE14D"
			(at 0 0 -90)
			(unlocked yes)
			(layer "B.Fab")
			(hide yes)
			(effects
				(font
					(size 1 1)
					(thickness 0.15)
				)
				(justify mirror)
			)
		)
		(property "Manufacturer" "Murata"
			(at 0 0 -90)
			(unlocked yes)
			(layer "B.Fab")
			(hide yes)
			(effects
				(font
					(size 1 1)
					(thickness 0.15)
				)
				(justify mirror)
			)
		)
		(property "License" "Apache-2.0"
			(at 0 0 -90)
			(unlocked yes)
			(layer "B.Fab")
			(hide yes)
			(effects
				(font
					(size 1 1)
					(thickness 0.15)
				)
				(justify mirror)
			)
		)
		(property "Author" "Antmicro"
			(at 0 0 -90)
			(unlocked yes)
			(layer "B.Fab")
			(hide yes)
			(effects
				(font
					(size 1 1)
					(thickness 0.15)
				)
				(justify mirror)
			)
		)
		(property "Val" "100n"
			(at 0 0 -90)
			(unlocked yes)
			(layer "B.Fab")
			(hide yes)
			(effects
				(font
					(size 1 1)
					(thickness 0.15)
				)
				(justify mirror)
			)
		)
		(property "Voltage" "50V"
			(at 0 0 -90)
			(unlocked yes)
			(layer "B.Fab")
			(hide yes)
			(effects
				(font
					(size 1 1)
					(thickness 0.15)
				)
				(justify mirror)
			)
		)
		(property "Dielectric" "X5R"
			(at 0 0 -90)
			(unlocked yes)
			(layer "B.Fab")
			(hide yes)
			(effects
				(font
					(size 1 1)
					(thickness 0.15)
				)
				(justify mirror)
			)
		)
		(property "Public" "False"
			(at 0 0 -90)
			(unlocked yes)
			(layer "B.Fab")
			(hide yes)
			(effects
				(font
					(size 1 1)
					(thickness 0.15)
				)
				(justify mirror)
			)
		)
		(sheetname "Root")
		(sheetfile "jetson-orin-baseboard-oculink-expansion.kicad_sch")
		(attr smd)
		(fp_rect
			(start -0.925 0.47)
			(end 0.925 -0.47)
			(stroke
				(width 0.05)
				(type default)
			)
			(fill none)
			(layer "B.CrtYd")
		)
		(fp_line
			(start 0.504 -0.248)
			(end 0.504 0.25)
			(stroke
				(width 0.15)
				(type solid)
			)
			(layer "B.Fab")
		)
		(fp_line
			(start -0.494 -0.248)
			(end 0.504 -0.248)
			(stroke
				(width 0.15)
				(type solid)
			)
			(layer "B.Fab")
		)
		(fp_line
			(start 0.504 0.25)
			(end -0.494 0.25)
			(stroke
				(width 0.15)
				(type solid)
			)
			(layer "B.Fab")
		)
		(fp_line
			(start -0.494 0.25)
			(end -0.494 -0.248)
			(stroke
				(width 0.15)
				(type solid)
			)
			(layer "B.Fab")
		)
		(fp_text user "Author: Antmicro"
			(at -0.939 -3.399 90)
			(layer "B.Fab")
			(hide yes)
			(effects
				(font
					(size 0.7 0.7)
					(thickness 0.15)
				)
				(justify right top mirror)
			)
		)
		(fp_text user "License: Apache-2.0"
			(at -0.939 -5.799 90)
			(layer "B.Fab")
			(hide yes)
			(effects
				(font
					(size 0.7 0.7)
					(thickness 0.15)
				)
				(justify right top mirror)
			)
		)
		(fp_text user "${REFERENCE}"
			(at -0.939 -4.599 90)
			(layer "B.Fab")
			(hide yes)
			(effects
				(font
					(size 0.7 0.7)
					(thickness 0.15)
				)
				(justify right top mirror)
			)
		)
		(pad "1" smd roundrect
			(at -0.48 0 90)
			(size 0.59 0.64)
			(layers "B.Cu" "B.Paste" "B.Mask")
			(roundrect_rratio 0.25)
			(net 51 "GND")
			(pintype "passive")
		)
		(pad "2" smd roundrect
			(at 0.48 0 90)
			(size 0.59 0.64)
			(layers "B.Cu" "B.Paste" "B.Mask")
			(roundrect_rratio 0.25)
			(net 23 "+3V3")
			(pintype "passive")
		)
	)
	(footprint "antmicro-footprints:TP_SMD_1.5mm"
		(layer "B.Cu")
		(at 126.45 132.7 -90)
		(property "Reference" "TP1"
			(at 0.2495 -2.9365 0)
			(layer "B.SilkS")
			(hide yes)
			(effects
				(font
					(size 0.7 0.7)
					(thickness 0.15)
				)
				(justify left bottom mirror)
			)
		)
		(property "Value" "TP_1.5mm_SMD"
			(at 0 -1.7 90)
			(layer "B.Fab")
			(effects
				(font
					(size 0.7 0.7)
					(thickness 0.15)
				)
				(justify left bottom mirror)
			)
		)
		(property "Footprint" "antmicro-footprints:TP_SMD_1.5mm"
			(at 0 0 90)
			(layer "B.Fab")
			(hide yes)
			(effects
				(font
					(size 1.27 1.27)
					(thickness 0.15)
				)
				(justify mirror)
			)
		)
		(property "Description" "test point, SMT"
			(at 0 0 90)
			(layer "B.Fab")
			(hide yes)
			(effects
				(font
					(size 1.27 1.27)
					(thickness 0.15)
				)
				(justify mirror)
			)
		)
		(property "MPN" ""
			(at 0 0 90)
			(unlocked yes)
			(layer "B.Fab")
			(hide yes)
			(effects
				(font
					(size 1 1)
					(thickness 0.15)
				)
				(justify mirror)
			)
		)
		(property "Manufacturer" ""
			(at 0 0 90)
			(unlocked yes)
			(layer "B.Fab")
			(hide yes)
			(effects
				(font
					(size 1 1)
					(thickness 0.15)
				)
				(justify mirror)
			)
		)
		(property "Author" "Antmicro"
			(at 0 0 90)
			(unlocked yes)
			(layer "B.Fab")
			(hide yes)
			(effects
				(font
					(size 1 1)
					(thickness 0.15)
				)
				(justify mirror)
			)
		)
		(property "License" "Apache-2.0"
			(at 0 0 90)
			(unlocked yes)
			(layer "B.Fab")
			(hide yes)
			(effects
				(font
					(size 1 1)
					(thickness 0.15)
				)
				(justify mirror)
			)
		)
		(sheetname "Root")
		(sheetfile "jetson-orin-baseboard-oculink-expansion.kicad_sch")
		(attr exclude_from_pos_files exclude_from_bom)
		(fp_circle
			(center 0 0)
			(end 0.85 0)
			(stroke
				(width 0.05)
				(type default)
			)
			(fill none)
			(layer "B.CrtYd")
		)
		(fp_text user "${REFERENCE}"
			(at -0.7 -2.9 90)
			(layer "B.Fab")
			(hide yes)
			(effects
				(font
					(size 0.7 0.7)
					(thickness 0.15)
				)
				(justify left bottom mirror)
			)
		)
		(fp_text user "License: Apache-2.0"
			(at -0.7 -5.301 90)
			(layer "B.Fab")
			(hide yes)
			(effects
				(font
					(size 0.7 0.7)
					(thickness 0.15)
				)
				(justify left bottom mirror)
			)
		)
		(fp_text user "Author: Antmicro"
			(at -0.7 -4.101 90)
			(layer "B.Fab")
			(hide yes)
			(effects
				(font
					(size 0.7 0.7)
					(thickness 0.15)
				)
				(justify left bottom mirror)
			)
		)
		(pad "1" smd circle
			(at 0 0)
			(size 1.5 1.5)
			(layers "B.Cu" "B.Mask")
			(net 64 "/I2C_SCL")
			(pinfunction "1")
			(pintype "passive")
		)
	)
	(footprint "antmicro-footprints:R_0402_1005Metric"
		(layer "B.Cu")
		(at 129.794 126.66775 180)
		(descr "Resistor SMD 0402")
		(tags "resistor SMD 0402")
		(property "Reference" "R22"
			(at -3.336 -0.43225 0)
			(layer "B.SilkS")
			(effects
				(font
					(size 0.7 0.7)
					(thickness 0.15)
				)
				(justify left bottom mirror)
			)
		)
		(property "Value" "R_1k_0402"
			(at -1.011843 -1.772047 0)
			(layer "B.Fab")
			(effects
				(font
					(size 0.7 0.7)
					(thickness 0.15)
				)
				(justify left bottom mirror)
			)
		)
		(property "Footprint" "antmicro-footprints:R_0402_1005Metric"
			(at 0 0 0)
			(layer "B.Fab")
			(hide yes)
			(effects
				(font
					(size 1.27 1.27)
					(thickness 0.15)
				)
				(justify mirror)
			)
		)
		(property "Datasheet" "https://www.bourns.com/docs/product-datasheets/cr.pdf"
			(at 0 0 0)
			(layer "B.Fab")
			(hide yes)
			(effects
				(font
					(size 1.27 1.27)
					(thickness 0.15)
				)
				(justify mirror)
			)
		)
		(property "Description" "SMD Chip Resistor, 1 kohm, ± 1%, 63 mW, 0402 [1005 Metric], Thick Film, General Purpose"
			(at 0 0 0)
			(layer "B.Fab")
			(hide yes)
			(effects
				(font
					(size 1.27 1.27)
					(thickness 0.15)
				)
				(justify mirror)
			)
		)
		(property "MPN" "CR0402-FX-1001GLF"
			(at 0 0 0)
			(unlocked yes)
			(layer "B.Fab")
			(hide yes)
			(effects
				(font
					(size 1 1)
					(thickness 0.15)
				)
				(justify mirror)
			)
		)
		(property "Manufacturer" "Bourns"
			(at 0 0 0)
			(unlocked yes)
			(layer "B.Fab")
			(hide yes)
			(effects
				(font
					(size 1 1)
					(thickness 0.15)
				)
				(justify mirror)
			)
		)
		(property "License" "Apache-2.0"
			(at 0 0 0)
			(unlocked yes)
			(layer "B.Fab")
			(hide yes)
			(effects
				(font
					(size 1 1)
					(thickness 0.15)
				)
				(justify mirror)
			)
		)
		(property "Author" "Antmicro"
			(at 0 0 0)
			(unlocked yes)
			(layer "B.Fab")
			(hide yes)
			(effects
				(font
					(size 1 1)
					(thickness 0.15)
				)
				(justify mirror)
			)
		)
		(property "Val" "1k"
			(at 0 0 0)
			(unlocked yes)
			(layer "B.Fab")
			(hide yes)
			(effects
				(font
					(size 1 1)
					(thickness 0.15)
				)
				(justify mirror)
			)
		)
		(property "Tolerance" "1%"
			(at 0 0 0)
			(unlocked yes)
			(layer "B.Fab")
			(hide yes)
			(effects
				(font
					(size 1 1)
					(thickness 0.15)
				)
				(justify mirror)
			)
		)
		(property "Public" "False"
			(at 0 0 0)
			(unlocked yes)
			(layer "B.Fab")
			(hide yes)
			(effects
				(font
					(size 1 1)
					(thickness 0.15)
				)
				(justify mirror)
			)
		)
		(sheetname "Root")
		(sheetfile "jetson-orin-baseboard-oculink-expansion.kicad_sch")
		(attr smd dnp)
		(fp_rect
			(start -0.925 0.47)
			(end 0.925 -0.47)
			(stroke
				(width 0.05)
				(type default)
			)
			(fill none)
			(layer "B.CrtYd")
		)
		(fp_rect
			(start -0.5 0.25)
			(end 0.5 -0.25)
			(stroke
				(width 0.15)
				(type solid)
			)
			(fill none)
			(layer "B.Fab")
		)
		(fp_text user "License: Apache-2.0"
			(at -0.95 -5.169 0)
			(layer "B.Fab")
			(hide yes)
			(effects
				(font
					(size 0.7 0.7)
					(thickness 0.15)
				)
				(justify left bottom mirror)
			)
		)
		(fp_text user "Author: Antmicro"
			(at -0.95 -4.169 0)
			(layer "B.Fab")
			(hide yes)
			(effects
				(font
					(size 0.7 0.7)
					(thickness 0.15)
				)
				(justify left bottom mirror)
			)
		)
		(fp_text user "${REFERENCE}"
			(at -0.95 -3.168 0)
			(layer "B.Fab")
			(hide yes)
			(effects
				(font
					(size 0.7 0.7)
					(thickness 0.15)
				)
				(justify left bottom mirror)
			)
		)
		(pad "1" smd roundrect
			(at -0.48 0 180)
			(size 0.59 0.64)
			(layers "B.Cu" "B.Paste" "B.Mask")
			(roundrect_rratio 0.25)
			(net 51 "GND")
			(pintype "passive")
		)
		(pad "2" smd roundrect
			(at 0.48 0 180)
			(size 0.59 0.64)
			(layers "B.Cu" "B.Paste" "B.Mask")
			(roundrect_rratio 0.25)
			(net 98 "/TX_EQ1")
			(pintype "passive")
		)
	)
	(footprint "antmicro-footprints:C_0402_1005Metric"
		(layer "B.Cu")
		(at 124.275 125.795 90)
		(descr "Capacitor SMD 0402")
		(tags "capacitor SMD 0402")
		(property "Reference" "C18"
			(at 1.605 -0.555 90)
			(layer "B.SilkS")
			(effects
				(font
					(size 0.7 0.7)
					(thickness 0.15)
				)
				(justify right top mirror)
			)
		)
		(property "Value" "C_100n_0402"
			(at -1.022927 -2.155213 90)
			(layer "B.Fab")
			(effects
				(font
					(size 0.7 0.7)
					(thickness 0.15)
				)
				(justify right top mirror)
			)
		)
		(property "Footprint" "antmicro-footprints:C_0402_1005Metric"
			(at 0 0 90)
			(layer "B.Fab")
			(hide yes)
			(effects
				(font
					(size 1.27 1.27)
					(thickness 0.15)
				)
				(justify mirror)
			)
		)
		(property "Datasheet" "https://www.murata.com/products/productdetail?partno=GRM155R61H104KE14%23"
			(at 0 0 90)
			(layer "B.Fab")
			(hide yes)
			(effects
				(font
					(size 1.27 1.27)
					(thickness 0.15)
				)
				(justify mirror)
			)
		)
		(property "Description" "SMD Multilayer Ceramic Capacitor, 0.1 µF, 50 V, 0402 [1005 Metric], ± 10%, X5R, GRM Series"
			(at 0 0 90)
			(layer "B.Fab")
			(hide yes)
			(effects
				(font
					(size 1.27 1.27)
					(thickness 0.15)
				)
				(justify mirror)
			)
		)
		(property "MPN" "GRM155R61H104KE14D"
			(at 0 0 -90)
			(unlocked yes)
			(layer "B.Fab")
			(hide yes)
			(effects
				(font
					(size 1 1)
					(thickness 0.15)
				)
				(justify mirror)
			)
		)
		(property "Manufacturer" "Murata"
			(at 0 0 -90)
			(unlocked yes)
			(layer "B.Fab")
			(hide yes)
			(effects
				(font
					(size 1 1)
					(thickness 0.15)
				)
				(justify mirror)
			)
		)
		(property "License" "Apache-2.0"
			(at 0 0 -90)
			(unlocked yes)
			(layer "B.Fab")
			(hide yes)
			(effects
				(font
					(size 1 1)
					(thickness 0.15)
				)
				(justify mirror)
			)
		)
		(property "Author" "Antmicro"
			(at 0 0 -90)
			(unlocked yes)
			(layer "B.Fab")
			(hide yes)
			(effects
				(font
					(size 1 1)
					(thickness 0.15)
				)
				(justify mirror)
			)
		)
		(property "Val" "100n"
			(at 0 0 -90)
			(unlocked yes)
			(layer "B.Fab")
			(hide yes)
			(effects
				(font
					(size 1 1)
					(thickness 0.15)
				)
				(justify mirror)
			)
		)
		(property "Voltage" "50V"
			(at 0 0 -90)
			(unlocked yes)
			(layer "B.Fab")
			(hide yes)
			(effects
				(font
					(size 1 1)
					(thickness 0.15)
				)
				(justify mirror)
			)
		)
		(property "Dielectric" "X5R"
			(at 0 0 -90)
			(unlocked yes)
			(layer "B.Fab")
			(hide yes)
			(effects
				(font
					(size 1 1)
					(thickness 0.15)
				)
				(justify mirror)
			)
		)
		(property "Public" "False"
			(at 0 0 -90)
			(unlocked yes)
			(layer "B.Fab")
			(hide yes)
			(effects
				(font
					(size 1 1)
					(thickness 0.15)
				)
				(justify mirror)
			)
		)
		(sheetname "Root")
		(sheetfile "jetson-orin-baseboard-oculink-expansion.kicad_sch")
		(attr smd)
		(fp_rect
			(start -0.925 0.47)
			(end 0.925 -0.47)
			(stroke
				(width 0.05)
				(type default)
			)
			(fill none)
			(layer "B.CrtYd")
		)
		(fp_line
			(start 0.504 -0.248)
			(end 0.504 0.25)
			(stroke
				(width 0.15)
				(type solid)
			)
			(layer "B.Fab")
		)
		(fp_line
			(start -0.494 -0.248)
			(end 0.504 -0.248)
			(stroke
				(width 0.15)
				(type solid)
			)
			(layer "B.Fab")
		)
		(fp_line
			(start 0.504 0.25)
			(end -0.494 0.25)
			(stroke
				(width 0.15)
				(type solid)
			)
			(layer "B.Fab")
		)
		(fp_line
			(start -0.494 0.25)
			(end -0.494 -0.248)
			(stroke
				(width 0.15)
				(type solid)
			)
			(layer "B.Fab")
		)
		(fp_text user "${REFERENCE}"
			(at -0.939 -4.599 90)
			(layer "B.Fab")
			(hide yes)
			(effects
				(font
					(size 0.7 0.7)
					(thickness 0.15)
				)
				(justify right top mirror)
			)
		)
		(fp_text user "License: Apache-2.0"
			(at -0.939 -5.799 90)
			(layer "B.Fab")
			(hide yes)
			(effects
				(font
					(size 0.7 0.7)
					(thickness 0.15)
				)
				(justify right top mirror)
			)
		)
		(fp_text user "Author: Antmicro"
			(at -0.939 -3.399 90)
			(layer "B.Fab")
			(hide yes)
			(effects
				(font
					(size 0.7 0.7)
					(thickness 0.15)
				)
				(justify right top mirror)
			)
		)
		(pad "1" smd roundrect
			(at -0.48 0 90)
			(size 0.59 0.64)
			(layers "B.Cu" "B.Paste" "B.Mask")
			(roundrect_rratio 0.25)
			(net 51 "GND")
			(pintype "passive")
		)
		(pad "2" smd roundrect
			(at 0.48 0 90)
			(size 0.59 0.64)
			(layers "B.Cu" "B.Paste" "B.Mask")
			(roundrect_rratio 0.25)
			(net 23 "+3V3")
			(pintype "passive")
		)
	)
	(footprint "antmicro-footprints:R_0402_1005Metric"
		(layer "B.Cu")
		(at 116.55 128.28 180)
		(descr "Resistor SMD 0402")
		(tags "resistor SMD 0402")
		(property "Reference" "R34"
			(at 0.79 -0.19 0)
			(layer "B.SilkS")
			(effects
				(font
					(size 0.7 0.7)
					(thickness 0.15)
				)
				(justify left bottom mirror)
			)
		)
		(property "Value" "R_10k_0402"
			(at -1.011843 -1.772047 0)
			(layer "B.Fab")
			(effects
				(font
					(size 0.7 0.7)
					(thickness 0.15)
				)
				(justify left bottom mirror)
			)
		)
		(property "Footprint" "antmicro-footprints:R_0402_1005Metric"
			(at 0 0 0)
			(layer "B.Fab")
			(hide yes)
			(effects
				(font
					(size 1.27 1.27)
					(thickness 0.15)
				)
				(justify mirror)
			)
		)
		(property "Datasheet" "https://www.bourns.com/docs/product-datasheets/cr.pdf"
			(at 0 0 0)
			(layer "B.Fab")
			(hide yes)
			(effects
				(font
					(size 1.27 1.27)
					(thickness 0.15)
				)
				(justify mirror)
			)
		)
		(property "Description" "SMD Chip Resistor, 10 kohm, ± 1%, 62.5 mW, 0402 [1005 Metric], Thick Film, General Purpose"
			(at 0 0 0)
			(layer "B.Fab")
			(hide yes)
			(effects
				(font
					(size 1.27 1.27)
					(thickness 0.15)
				)
				(justify mirror)
			)
		)
		(property "MPN" "CR0402-FX-1002GLF"
			(at 0 0 0)
			(unlocked yes)
			(layer "B.Fab")
			(hide yes)
			(effects
				(font
					(size 1 1)
					(thickness 0.15)
				)
				(justify mirror)
			)
		)
		(property "Manufacturer" "Bourns"
			(at 0 0 0)
			(unlocked yes)
			(layer "B.Fab")
			(hide yes)
			(effects
				(font
					(size 1 1)
					(thickness 0.15)
				)
				(justify mirror)
			)
		)
		(property "License" "Apache-2.0"
			(at 0 0 0)
			(unlocked yes)
			(layer "B.Fab")
			(hide yes)
			(effects
				(font
					(size 1 1)
					(thickness 0.15)
				)
				(justify mirror)
			)
		)
		(property "Author" "Antmicro"
			(at 0 0 0)
			(unlocked yes)
			(layer "B.Fab")
			(hide yes)
			(effects
				(font
					(size 1 1)
					(thickness 0.15)
				)
				(justify mirror)
			)
		)
		(property "Val" "10k"
			(at 0 0 0)
			(unlocked yes)
			(layer "B.Fab")
			(hide yes)
			(effects
				(font
					(size 1 1)
					(thickness 0.15)
				)
				(justify mirror)
			)
		)
		(property "Tolerance" "1%"
			(at 0 0 0)
			(unlocked yes)
			(layer "B.Fab")
			(hide yes)
			(effects
				(font
					(size 1 1)
					(thickness 0.15)
				)
				(justify mirror)
			)
		)
		(sheetname "Root")
		(sheetfile "jetson-orin-baseboard-oculink-expansion.kicad_sch")
		(attr smd)
		(fp_rect
			(start -0.925 0.47)
			(end 0.925 -0.47)
			(stroke
				(width 0.05)
				(type default)
			)
			(fill none)
			(layer "B.CrtYd")
		)
		(fp_rect
			(start -0.5 0.25)
			(end 0.5 -0.25)
			(stroke
				(width 0.15)
				(type solid)
			)
			(fill none)
			(layer "B.Fab")
		)
		(fp_text user "${REFERENCE}"
			(at -0.95 -3.168 0)
			(layer "B.Fab")
			(hide yes)
			(effects
				(font
					(size 0.7 0.7)
					(thickness 0.15)
				)
				(justify left bottom mirror)
			)
		)
		(fp_text user "License: Apache-2.0"
			(at -0.95 -5.169 0)
			(layer "B.Fab")
			(hide yes)
			(effects
				(font
					(size 0.7 0.7)
					(thickness 0.15)
				)
				(justify left bottom mirror)
			)
		)
		(fp_text user "Author: Antmicro"
			(at -0.95 -4.169 0)
			(layer "B.Fab")
			(hide yes)
			(effects
				(font
					(size 0.7 0.7)
					(thickness 0.15)
				)
				(justify left bottom mirror)
			)
		)
		(pad "1" smd roundrect
			(at -0.48 0 180)
			(size 0.59 0.64)
			(layers "B.Cu" "B.Paste" "B.Mask")
			(roundrect_rratio 0.25)
			(net 51 "GND")
			(pintype "passive")
		)
		(pad "2" smd roundrect
			(at 0.48 0 180)
			(size 0.59 0.64)
			(layers "B.Cu" "B.Paste" "B.Mask")
			(roundrect_rratio 0.25)
			(net 105 "Net-(U3-EN_{I2C})")
			(pintype "passive")
		)
	)
	(footprint "antmicro-footprints:C_0402_1005Metric"
		(layer "B.Cu")
		(at 118.275 127.913 -90)
		(descr "Capacitor SMD 0402")
		(tags "capacitor SMD 0402")
		(property "Reference" "C29"
			(at 1.627 -0.445 90)
			(layer "B.SilkS")
			(effects
				(font
					(size 0.7 0.7)
					(thickness 0.15)
				)
				(justify left bottom mirror)
			)
		)
		(property "Value" "C_100n_0402"
			(at -1.022927 -2.155213 90)
			(layer "B.Fab")
			(effects
				(font
					(size 0.7 0.7)
					(thickness 0.15)
				)
				(justify left bottom mirror)
			)
		)
		(property "Footprint" "antmicro-footprints:C_0402_1005Metric"
			(at 0 0 90)
			(layer "B.Fab")
			(hide yes)
			(effects
				(font
					(size 1.27 1.27)
					(thickness 0.15)
				)
				(justify mirror)
			)
		)
		(property "Datasheet" "https://www.murata.com/products/productdetail?partno=GRM155R61H104KE14%23"
			(at 0 0 90)
			(layer "B.Fab")
			(hide yes)
			(effects
				(font
					(size 1.27 1.27)
					(thickness 0.15)
				)
				(justify mirror)
			)
		)
		(property "Description" "SMD Multilayer Ceramic Capacitor, 0.1 µF, 50 V, 0402 [1005 Metric], ± 10%, X5R, GRM Series"
			(at 0 0 90)
			(layer "B.Fab")
			(hide yes)
			(effects
				(font
					(size 1.27 1.27)
					(thickness 0.15)
				)
				(justify mirror)
			)
		)
		(property "MPN" "GRM155R61H104KE14D"
			(at 0 0 90)
			(unlocked yes)
			(layer "B.Fab")
			(hide yes)
			(effects
				(font
					(size 1 1)
					(thickness 0.15)
				)
				(justify mirror)
			)
		)
		(property "Manufacturer" "Murata"
			(at 0 0 90)
			(unlocked yes)
			(layer "B.Fab")
			(hide yes)
			(effects
				(font
					(size 1 1)
					(thickness 0.15)
				)
				(justify mirror)
			)
		)
		(property "License" "Apache-2.0"
			(at 0 0 90)
			(unlocked yes)
			(layer "B.Fab")
			(hide yes)
			(effects
				(font
					(size 1 1)
					(thickness 0.15)
				)
				(justify mirror)
			)
		)
		(property "Author" "Antmicro"
			(at 0 0 90)
			(unlocked yes)
			(layer "B.Fab")
			(hide yes)
			(effects
				(font
					(size 1 1)
					(thickness 0.15)
				)
				(justify mirror)
			)
		)
		(property "Val" "100n"
			(at 0 0 90)
			(unlocked yes)
			(layer "B.Fab")
			(hide yes)
			(effects
				(font
					(size 1 1)
					(thickness 0.15)
				)
				(justify mirror)
			)
		)
		(property "Voltage" "50V"
			(at 0 0 90)
			(unlocked yes)
			(layer "B.Fab")
			(hide yes)
			(effects
				(font
					(size 1 1)
					(thickness 0.15)
				)
				(justify mirror)
			)
		)
		(property "Dielectric" "X5R"
			(at 0 0 90)
			(unlocked yes)
			(layer "B.Fab")
			(hide yes)
			(effects
				(font
					(size 1 1)
					(thickness 0.15)
				)
				(justify mirror)
			)
		)
		(property "Public" "False"
			(at 0 0 90)
			(unlocked yes)
			(layer "B.Fab")
			(hide yes)
			(effects
				(font
					(size 1 1)
					(thickness 0.15)
				)
				(justify mirror)
			)
		)
		(sheetname "Root")
		(sheetfile "jetson-orin-baseboard-oculink-expansion.kicad_sch")
		(attr smd)
		(fp_rect
			(start -0.925 0.47)
			(end 0.925 -0.47)
			(stroke
				(width 0.05)
				(type default)
			)
			(fill none)
			(layer "B.CrtYd")
		)
		(fp_line
			(start -0.494 0.25)
			(end -0.494 -0.248)
			(stroke
				(width 0.15)
				(type solid)
			)
			(layer "B.Fab")
		)
		(fp_line
			(start 0.504 0.25)
			(end -0.494 0.25)
			(stroke
				(width 0.15)
				(type solid)
			)
			(layer "B.Fab")
		)
		(fp_line
			(start -0.494 -0.248)
			(end 0.504 -0.248)
			(stroke
				(width 0.15)
				(type solid)
			)
			(layer "B.Fab")
		)
		(fp_line
			(start 0.504 -0.248)
			(end 0.504 0.25)
			(stroke
				(width 0.15)
				(type solid)
			)
			(layer "B.Fab")
		)
		(fp_text user "Author: Antmicro"
			(at -0.939 -3.399 90)
			(layer "B.Fab")
			(hide yes)
			(effects
				(font
					(size 0.7 0.7)
					(thickness 0.15)
				)
				(justify left bottom mirror)
			)
		)
		(fp_text user "License: Apache-2.0"
			(at -0.939 -5.799 90)
			(layer "B.Fab")
			(hide yes)
			(effects
				(font
					(size 0.7 0.7)
					(thickness 0.15)
				)
				(justify left bottom mirror)
			)
		)
		(fp_text user "${REFERENCE}"
			(at -0.939 -4.599 90)
			(layer "B.Fab")
			(hide yes)
			(effects
				(font
					(size 0.7 0.7)
					(thickness 0.15)
				)
				(justify left bottom mirror)
			)
		)
		(pad "1" smd roundrect
			(at -0.48 0 270)
			(size 0.59 0.64)
			(layers "B.Cu" "B.Paste" "B.Mask")
			(roundrect_rratio 0.25)
			(net 51 "GND")
			(pintype "passive")
		)
		(pad "2" smd roundrect
			(at 0.48 0 270)
			(size 0.59 0.64)
			(layers "B.Cu" "B.Paste" "B.Mask")
			(roundrect_rratio 0.25)
			(net 23 "+3V3")
			(pintype "passive")
		)
	)
	(footprint "antmicro-footprints:C_0402_1005Metric"
		(layer "B.Cu")
		(at 125.005 114.569251 90)
		(descr "Capacitor SMD 0402")
		(tags "capacitor SMD 0402")
		(property "Reference" "C11"
			(at 1.779251 -0.385 90)
			(layer "B.SilkS")
			(effects
				(font
					(size 0.7 0.7)
					(thickness 0.15)
				)
				(justify right top mirror)
			)
		)
		(property "Value" "C_100n_0402"
			(at -1.022927 -2.155213 90)
			(layer "B.Fab")
			(effects
				(font
					(size 0.7 0.7)
					(thickness 0.15)
				)
				(justify right top mirror)
			)
		)
		(property "Footprint" "antmicro-footprints:C_0402_1005Metric"
			(at 0 0 90)
			(layer "B.Fab")
			(hide yes)
			(effects
				(font
					(size 1.27 1.27)
					(thickness 0.15)
				)
				(justify mirror)
			)
		)
		(property "Datasheet" "https://www.murata.com/products/productdetail?partno=GRM155R61H104KE14%23"
			(at 0 0 90)
			(layer "B.Fab")
			(hide yes)
			(effects
				(font
					(size 1.27 1.27)
					(thickness 0.15)
				)
				(justify mirror)
			)
		)
		(property "Description" "SMD Multilayer Ceramic Capacitor, 0.1 µF, 50 V, 0402 [1005 Metric], ± 10%, X5R, GRM Series"
			(at 0 0 90)
			(layer "B.Fab")
			(hide yes)
			(effects
				(font
					(size 1.27 1.27)
					(thickness 0.15)
				)
				(justify mirror)
			)
		)
		(property "MPN" "GRM155R61H104KE14D"
			(at 0 0 -90)
			(unlocked yes)
			(layer "B.Fab")
			(hide yes)
			(effects
				(font
					(size 1 1)
					(thickness 0.15)
				)
				(justify mirror)
			)
		)
		(property "Manufacturer" "Murata"
			(at 0 0 -90)
			(unlocked yes)
			(layer "B.Fab")
			(hide yes)
			(effects
				(font
					(size 1 1)
					(thickness 0.15)
				)
				(justify mirror)
			)
		)
		(property "License" "Apache-2.0"
			(at 0 0 -90)
			(unlocked yes)
			(layer "B.Fab")
			(hide yes)
			(effects
				(font
					(size 1 1)
					(thickness 0.15)
				)
				(justify mirror)
			)
		)
		(property "Author" "Antmicro"
			(at 0 0 -90)
			(unlocked yes)
			(layer "B.Fab")
			(hide yes)
			(effects
				(font
					(size 1 1)
					(thickness 0.15)
				)
				(justify mirror)
			)
		)
		(property "Val" "100n"
			(at 0 0 -90)
			(unlocked yes)
			(layer "B.Fab")
			(hide yes)
			(effects
				(font
					(size 1 1)
					(thickness 0.15)
				)
				(justify mirror)
			)
		)
		(property "Voltage" "50V"
			(at 0 0 -90)
			(unlocked yes)
			(layer "B.Fab")
			(hide yes)
			(effects
				(font
					(size 1 1)
					(thickness 0.15)
				)
				(justify mirror)
			)
		)
		(property "Dielectric" "X5R"
			(at 0 0 -90)
			(unlocked yes)
			(layer "B.Fab")
			(hide yes)
			(effects
				(font
					(size 1 1)
					(thickness 0.15)
				)
				(justify mirror)
			)
		)
		(property "Public" "False"
			(at 0 0 -90)
			(unlocked yes)
			(layer "B.Fab")
			(hide yes)
			(effects
				(font
					(size 1 1)
					(thickness 0.15)
				)
				(justify mirror)
			)
		)
		(sheetname "Root")
		(sheetfile "jetson-orin-baseboard-oculink-expansion.kicad_sch")
		(attr smd)
		(fp_rect
			(start -0.925 0.47)
			(end 0.925 -0.47)
			(stroke
				(width 0.05)
				(type default)
			)
			(fill none)
			(layer "B.CrtYd")
		)
		(fp_line
			(start 0.504 -0.248)
			(end 0.504 0.25)
			(stroke
				(width 0.15)
				(type solid)
			)
			(layer "B.Fab")
		)
		(fp_line
			(start -0.494 -0.248)
			(end 0.504 -0.248)
			(stroke
				(width 0.15)
				(type solid)
			)
			(layer "B.Fab")
		)
		(fp_line
			(start 0.504 0.25)
			(end -0.494 0.25)
			(stroke
				(width 0.15)
				(type solid)
			)
			(layer "B.Fab")
		)
		(fp_line
			(start -0.494 0.25)
			(end -0.494 -0.248)
			(stroke
				(width 0.15)
				(type solid)
			)
			(layer "B.Fab")
		)
		(fp_text user "License: Apache-2.0"
			(at -0.939 -5.799 90)
			(layer "B.Fab")
			(hide yes)
			(effects
				(font
					(size 0.7 0.7)
					(thickness 0.15)
				)
				(justify right top mirror)
			)
		)
		(fp_text user "${REFERENCE}"
			(at -0.939 -4.599 90)
			(layer "B.Fab")
			(hide yes)
			(effects
				(font
					(size 0.7 0.7)
					(thickness 0.15)
				)
				(justify right top mirror)
			)
		)
		(fp_text user "Author: Antmicro"
			(at -0.939 -3.399 90)
			(layer "B.Fab")
			(hide yes)
			(effects
				(font
					(size 0.7 0.7)
					(thickness 0.15)
				)
				(justify right top mirror)
			)
		)
		(pad "1" smd roundrect
			(at -0.48 0 90)
			(size 0.59 0.64)
			(layers "B.Cu" "B.Paste" "B.Mask")
			(roundrect_rratio 0.25)
			(net 51 "GND")
			(pintype "passive")
		)
		(pad "2" smd roundrect
			(at 0.48 0 90)
			(size 0.59 0.64)
			(layers "B.Cu" "B.Paste" "B.Mask")
			(roundrect_rratio 0.25)
			(net 23 "+3V3")
			(pintype "passive")
		)
	)
	(footprint "antmicro-footprints:C_0402_1005Metric"
		(layer "B.Cu")
		(at 118.275 125.795 90)
		(descr "Capacitor SMD 0402")
		(tags "capacitor SMD 0402")
		(property "Reference" "C30"
			(at 1.605 -0.375 90)
			(layer "B.SilkS")
			(effects
				(font
					(size 0.7 0.7)
					(thickness 0.15)
				)
				(justify right top mirror)
			)
		)
		(property "Value" "C_100n_0402"
			(at -1.022927 -2.155213 90)
			(layer "B.Fab")
			(effects
				(font
					(size 0.7 0.7)
					(thickness 0.15)
				)
				(justify right top mirror)
			)
		)
		(property "Footprint" "antmicro-footprints:C_0402_1005Metric"
			(at 0 0 90)
			(layer "B.Fab")
			(hide yes)
			(effects
				(font
					(size 1.27 1.27)
					(thickness 0.15)
				)
				(justify mirror)
			)
		)
		(property "Datasheet" "https://www.murata.com/products/productdetail?partno=GRM155R61H104KE14%23"
			(at 0 0 90)
			(layer "B.Fab")
			(hide yes)
			(effects
				(font
					(size 1.27 1.27)
					(thickness 0.15)
				)
				(justify mirror)
			)
		)
		(property "Description" "SMD Multilayer Ceramic Capacitor, 0.1 µF, 50 V, 0402 [1005 Metric], ± 10%, X5R, GRM Series"
			(at 0 0 90)
			(layer "B.Fab")
			(hide yes)
			(effects
				(font
					(size 1.27 1.27)
					(thickness 0.15)
				)
				(justify mirror)
			)
		)
		(property "MPN" "GRM155R61H104KE14D"
			(at 0 0 -90)
			(unlocked yes)
			(layer "B.Fab")
			(hide yes)
			(effects
				(font
					(size 1 1)
					(thickness 0.15)
				)
				(justify mirror)
			)
		)
		(property "Manufacturer" "Murata"
			(at 0 0 -90)
			(unlocked yes)
			(layer "B.Fab")
			(hide yes)
			(effects
				(font
					(size 1 1)
					(thickness 0.15)
				)
				(justify mirror)
			)
		)
		(property "License" "Apache-2.0"
			(at 0 0 -90)
			(unlocked yes)
			(layer "B.Fab")
			(hide yes)
			(effects
				(font
					(size 1 1)
					(thickness 0.15)
				)
				(justify mirror)
			)
		)
		(property "Author" "Antmicro"
			(at 0 0 -90)
			(unlocked yes)
			(layer "B.Fab")
			(hide yes)
			(effects
				(font
					(size 1 1)
					(thickness 0.15)
				)
				(justify mirror)
			)
		)
		(property "Val" "100n"
			(at 0 0 -90)
			(unlocked yes)
			(layer "B.Fab")
			(hide yes)
			(effects
				(font
					(size 1 1)
					(thickness 0.15)
				)
				(justify mirror)
			)
		)
		(property "Voltage" "50V"
			(at 0 0 -90)
			(unlocked yes)
			(layer "B.Fab")
			(hide yes)
			(effects
				(font
					(size 1 1)
					(thickness 0.15)
				)
				(justify mirror)
			)
		)
		(property "Dielectric" "X5R"
			(at 0 0 -90)
			(unlocked yes)
			(layer "B.Fab")
			(hide yes)
			(effects
				(font
					(size 1 1)
					(thickness 0.15)
				)
				(justify mirror)
			)
		)
		(property "Public" "False"
			(at 0 0 -90)
			(unlocked yes)
			(layer "B.Fab")
			(hide yes)
			(effects
				(font
					(size 1 1)
					(thickness 0.15)
				)
				(justify mirror)
			)
		)
		(sheetname "Root")
		(sheetfile "jetson-orin-baseboard-oculink-expansion.kicad_sch")
		(attr smd)
		(fp_rect
			(start -0.925 0.47)
			(end 0.925 -0.47)
			(stroke
				(width 0.05)
				(type default)
			)
			(fill none)
			(layer "B.CrtYd")
		)
		(fp_line
			(start 0.504 -0.248)
			(end 0.504 0.25)
			(stroke
				(width 0.15)
				(type solid)
			)
			(layer "B.Fab")
		)
		(fp_line
			(start -0.494 -0.248)
			(end 0.504 -0.248)
			(stroke
				(width 0.15)
				(type solid)
			)
			(layer "B.Fab")
		)
		(fp_line
			(start 0.504 0.25)
			(end -0.494 0.25)
			(stroke
				(width 0.15)
				(type solid)
			)
			(layer "B.Fab")
		)
		(fp_line
			(start -0.494 0.25)
			(end -0.494 -0.248)
			(stroke
				(width 0.15)
				(type solid)
			)
			(layer "B.Fab")
		)
		(fp_text user "${REFERENCE}"
			(at -0.939 -4.599 90)
			(layer "B.Fab")
			(hide yes)
			(effects
				(font
					(size 0.7 0.7)
					(thickness 0.15)
				)
				(justify right top mirror)
			)
		)
		(fp_text user "Author: Antmicro"
			(at -0.939 -3.399 90)
			(layer "B.Fab")
			(hide yes)
			(effects
				(font
					(size 0.7 0.7)
					(thickness 0.15)
				)
				(justify right top mirror)
			)
		)
		(fp_text user "License: Apache-2.0"
			(at -0.939 -5.799 90)
			(layer "B.Fab")
			(hide yes)
			(effects
				(font
					(size 0.7 0.7)
					(thickness 0.15)
				)
				(justify right top mirror)
			)
		)
		(pad "1" smd roundrect
			(at -0.48 0 90)
			(size 0.59 0.64)
			(layers "B.Cu" "B.Paste" "B.Mask")
			(roundrect_rratio 0.25)
			(net 51 "GND")
			(pintype "passive")
		)
		(pad "2" smd roundrect
			(at 0.48 0 90)
			(size 0.59 0.64)
			(layers "B.Cu" "B.Paste" "B.Mask")
			(roundrect_rratio 0.25)
			(net 23 "+3V3")
			(pintype "passive")
		)
	)
	(footprint "antmicro-footprints:R_0402_1005Metric"
		(layer "B.Cu")
		(at 129.794 125.32775 180)
		(descr "Resistor SMD 0402")
		(tags "resistor SMD 0402")
		(property "Reference" "R24"
			(at -3.336 -0.46225 0)
			(layer "B.SilkS")
			(effects
				(font
					(size 0.7 0.7)
					(thickness 0.15)
				)
				(justify left bottom mirror)
			)
		)
		(property "Value" "R_1k_0402"
			(at -1.011843 -1.772047 0)
			(layer "B.Fab")
			(effects
				(font
					(size 0.7 0.7)
					(thickness 0.15)
				)
				(justify left bottom mirror)
			)
		)
		(property "Footprint" "antmicro-footprints:R_0402_1005Metric"
			(at 0 0 0)
			(layer "B.Fab")
			(hide yes)
			(effects
				(font
					(size 1.27 1.27)
					(thickness 0.15)
				)
				(justify mirror)
			)
		)
		(property "Datasheet" "https://www.bourns.com/docs/product-datasheets/cr.pdf"
			(at 0 0 0)
			(layer "B.Fab")
			(hide yes)
			(effects
				(font
					(size 1.27 1.27)
					(thickness 0.15)
				)
				(justify mirror)
			)
		)
		(property "Description" "SMD Chip Resistor, 1 kohm, ± 1%, 63 mW, 0402 [1005 Metric], Thick Film, General Purpose"
			(at 0 0 0)
			(layer "B.Fab")
			(hide yes)
			(effects
				(font
					(size 1.27 1.27)
					(thickness 0.15)
				)
				(justify mirror)
			)
		)
		(property "MPN" "CR0402-FX-1001GLF"
			(at 0 0 0)
			(unlocked yes)
			(layer "B.Fab")
			(hide yes)
			(effects
				(font
					(size 1 1)
					(thickness 0.15)
				)
				(justify mirror)
			)
		)
		(property "Manufacturer" "Bourns"
			(at 0 0 0)
			(unlocked yes)
			(layer "B.Fab")
			(hide yes)
			(effects
				(font
					(size 1 1)
					(thickness 0.15)
				)
				(justify mirror)
			)
		)
		(property "License" "Apache-2.0"
			(at 0 0 0)
			(unlocked yes)
			(layer "B.Fab")
			(hide yes)
			(effects
				(font
					(size 1 1)
					(thickness 0.15)
				)
				(justify mirror)
			)
		)
		(property "Author" "Antmicro"
			(at 0 0 0)
			(unlocked yes)
			(layer "B.Fab")
			(hide yes)
			(effects
				(font
					(size 1 1)
					(thickness 0.15)
				)
				(justify mirror)
			)
		)
		(property "Val" "1k"
			(at 0 0 0)
			(unlocked yes)
			(layer "B.Fab")
			(hide yes)
			(effects
				(font
					(size 1 1)
					(thickness 0.15)
				)
				(justify mirror)
			)
		)
		(property "Tolerance" "1%"
			(at 0 0 0)
			(unlocked yes)
			(layer "B.Fab")
			(hide yes)
			(effects
				(font
					(size 1 1)
					(thickness 0.15)
				)
				(justify mirror)
			)
		)
		(property "Public" "False"
			(at 0 0 0)
			(unlocked yes)
			(layer "B.Fab")
			(hide yes)
			(effects
				(font
					(size 1 1)
					(thickness 0.15)
				)
				(justify mirror)
			)
		)
		(sheetname "Root")
		(sheetfile "jetson-orin-baseboard-oculink-expansion.kicad_sch")
		(attr smd)
		(fp_rect
			(start -0.925 0.47)
			(end 0.925 -0.47)
			(stroke
				(width 0.05)
				(type default)
			)
			(fill none)
			(layer "B.CrtYd")
		)
		(fp_rect
			(start -0.5 0.25)
			(end 0.5 -0.25)
			(stroke
				(width 0.15)
				(type solid)
			)
			(fill none)
			(layer "B.Fab")
		)
		(fp_text user "License: Apache-2.0"
			(at -0.95 -5.169 0)
			(layer "B.Fab")
			(hide yes)
			(effects
				(font
					(size 0.7 0.7)
					(thickness 0.15)
				)
				(justify left bottom mirror)
			)
		)
		(fp_text user "${REFERENCE}"
			(at -0.95 -3.168 0)
			(layer "B.Fab")
			(hide yes)
			(effects
				(font
					(size 0.7 0.7)
					(thickness 0.15)
				)
				(justify left bottom mirror)
			)
		)
		(fp_text user "Author: Antmicro"
			(at -0.95 -4.169 0)
			(layer "B.Fab")
			(hide yes)
			(effects
				(font
					(size 0.7 0.7)
					(thickness 0.15)
				)
				(justify left bottom mirror)
			)
		)
		(pad "1" smd roundrect
			(at -0.48 0 180)
			(size 0.59 0.64)
			(layers "B.Cu" "B.Paste" "B.Mask")
			(roundrect_rratio 0.25)
			(net 51 "GND")
			(pintype "passive")
		)
		(pad "2" smd roundrect
			(at 0.48 0 180)
			(size 0.59 0.64)
			(layers "B.Cu" "B.Paste" "B.Mask")
			(roundrect_rratio 0.25)
			(net 99 "/TX_EQ2")
			(pintype "passive")
		)
	)
	(footprint "antmicro-footprints:R_0402_1005Metric"
		(layer "B.Cu")
		(at 118.324 116.653751 180)
		(descr "Resistor SMD 0402")
		(tags "resistor SMD 0402")
		(property "Reference" "R8"
			(at -2.589333 -0.47725 0)
			(layer "B.SilkS")
			(effects
				(font
					(size 0.7 0.7)
					(thickness 0.15)
				)
				(justify left bottom mirror)
			)
		)
		(property "Value" "R_1k_0402"
			(at -1.011843 -1.772047 0)
			(layer "B.Fab")
			(effects
				(font
					(size 0.7 0.7)
					(thickness 0.15)
				)
				(justify left bottom mirror)
			)
		)
		(property "Footprint" "antmicro-footprints:R_0402_1005Metric"
			(at 0 0 0)
			(layer "B.Fab")
			(hide yes)
			(effects
				(font
					(size 1.27 1.27)
					(thickness 0.15)
				)
				(justify mirror)
			)
		)
		(property "Datasheet" "https://www.bourns.com/docs/product-datasheets/cr.pdf"
			(at 0 0 0)
			(layer "B.Fab")
			(hide yes)
			(effects
				(font
					(size 1.27 1.27)
					(thickness 0.15)
				)
				(justify mirror)
			)
		)
		(property "Description" "SMD Chip Resistor, 1 kohm, ± 1%, 63 mW, 0402 [1005 Metric], Thick Film, General Purpose"
			(at 0 0 0)
			(layer "B.Fab")
			(hide yes)
			(effects
				(font
					(size 1.27 1.27)
					(thickness 0.15)
				)
				(justify mirror)
			)
		)
		(property "MPN" "CR0402-FX-1001GLF"
			(at 0 0 0)
			(unlocked yes)
			(layer "B.Fab")
			(hide yes)
			(effects
				(font
					(size 1 1)
					(thickness 0.15)
				)
				(justify mirror)
			)
		)
		(property "Manufacturer" "Bourns"
			(at 0 0 0)
			(unlocked yes)
			(layer "B.Fab")
			(hide yes)
			(effects
				(font
					(size 1 1)
					(thickness 0.15)
				)
				(justify mirror)
			)
		)
		(property "License" "Apache-2.0"
			(at 0 0 0)
			(unlocked yes)
			(layer "B.Fab")
			(hide yes)
			(effects
				(font
					(size 1 1)
					(thickness 0.15)
				)
				(justify mirror)
			)
		)
		(property "Author" "Antmicro"
			(at 0 0 0)
			(unlocked yes)
			(layer "B.Fab")
			(hide yes)
			(effects
				(font
					(size 1 1)
					(thickness 0.15)
				)
				(justify mirror)
			)
		)
		(property "Val" "1k"
			(at 0 0 0)
			(unlocked yes)
			(layer "B.Fab")
			(hide yes)
			(effects
				(font
					(size 1 1)
					(thickness 0.15)
				)
				(justify mirror)
			)
		)
		(property "Tolerance" "1%"
			(at 0 0 0)
			(unlocked yes)
			(layer "B.Fab")
			(hide yes)
			(effects
				(font
					(size 1 1)
					(thickness 0.15)
				)
				(justify mirror)
			)
		)
		(property "Public" "False"
			(at 0 0 0)
			(unlocked yes)
			(layer "B.Fab")
			(hide yes)
			(effects
				(font
					(size 1 1)
					(thickness 0.15)
				)
				(justify mirror)
			)
		)
		(sheetname "Root")
		(sheetfile "jetson-orin-baseboard-oculink-expansion.kicad_sch")
		(attr smd)
		(fp_rect
			(start -0.925 0.47)
			(end 0.925 -0.47)
			(stroke
				(width 0.05)
				(type default)
			)
			(fill none)
			(layer "B.CrtYd")
		)
		(fp_rect
			(start -0.5 0.25)
			(end 0.5 -0.25)
			(stroke
				(width 0.15)
				(type solid)
			)
			(fill none)
			(layer "B.Fab")
		)
		(fp_text user "License: Apache-2.0"
			(at -0.95 -5.169 0)
			(layer "B.Fab")
			(hide yes)
			(effects
				(font
					(size 0.7 0.7)
					(thickness 0.15)
				)
				(justify left bottom mirror)
			)
		)
		(fp_text user "Author: Antmicro"
			(at -0.95 -4.169 0)
			(layer "B.Fab")
			(hide yes)
			(effects
				(font
					(size 0.7 0.7)
					(thickness 0.15)
				)
				(justify left bottom mirror)
			)
		)
		(fp_text user "${REFERENCE}"
			(at -0.95 -3.168 0)
			(layer "B.Fab")
			(hide yes)
			(effects
				(font
					(size 0.7 0.7)
					(thickness 0.15)
				)
				(justify left bottom mirror)
			)
		)
		(pad "1" smd roundrect
			(at -0.48 0 180)
			(size 0.59 0.64)
			(layers "B.Cu" "B.Paste" "B.Mask")
			(roundrect_rratio 0.25)
			(net 23 "+3V3")
			(pintype "passive")
		)
		(pad "2" smd roundrect
			(at 0.48 0 180)
			(size 0.59 0.64)
			(layers "B.Cu" "B.Paste" "B.Mask")
			(roundrect_rratio 0.25)
			(net 91 "/RX_EQ2")
			(pintype "passive")
		)
	)
	(footprint "antmicro-footprints:C_0402_1005Metric"
		(layer "B.Cu")
		(at 123.505 116.687251 -90)
		(descr "Capacitor SMD 0402")
		(tags "capacitor SMD 0402")
		(property "Reference" "C24"
			(at 1.782749 -0.445 90)
			(layer "B.SilkS")
			(effects
				(font
					(size 0.7 0.7)
					(thickness 0.15)
				)
				(justify left bottom mirror)
			)
		)
		(property "Value" "C_100n_0402"
			(at -1.022927 -2.155213 90)
			(layer "B.Fab")
			(effects
				(font
					(size 0.7 0.7)
					(thickness 0.15)
				)
				(justify left bottom mirror)
			)
		)
		(property "Footprint" "antmicro-footprints:C_0402_1005Metric"
			(at 0 0 90)
			(layer "B.Fab")
			(hide yes)
			(effects
				(font
					(size 1.27 1.27)
					(thickness 0.15)
				)
				(justify mirror)
			)
		)
		(property "Datasheet" "https://www.murata.com/products/productdetail?partno=GRM155R61H104KE14%23"
			(at 0 0 90)
			(layer "B.Fab")
			(hide yes)
			(effects
				(font
					(size 1.27 1.27)
					(thickness 0.15)
				)
				(justify mirror)
			)
		)
		(property "Description" "SMD Multilayer Ceramic Capacitor, 0.1 µF, 50 V, 0402 [1005 Metric], ± 10%, X5R, GRM Series"
			(at 0 0 90)
			(layer "B.Fab")
			(hide yes)
			(effects
				(font
					(size 1.27 1.27)
					(thickness 0.15)
				)
				(justify mirror)
			)
		)
		(property "MPN" "GRM155R61H104KE14D"
			(at 0 0 90)
			(unlocked yes)
			(layer "B.Fab")
			(hide yes)
			(effects
				(font
					(size 1 1)
					(thickness 0.15)
				)
				(justify mirror)
			)
		)
		(property "Manufacturer" "Murata"
			(at 0 0 90)
			(unlocked yes)
			(layer "B.Fab")
			(hide yes)
			(effects
				(font
					(size 1 1)
					(thickness 0.15)
				)
				(justify mirror)
			)
		)
		(property "License" "Apache-2.0"
			(at 0 0 90)
			(unlocked yes)
			(layer "B.Fab")
			(hide yes)
			(effects
				(font
					(size 1 1)
					(thickness 0.15)
				)
				(justify mirror)
			)
		)
		(property "Author" "Antmicro"
			(at 0 0 90)
			(unlocked yes)
			(layer "B.Fab")
			(hide yes)
			(effects
				(font
					(size 1 1)
					(thickness 0.15)
				)
				(justify mirror)
			)
		)
		(property "Val" "100n"
			(at 0 0 90)
			(unlocked yes)
			(layer "B.Fab")
			(hide yes)
			(effects
				(font
					(size 1 1)
					(thickness 0.15)
				)
				(justify mirror)
			)
		)
		(property "Voltage" "50V"
			(at 0 0 90)
			(unlocked yes)
			(layer "B.Fab")
			(hide yes)
			(effects
				(font
					(size 1 1)
					(thickness 0.15)
				)
				(justify mirror)
			)
		)
		(property "Dielectric" "X5R"
			(at 0 0 90)
			(unlocked yes)
			(layer "B.Fab")
			(hide yes)
			(effects
				(font
					(size 1 1)
					(thickness 0.15)
				)
				(justify mirror)
			)
		)
		(property "Public" "False"
			(at 0 0 90)
			(unlocked yes)
			(layer "B.Fab")
			(hide yes)
			(effects
				(font
					(size 1 1)
					(thickness 0.15)
				)
				(justify mirror)
			)
		)
		(sheetname "Root")
		(sheetfile "jetson-orin-baseboard-oculink-expansion.kicad_sch")
		(attr smd)
		(fp_rect
			(start -0.925 0.47)
			(end 0.925 -0.47)
			(stroke
				(width 0.05)
				(type default)
			)
			(fill none)
			(layer "B.CrtYd")
		)
		(fp_line
			(start -0.494 0.25)
			(end -0.494 -0.248)
			(stroke
				(width 0.15)
				(type solid)
			)
			(layer "B.Fab")
		)
		(fp_line
			(start 0.504 0.25)
			(end -0.494 0.25)
			(stroke
				(width 0.15)
				(type solid)
			)
			(layer "B.Fab")
		)
		(fp_line
			(start -0.494 -0.248)
			(end 0.504 -0.248)
			(stroke
				(width 0.15)
				(type solid)
			)
			(layer "B.Fab")
		)
		(fp_line
			(start 0.504 -0.248)
			(end 0.504 0.25)
			(stroke
				(width 0.15)
				(type solid)
			)
			(layer "B.Fab")
		)
		(fp_text user "Author: Antmicro"
			(at -0.939 -3.399 90)
			(layer "B.Fab")
			(hide yes)
			(effects
				(font
					(size 0.7 0.7)
					(thickness 0.15)
				)
				(justify left bottom mirror)
			)
		)
		(fp_text user "${REFERENCE}"
			(at -0.939 -4.599 90)
			(layer "B.Fab")
			(hide yes)
			(effects
				(font
					(size 0.7 0.7)
					(thickness 0.15)
				)
				(justify left bottom mirror)
			)
		)
		(fp_text user "License: Apache-2.0"
			(at -0.939 -5.799 90)
			(layer "B.Fab")
			(hide yes)
			(effects
				(font
					(size 0.7 0.7)
					(thickness 0.15)
				)
				(justify left bottom mirror)
			)
		)
		(pad "1" smd roundrect
			(at -0.48 0 270)
			(size 0.59 0.64)
			(layers "B.Cu" "B.Paste" "B.Mask")
			(roundrect_rratio 0.25)
			(net 51 "GND")
			(pintype "passive")
		)
		(pad "2" smd roundrect
			(at 0.48 0 270)
			(size 0.59 0.64)
			(layers "B.Cu" "B.Paste" "B.Mask")
			(roundrect_rratio 0.25)
			(net 23 "+3V3")
			(pintype "passive")
		)
	)
	(footprint "antmicro-footprints:R_0402_1005Metric"
		(layer "B.Cu")
		(at 129.72 113.79)
		(descr "Resistor SMD 0402")
		(tags "resistor SMD 0402")
		(property "Reference" "R31"
			(at 0.65 -0.34 0)
			(layer "B.SilkS")
			(effects
				(font
					(size 0.7 0.7)
					(thickness 0.15)
				)
				(justify right top mirror)
			)
		)
		(property "Value" "R_10k_0402"
			(at -1.011843 -1.772047 0)
			(layer "B.Fab")
			(effects
				(font
					(size 0.7 0.7)
					(thickness 0.15)
				)
				(justify right top mirror)
			)
		)
		(property "Footprint" "antmicro-footprints:R_0402_1005Metric"
			(at 0 0 0)
			(layer "B.Fab")
			(hide yes)
			(effects
				(font
					(size 1.27 1.27)
					(thickness 0.15)
				)
				(justify mirror)
			)
		)
		(property "Datasheet" "https://www.bourns.com/docs/product-datasheets/cr.pdf"
			(at 0 0 0)
			(layer "B.Fab")
			(hide yes)
			(effects
				(font
					(size 1.27 1.27)
					(thickness 0.15)
				)
				(justify mirror)
			)
		)
		(property "Description" "SMD Chip Resistor, 10 kohm, ± 1%, 62.5 mW, 0402 [1005 Metric], Thick Film, General Purpose"
			(at 0 0 0)
			(layer "B.Fab")
			(hide yes)
			(effects
				(font
					(size 1.27 1.27)
					(thickness 0.15)
				)
				(justify mirror)
			)
		)
		(property "MPN" "CR0402-FX-1002GLF"
			(at 0 0 180)
			(unlocked yes)
			(layer "B.Fab")
			(hide yes)
			(effects
				(font
					(size 1 1)
					(thickness 0.15)
				)
				(justify mirror)
			)
		)
		(property "Manufacturer" "Bourns"
			(at 0 0 180)
			(unlocked yes)
			(layer "B.Fab")
			(hide yes)
			(effects
				(font
					(size 1 1)
					(thickness 0.15)
				)
				(justify mirror)
			)
		)
		(property "License" "Apache-2.0"
			(at 0 0 180)
			(unlocked yes)
			(layer "B.Fab")
			(hide yes)
			(effects
				(font
					(size 1 1)
					(thickness 0.15)
				)
				(justify mirror)
			)
		)
		(property "Author" "Antmicro"
			(at 0 0 180)
			(unlocked yes)
			(layer "B.Fab")
			(hide yes)
			(effects
				(font
					(size 1 1)
					(thickness 0.15)
				)
				(justify mirror)
			)
		)
		(property "Val" "10k"
			(at 0 0 180)
			(unlocked yes)
			(layer "B.Fab")
			(hide yes)
			(effects
				(font
					(size 1 1)
					(thickness 0.15)
				)
				(justify mirror)
			)
		)
		(property "Tolerance" "1%"
			(at 0 0 180)
			(unlocked yes)
			(layer "B.Fab")
			(hide yes)
			(effects
				(font
					(size 1 1)
					(thickness 0.15)
				)
				(justify mirror)
			)
		)
		(sheetname "Root")
		(sheetfile "jetson-orin-baseboard-oculink-expansion.kicad_sch")
		(attr smd)
		(fp_rect
			(start -0.925 0.47)
			(end 0.925 -0.47)
			(stroke
				(width 0.05)
				(type default)
			)
			(fill none)
			(layer "B.CrtYd")
		)
		(fp_rect
			(start -0.5 0.25)
			(end 0.5 -0.25)
			(stroke
				(width 0.15)
				(type solid)
			)
			(fill none)
			(layer "B.Fab")
		)
		(fp_text user "License: Apache-2.0"
			(at -0.95 -5.169 0)
			(layer "B.Fab")
			(hide yes)
			(effects
				(font
					(size 0.7 0.7)
					(thickness 0.15)
				)
				(justify right top mirror)
			)
		)
		(fp_text user "${REFERENCE}"
			(at -0.95 -3.168 0)
			(layer "B.Fab")
			(hide yes)
			(effects
				(font
					(size 0.7 0.7)
					(thickness 0.15)
				)
				(justify right top mirror)
			)
		)
		(fp_text user "Author: Antmicro"
			(at -0.95 -4.169 0)
			(layer "B.Fab")
			(hide yes)
			(effects
				(font
					(size 0.7 0.7)
					(thickness 0.15)
				)
				(justify right top mirror)
			)
		)
		(pad "1" smd roundrect
			(at -0.48 0)
			(size 0.59 0.64)
			(layers "B.Cu" "B.Paste" "B.Mask")
			(roundrect_rratio 0.25)
			(net 51 "GND")
			(pintype "passive")
		)
		(pad "2" smd roundrect
			(at 0.48 0)
			(size 0.59 0.64)
			(layers "B.Cu" "B.Paste" "B.Mask")
			(roundrect_rratio 0.25)
			(net 103 "Net-(U2-EN_{I2C})")
			(pintype "passive")
		)
	)
	(footprint "antmicro-footprints:R_0402_1005Metric"
		(layer "B.Cu")
		(at 116.55 129.22 180)
		(descr "Resistor SMD 0402")
		(tags "resistor SMD 0402")
		(property "Reference" "R38"
			(at 0.79 -0.22 0)
			(layer "B.SilkS")
			(effects
				(font
					(size 0.7 0.7)
					(thickness 0.15)
				)
				(justify left bottom mirror)
			)
		)
		(property "Value" "R_0R_0402"
			(at -1.011843 -1.772047 0)
			(layer "B.Fab")
			(effects
				(font
					(size 0.7 0.7)
					(thickness 0.15)
				)
				(justify left bottom mirror)
			)
		)
		(property "Footprint" "antmicro-footprints:R_0402_1005Metric"
			(at 0 0 0)
			(layer "B.Fab")
			(hide yes)
			(effects
				(font
					(size 1.27 1.27)
					(thickness 0.15)
				)
				(justify mirror)
			)
		)
		(property "Datasheet" "https://industrial.panasonic.com/cdbs/www-data/pdf/RDA0000/AOA0000C301.pdf"
			(at 0 0 0)
			(layer "B.Fab")
			(hide yes)
			(effects
				(font
					(size 1.27 1.27)
					(thickness 0.15)
				)
				(justify mirror)
			)
		)
		(property "Description" "SMD Chip Resistor, Jumper, 0 ohm, 100 mW, 0402 [1005 Metric], Thick Film, General Purpose"
			(at 0 0 0)
			(layer "B.Fab")
			(hide yes)
			(effects
				(font
					(size 1.27 1.27)
					(thickness 0.15)
				)
				(justify mirror)
			)
		)
		(property "MPN" "ERJ2GE0R00X"
			(at 0 0 0)
			(unlocked yes)
			(layer "B.Fab")
			(hide yes)
			(effects
				(font
					(size 1 1)
					(thickness 0.15)
				)
				(justify mirror)
			)
		)
		(property "Manufacturer" "Panasonic"
			(at 0 0 0)
			(unlocked yes)
			(layer "B.Fab")
			(hide yes)
			(effects
				(font
					(size 1 1)
					(thickness 0.15)
				)
				(justify mirror)
			)
		)
		(property "License" "Apache-2.0"
			(at 0 0 0)
			(unlocked yes)
			(layer "B.Fab")
			(hide yes)
			(effects
				(font
					(size 1 1)
					(thickness 0.15)
				)
				(justify mirror)
			)
		)
		(property "Author" "Antmicro"
			(at 0 0 0)
			(unlocked yes)
			(layer "B.Fab")
			(hide yes)
			(effects
				(font
					(size 1 1)
					(thickness 0.15)
				)
				(justify mirror)
			)
		)
		(property "Val" "0R"
			(at 0 0 0)
			(unlocked yes)
			(layer "B.Fab")
			(hide yes)
			(effects
				(font
					(size 1 1)
					(thickness 0.15)
				)
				(justify mirror)
			)
		)
		(property "Tolerance" ""
			(at 0 0 0)
			(unlocked yes)
			(layer "B.Fab")
			(hide yes)
			(effects
				(font
					(size 1 1)
					(thickness 0.15)
				)
				(justify mirror)
			)
		)
		(property "Current" "1A"
			(at 0 0 0)
			(unlocked yes)
			(layer "B.Fab")
			(hide yes)
			(effects
				(font
					(size 1 1)
					(thickness 0.15)
				)
				(justify mirror)
			)
		)
		(property "Public" "False"
			(at 0 0 0)
			(unlocked yes)
			(layer "B.Fab")
			(hide yes)
			(effects
				(font
					(size 1 1)
					(thickness 0.15)
				)
				(justify mirror)
			)
		)
		(sheetname "Root")
		(sheetfile "jetson-orin-baseboard-oculink-expansion.kicad_sch")
		(attr smd dnp)
		(fp_rect
			(start -0.925 0.47)
			(end 0.925 -0.47)
			(stroke
				(width 0.05)
				(type default)
			)
			(fill none)
			(layer "B.CrtYd")
		)
		(fp_rect
			(start -0.5 0.25)
			(end 0.5 -0.25)
			(stroke
				(width 0.15)
				(type solid)
			)
			(fill none)
			(layer "B.Fab")
		)
		(fp_text user "License: Apache-2.0"
			(at -0.95 -5.169 0)
			(layer "B.Fab")
			(hide yes)
			(effects
				(font
					(size 0.7 0.7)
					(thickness 0.15)
				)
				(justify left bottom mirror)
			)
		)
		(fp_text user "Author: Antmicro"
			(at -0.95 -4.169 0)
			(layer "B.Fab")
			(hide yes)
			(effects
				(font
					(size 0.7 0.7)
					(thickness 0.15)
				)
				(justify left bottom mirror)
			)
		)
		(fp_text user "${REFERENCE}"
			(at -0.95 -3.168 0)
			(layer "B.Fab")
			(hide yes)
			(effects
				(font
					(size 0.7 0.7)
					(thickness 0.15)
				)
				(justify left bottom mirror)
			)
		)
		(pad "1" smd roundrect
			(at -0.48 0 180)
			(size 0.59 0.64)
			(layers "B.Cu" "B.Paste" "B.Mask")
			(roundrect_rratio 0.25)
			(net 23 "+3V3")
			(pintype "passive")
		)
		(pad "2" smd roundrect
			(at 0.48 0 180)
			(size 0.59 0.64)
			(layers "B.Cu" "B.Paste" "B.Mask")
			(roundrect_rratio 0.25)
			(net 105 "Net-(U3-EN_{I2C})")
			(pintype "passive")
		)
	)
	(footprint "antmicro-footprints:R_0402_1005Metric"
		(layer "B.Cu")
		(at 113.73 130.28 90)
		(descr "Resistor SMD 0402")
		(tags "resistor SMD 0402")
		(property "Reference" "R44"
			(at -2.96 -0.39 90)
			(layer "B.SilkS")
			(effects
				(font
					(size 0.7 0.7)
					(thickness 0.15)
				)
				(justify right top mirror)
			)
		)
		(property "Value" "R_0R_0402"
			(at -1.011843 -1.772047 90)
			(layer "B.Fab")
			(effects
				(font
					(size 0.7 0.7)
					(thickness 0.15)
				)
				(justify right top mirror)
			)
		)
		(property "Footprint" "antmicro-footprints:R_0402_1005Metric"
			(at 0 0 90)
			(layer "B.Fab")
			(hide yes)
			(effects
				(font
					(size 1.27 1.27)
					(thickness 0.15)
				)
				(justify mirror)
			)
		)
		(property "Datasheet" "https://industrial.panasonic.com/cdbs/www-data/pdf/RDA0000/AOA0000C301.pdf"
			(at 0 0 90)
			(layer "B.Fab")
			(hide yes)
			(effects
				(font
					(size 1.27 1.27)
					(thickness 0.15)
				)
				(justify mirror)
			)
		)
		(property "Description" "SMD Chip Resistor, Jumper, 0 ohm, 100 mW, 0402 [1005 Metric], Thick Film, General Purpose"
			(at 0 0 90)
			(layer "B.Fab")
			(hide yes)
			(effects
				(font
					(size 1.27 1.27)
					(thickness 0.15)
				)
				(justify mirror)
			)
		)
		(property "MPN" "ERJ2GE0R00X"
			(at 0 0 -90)
			(unlocked yes)
			(layer "B.Fab")
			(hide yes)
			(effects
				(font
					(size 1 1)
					(thickness 0.15)
				)
				(justify mirror)
			)
		)
		(property "Manufacturer" "Panasonic"
			(at 0 0 -90)
			(unlocked yes)
			(layer "B.Fab")
			(hide yes)
			(effects
				(font
					(size 1 1)
					(thickness 0.15)
				)
				(justify mirror)
			)
		)
		(property "License" "Apache-2.0"
			(at 0 0 -90)
			(unlocked yes)
			(layer "B.Fab")
			(hide yes)
			(effects
				(font
					(size 1 1)
					(thickness 0.15)
				)
				(justify mirror)
			)
		)
		(property "Author" "Antmicro"
			(at 0 0 -90)
			(unlocked yes)
			(layer "B.Fab")
			(hide yes)
			(effects
				(font
					(size 1 1)
					(thickness 0.15)
				)
				(justify mirror)
			)
		)
		(property "Val" "0R"
			(at 0 0 -90)
			(unlocked yes)
			(layer "B.Fab")
			(hide yes)
			(effects
				(font
					(size 1 1)
					(thickness 0.15)
				)
				(justify mirror)
			)
		)
		(property "Tolerance" ""
			(at 0 0 -90)
			(unlocked yes)
			(layer "B.Fab")
			(hide yes)
			(effects
				(font
					(size 1 1)
					(thickness 0.15)
				)
				(justify mirror)
			)
		)
		(property "Current" "1A"
			(at 0 0 -90)
			(unlocked yes)
			(layer "B.Fab")
			(hide yes)
			(effects
				(font
					(size 1 1)
					(thickness 0.15)
				)
				(justify mirror)
			)
		)
		(property "Public" "False"
			(at 0 0 -90)
			(unlocked yes)
			(layer "B.Fab")
			(hide yes)
			(effects
				(font
					(size 1 1)
					(thickness 0.15)
				)
				(justify mirror)
			)
		)
		(sheetname "Root")
		(sheetfile "jetson-orin-baseboard-oculink-expansion.kicad_sch")
		(attr smd dnp)
		(fp_rect
			(start -0.925 0.47)
			(end 0.925 -0.47)
			(stroke
				(width 0.05)
				(type default)
			)
			(fill none)
			(layer "B.CrtYd")
		)
		(fp_rect
			(start -0.5 0.25)
			(end 0.5 -0.25)
			(stroke
				(width 0.15)
				(type solid)
			)
			(fill none)
			(layer "B.Fab")
		)
		(fp_text user "License: Apache-2.0"
			(at -0.95 -5.169 90)
			(layer "B.Fab")
			(hide yes)
			(effects
				(font
					(size 0.7 0.7)
					(thickness 0.15)
				)
				(justify right top mirror)
			)
		)
		(fp_text user "Author: Antmicro"
			(at -0.95 -4.169 90)
			(layer "B.Fab")
			(hide yes)
			(effects
				(font
					(size 0.7 0.7)
					(thickness 0.15)
				)
				(justify right top mirror)
			)
		)
		(fp_text user "${REFERENCE}"
			(at -0.95 -3.168 90)
			(layer "B.Fab")
			(hide yes)
			(effects
				(font
					(size 0.7 0.7)
					(thickness 0.15)
				)
				(justify right top mirror)
			)
		)
		(pad "1" smd roundrect
			(at -0.48 0 90)
			(size 0.59 0.64)
			(layers "B.Cu" "B.Paste" "B.Mask")
			(roundrect_rratio 0.25)
			(net 61 "/I2C_SDA")
			(pintype "passive")
		)
		(pad "2" smd roundrect
			(at 0.48 0 90)
			(size 0.59 0.64)
			(layers "B.Cu" "B.Paste" "B.Mask")
			(roundrect_rratio 0.25)
			(net 107 "Net-(U3-SDA)")
			(pintype "passive")
		)
	)
	(footprint "antmicro-footprints:C_0402_1005Metric"
		(layer "B.Cu")
		(at 126.505 116.687251 -90)
		(descr "Capacitor SMD 0402")
		(tags "capacitor SMD 0402")
		(property "Reference" "C10"
			(at 1.782749 -0.435 90)
			(layer "B.SilkS")
			(effects
				(font
					(size 0.7 0.7)
					(thickness 0.15)
				)
				(justify left bottom mirror)
			)
		)
		(property "Value" "C_100n_0402"
			(at -1.022927 -2.155213 90)
			(layer "B.Fab")
			(effects
				(font
					(size 0.7 0.7)
					(thickness 0.15)
				)
				(justify left bottom mirror)
			)
		)
		(property "Footprint" "antmicro-footprints:C_0402_1005Metric"
			(at 0 0 90)
			(layer "B.Fab")
			(hide yes)
			(effects
				(font
					(size 1.27 1.27)
					(thickness 0.15)
				)
				(justify mirror)
			)
		)
		(property "Datasheet" "https://www.murata.com/products/productdetail?partno=GRM155R61H104KE14%23"
			(at 0 0 90)
			(layer "B.Fab")
			(hide yes)
			(effects
				(font
					(size 1.27 1.27)
					(thickness 0.15)
				)
				(justify mirror)
			)
		)
		(property "Description" "SMD Multilayer Ceramic Capacitor, 0.1 µF, 50 V, 0402 [1005 Metric], ± 10%, X5R, GRM Series"
			(at 0 0 90)
			(layer "B.Fab")
			(hide yes)
			(effects
				(font
					(size 1.27 1.27)
					(thickness 0.15)
				)
				(justify mirror)
			)
		)
		(property "MPN" "GRM155R61H104KE14D"
			(at 0 0 90)
			(unlocked yes)
			(layer "B.Fab")
			(hide yes)
			(effects
				(font
					(size 1 1)
					(thickness 0.15)
				)
				(justify mirror)
			)
		)
		(property "Manufacturer" "Murata"
			(at 0 0 90)
			(unlocked yes)
			(layer "B.Fab")
			(hide yes)
			(effects
				(font
					(size 1 1)
					(thickness 0.15)
				)
				(justify mirror)
			)
		)
		(property "License" "Apache-2.0"
			(at 0 0 90)
			(unlocked yes)
			(layer "B.Fab")
			(hide yes)
			(effects
				(font
					(size 1 1)
					(thickness 0.15)
				)
				(justify mirror)
			)
		)
		(property "Author" "Antmicro"
			(at 0 0 90)
			(unlocked yes)
			(layer "B.Fab")
			(hide yes)
			(effects
				(font
					(size 1 1)
					(thickness 0.15)
				)
				(justify mirror)
			)
		)
		(property "Val" "100n"
			(at 0 0 90)
			(unlocked yes)
			(layer "B.Fab")
			(hide yes)
			(effects
				(font
					(size 1 1)
					(thickness 0.15)
				)
				(justify mirror)
			)
		)
		(property "Voltage" "50V"
			(at 0 0 90)
			(unlocked yes)
			(layer "B.Fab")
			(hide yes)
			(effects
				(font
					(size 1 1)
					(thickness 0.15)
				)
				(justify mirror)
			)
		)
		(property "Dielectric" "X5R"
			(at 0 0 90)
			(unlocked yes)
			(layer "B.Fab")
			(hide yes)
			(effects
				(font
					(size 1 1)
					(thickness 0.15)
				)
				(justify mirror)
			)
		)
		(property "Public" "False"
			(at 0 0 90)
			(unlocked yes)
			(layer "B.Fab")
			(hide yes)
			(effects
				(font
					(size 1 1)
					(thickness 0.15)
				)
				(justify mirror)
			)
		)
		(sheetname "Root")
		(sheetfile "jetson-orin-baseboard-oculink-expansion.kicad_sch")
		(attr smd)
		(fp_rect
			(start -0.925 0.47)
			(end 0.925 -0.47)
			(stroke
				(width 0.05)
				(type default)
			)
			(fill none)
			(layer "B.CrtYd")
		)
		(fp_line
			(start -0.494 0.25)
			(end -0.494 -0.248)
			(stroke
				(width 0.15)
				(type solid)
			)
			(layer "B.Fab")
		)
		(fp_line
			(start 0.504 0.25)
			(end -0.494 0.25)
			(stroke
				(width 0.15)
				(type solid)
			)
			(layer "B.Fab")
		)
		(fp_line
			(start -0.494 -0.248)
			(end 0.504 -0.248)
			(stroke
				(width 0.15)
				(type solid)
			)
			(layer "B.Fab")
		)
		(fp_line
			(start 0.504 -0.248)
			(end 0.504 0.25)
			(stroke
				(width 0.15)
				(type solid)
			)
			(layer "B.Fab")
		)
		(fp_text user "Author: Antmicro"
			(at -0.939 -3.399 90)
			(layer "B.Fab")
			(hide yes)
			(effects
				(font
					(size 0.7 0.7)
					(thickness 0.15)
				)
				(justify left bottom mirror)
			)
		)
		(fp_text user "${REFERENCE}"
			(at -0.939 -4.599 90)
			(layer "B.Fab")
			(hide yes)
			(effects
				(font
					(size 0.7 0.7)
					(thickness 0.15)
				)
				(justify left bottom mirror)
			)
		)
		(fp_text user "License: Apache-2.0"
			(at -0.939 -5.799 90)
			(layer "B.Fab")
			(hide yes)
			(effects
				(font
					(size 0.7 0.7)
					(thickness 0.15)
				)
				(justify left bottom mirror)
			)
		)
		(pad "1" smd roundrect
			(at -0.48 0 270)
			(size 0.59 0.64)
			(layers "B.Cu" "B.Paste" "B.Mask")
			(roundrect_rratio 0.25)
			(net 51 "GND")
			(pintype "passive")
		)
		(pad "2" smd roundrect
			(at 0.48 0 270)
			(size 0.59 0.64)
			(layers "B.Cu" "B.Paste" "B.Mask")
			(roundrect_rratio 0.25)
			(net 23 "+3V3")
			(pintype "passive")
		)
	)
	(footprint "antmicro-footprints:R_0402_1005Metric"
		(layer "B.Cu")
		(at 130.5 117.17 180)
		(descr "Resistor SMD 0402")
		(tags "resistor SMD 0402")
		(property "Reference" "R16"
			(at -2.946 -0.451749 0)
			(layer "B.SilkS")
			(effects
				(font
					(size 0.7 0.7)
					(thickness 0.15)
				)
				(justify left bottom mirror)
			)
		)
		(property "Value" "R_10k_0402"
			(at -1.011843 -1.772047 0)
			(layer "B.Fab")
			(effects
				(font
					(size 0.7 0.7)
					(thickness 0.15)
				)
				(justify left bottom mirror)
			)
		)
		(property "Footprint" "antmicro-footprints:R_0402_1005Metric"
			(at 0 0 0)
			(layer "B.Fab")
			(hide yes)
			(effects
				(font
					(size 1.27 1.27)
					(thickness 0.15)
				)
				(justify mirror)
			)
		)
		(property "Datasheet" "https://www.bourns.com/docs/product-datasheets/cr.pdf"
			(at 0 0 0)
			(layer "B.Fab")
			(hide yes)
			(effects
				(font
					(size 1.27 1.27)
					(thickness 0.15)
				)
				(justify mirror)
			)
		)
		(property "Description" "SMD Chip Resistor, 10 kohm, ± 1%, 62.5 mW, 0402 [1005 Metric], Thick Film, General Purpose"
			(at 0 0 0)
			(layer "B.Fab")
			(hide yes)
			(effects
				(font
					(size 1.27 1.27)
					(thickness 0.15)
				)
				(justify mirror)
			)
		)
		(property "MPN" "CR0402-FX-1002GLF"
			(at 0 0 0)
			(unlocked yes)
			(layer "B.Fab")
			(hide yes)
			(effects
				(font
					(size 1 1)
					(thickness 0.15)
				)
				(justify mirror)
			)
		)
		(property "Manufacturer" "Bourns"
			(at 0 0 0)
			(unlocked yes)
			(layer "B.Fab")
			(hide yes)
			(effects
				(font
					(size 1 1)
					(thickness 0.15)
				)
				(justify mirror)
			)
		)
		(property "License" "Apache-2.0"
			(at 0 0 0)
			(unlocked yes)
			(layer "B.Fab")
			(hide yes)
			(effects
				(font
					(size 1 1)
					(thickness 0.15)
				)
				(justify mirror)
			)
		)
		(property "Author" "Antmicro"
			(at 0 0 0)
			(unlocked yes)
			(layer "B.Fab")
			(hide yes)
			(effects
				(font
					(size 1 1)
					(thickness 0.15)
				)
				(justify mirror)
			)
		)
		(property "Val" "10k"
			(at 0 0 0)
			(unlocked yes)
			(layer "B.Fab")
			(hide yes)
			(effects
				(font
					(size 1 1)
					(thickness 0.15)
				)
				(justify mirror)
			)
		)
		(property "Tolerance" "1%"
			(at 0 0 0)
			(unlocked yes)
			(layer "B.Fab")
			(hide yes)
			(effects
				(font
					(size 1 1)
					(thickness 0.15)
				)
				(justify mirror)
			)
		)
		(sheetname "Root")
		(sheetfile "jetson-orin-baseboard-oculink-expansion.kicad_sch")
		(attr smd)
		(fp_rect
			(start -0.925 0.47)
			(end 0.925 -0.47)
			(stroke
				(width 0.05)
				(type default)
			)
			(fill none)
			(layer "B.CrtYd")
		)
		(fp_rect
			(start -0.5 0.25)
			(end 0.5 -0.25)
			(stroke
				(width 0.15)
				(type solid)
			)
			(fill none)
			(layer "B.Fab")
		)
		(fp_text user "${REFERENCE}"
			(at -0.95 -3.168 0)
			(layer "B.Fab")
			(hide yes)
			(effects
				(font
					(size 0.7 0.7)
					(thickness 0.15)
				)
				(justify left bottom mirror)
			)
		)
		(fp_text user "License: Apache-2.0"
			(at -0.95 -5.169 0)
			(layer "B.Fab")
			(hide yes)
			(effects
				(font
					(size 0.7 0.7)
					(thickness 0.15)
				)
				(justify left bottom mirror)
			)
		)
		(fp_text user "Author: Antmicro"
			(at -0.95 -4.169 0)
			(layer "B.Fab")
			(hide yes)
			(effects
				(font
					(size 0.7 0.7)
					(thickness 0.15)
				)
				(justify left bottom mirror)
			)
		)
		(pad "1" smd roundrect
			(at -0.48 0 180)
			(size 0.59 0.64)
			(layers "B.Cu" "B.Paste" "B.Mask")
			(roundrect_rratio 0.25)
			(net 95 "Net-(U2-SDA)")
			(pintype "passive")
		)
		(pad "2" smd roundrect
			(at 0.48 0 180)
			(size 0.59 0.64)
			(layers "B.Cu" "B.Paste" "B.Mask")
			(roundrect_rratio 0.25)
			(net 23 "+3V3")
			(pintype "passive")
		)
	)
	(footprint "antmicro-footprints:TP_SMD_1.5mm"
		(layer "B.Cu")
		(at 126.45 136.3 -90)
		(property "Reference" "TP2"
			(at 0.3395 -2.9365 0)
			(layer "B.SilkS")
			(hide yes)
			(effects
				(font
					(size 0.7 0.7)
					(thickness 0.15)
				)
				(justify left bottom mirror)
			)
		)
		(property "Value" "TP_1.5mm_SMD"
			(at 0 -1.7 90)
			(layer "B.Fab")
			(effects
				(font
					(size 0.7 0.7)
					(thickness 0.15)
				)
				(justify left bottom mirror)
			)
		)
		(property "Footprint" "antmicro-footprints:TP_SMD_1.5mm"
			(at 0 0 90)
			(layer "B.Fab")
			(hide yes)
			(effects
				(font
					(size 1.27 1.27)
					(thickness 0.15)
				)
				(justify mirror)
			)
		)
		(property "Description" "test point, SMT"
			(at 0 0 90)
			(layer "B.Fab")
			(hide yes)
			(effects
				(font
					(size 1.27 1.27)
					(thickness 0.15)
				)
				(justify mirror)
			)
		)
		(property "MPN" ""
			(at 0 0 90)
			(unlocked yes)
			(layer "B.Fab")
			(hide yes)
			(effects
				(font
					(size 1 1)
					(thickness 0.15)
				)
				(justify mirror)
			)
		)
		(property "Manufacturer" ""
			(at 0 0 90)
			(unlocked yes)
			(layer "B.Fab")
			(hide yes)
			(effects
				(font
					(size 1 1)
					(thickness 0.15)
				)
				(justify mirror)
			)
		)
		(property "Author" "Antmicro"
			(at 0 0 90)
			(unlocked yes)
			(layer "B.Fab")
			(hide yes)
			(effects
				(font
					(size 1 1)
					(thickness 0.15)
				)
				(justify mirror)
			)
		)
		(property "License" "Apache-2.0"
			(at 0 0 90)
			(unlocked yes)
			(layer "B.Fab")
			(hide yes)
			(effects
				(font
					(size 1 1)
					(thickness 0.15)
				)
				(justify mirror)
			)
		)
		(sheetname "Root")
		(sheetfile "jetson-orin-baseboard-oculink-expansion.kicad_sch")
		(attr exclude_from_pos_files exclude_from_bom)
		(fp_circle
			(center 0 0)
			(end 0.85 0)
			(stroke
				(width 0.05)
				(type default)
			)
			(fill none)
			(layer "B.CrtYd")
		)
		(fp_text user "License: Apache-2.0"
			(at -0.7 -5.301 90)
			(layer "B.Fab")
			(hide yes)
			(effects
				(font
					(size 0.7 0.7)
					(thickness 0.15)
				)
				(justify left bottom mirror)
			)
		)
		(fp_text user "${REFERENCE}"
			(at -0.7 -2.9 90)
			(layer "B.Fab")
			(hide yes)
			(effects
				(font
					(size 0.7 0.7)
					(thickness 0.15)
				)
				(justify left bottom mirror)
			)
		)
		(fp_text user "Author: Antmicro"
			(at -0.7 -4.101 90)
			(layer "B.Fab")
			(hide yes)
			(effects
				(font
					(size 0.7 0.7)
					(thickness 0.15)
				)
				(justify left bottom mirror)
			)
		)
		(pad "1" smd circle
			(at 0 0)
			(size 1.5 1.5)
			(layers "B.Cu" "B.Mask")
			(net 61 "/I2C_SDA")
			(pinfunction "1")
			(pintype "passive")
		)
	)
	(footprint "antmicro-footprints:R_0402_1005Metric"
		(layer "B.Cu")
		(at 116.475 118.193751)
		(descr "Resistor SMD 0402")
		(tags "resistor SMD 0402")
		(property "Reference" "R15"
			(at -3.251667 -0.383751 0)
			(layer "B.SilkS")
			(effects
				(font
					(size 0.7 0.7)
					(thickness 0.15)
				)
				(justify right top mirror)
			)
		)
		(property "Value" "R_1k_0402"
			(at -1.011843 -1.772047 0)
			(layer "B.Fab")
			(effects
				(font
					(size 0.7 0.7)
					(thickness 0.15)
				)
				(justify right top mirror)
			)
		)
		(property "Footprint" "antmicro-footprints:R_0402_1005Metric"
			(at 0 0 0)
			(layer "B.Fab")
			(hide yes)
			(effects
				(font
					(size 1.27 1.27)
					(thickness 0.15)
				)
				(justify mirror)
			)
		)
		(property "Datasheet" "https://www.bourns.com/docs/product-datasheets/cr.pdf"
			(at 0 0 0)
			(layer "B.Fab")
			(hide yes)
			(effects
				(font
					(size 1.27 1.27)
					(thickness 0.15)
				)
				(justify mirror)
			)
		)
		(property "Description" "SMD Chip Resistor, 1 kohm, ± 1%, 63 mW, 0402 [1005 Metric], Thick Film, General Purpose"
			(at 0 0 0)
			(layer "B.Fab")
			(hide yes)
			(effects
				(font
					(size 1.27 1.27)
					(thickness 0.15)
				)
				(justify mirror)
			)
		)
		(property "MPN" "CR0402-FX-1001GLF"
			(at 0 0 180)
			(unlocked yes)
			(layer "B.Fab")
			(hide yes)
			(effects
				(font
					(size 1 1)
					(thickness 0.15)
				)
				(justify mirror)
			)
		)
		(property "Manufacturer" "Bourns"
			(at 0 0 180)
			(unlocked yes)
			(layer "B.Fab")
			(hide yes)
			(effects
				(font
					(size 1 1)
					(thickness 0.15)
				)
				(justify mirror)
			)
		)
		(property "License" "Apache-2.0"
			(at 0 0 180)
			(unlocked yes)
			(layer "B.Fab")
			(hide yes)
			(effects
				(font
					(size 1 1)
					(thickness 0.15)
				)
				(justify mirror)
			)
		)
		(property "Author" "Antmicro"
			(at 0 0 180)
			(unlocked yes)
			(layer "B.Fab")
			(hide yes)
			(effects
				(font
					(size 1 1)
					(thickness 0.15)
				)
				(justify mirror)
			)
		)
		(property "Val" "1k"
			(at 0 0 180)
			(unlocked yes)
			(layer "B.Fab")
			(hide yes)
			(effects
				(font
					(size 1 1)
					(thickness 0.15)
				)
				(justify mirror)
			)
		)
		(property "Tolerance" "1%"
			(at 0 0 180)
			(unlocked yes)
			(layer "B.Fab")
			(hide yes)
			(effects
				(font
					(size 1 1)
					(thickness 0.15)
				)
				(justify mirror)
			)
		)
		(property "Public" "False"
			(at 0 0 180)
			(unlocked yes)
			(layer "B.Fab")
			(hide yes)
			(effects
				(font
					(size 1 1)
					(thickness 0.15)
				)
				(justify mirror)
			)
		)
		(sheetname "Root")
		(sheetfile "jetson-orin-baseboard-oculink-expansion.kicad_sch")
		(attr smd dnp)
		(fp_rect
			(start -0.925 0.47)
			(end 0.925 -0.47)
			(stroke
				(width 0.05)
				(type default)
			)
			(fill none)
			(layer "B.CrtYd")
		)
		(fp_rect
			(start -0.5 0.25)
			(end 0.5 -0.25)
			(stroke
				(width 0.15)
				(type solid)
			)
			(fill none)
			(layer "B.Fab")
		)
		(fp_text user "License: Apache-2.0"
			(at -0.95 -5.169 0)
			(layer "B.Fab")
			(hide yes)
			(effects
				(font
					(size 0.7 0.7)
					(thickness 0.15)
				)
				(justify right top mirror)
			)
		)
		(fp_text user "${REFERENCE}"
			(at -0.95 -3.168 0)
			(layer "B.Fab")
			(hide yes)
			(effects
				(font
					(size 0.7 0.7)
					(thickness 0.15)
				)
				(justify right top mirror)
			)
		)
		(fp_text user "Author: Antmicro"
			(at -0.95 -4.169 0)
			(layer "B.Fab")
			(hide yes)
			(effects
				(font
					(size 0.7 0.7)
					(thickness 0.15)
				)
				(justify right top mirror)
			)
		)
		(pad "1" smd roundrect
			(at -0.48 0)
			(size 0.59 0.64)
			(layers "B.Cu" "B.Paste" "B.Mask")
			(roundrect_rratio 0.25)
			(net 51 "GND")
			(pintype "passive")
		)
		(pad "2" smd roundrect
			(at 0.48 0)
			(size 0.59 0.64)
			(layers "B.Cu" "B.Paste" "B.Mask")
			(roundrect_rratio 0.25)
			(net 94 "/RX_SW")
			(pintype "passive")
		)
	)
	(footprint "antmicro-footprints:C_0402_1005Metric"
		(layer "B.Cu")
		(at 119.775 125.795 90)
		(descr "Capacitor SMD 0402")
		(tags "capacitor SMD 0402")
		(property "Reference" "C26"
			(at 1.605 -0.355 90)
			(layer "B.SilkS")
			(effects
				(font
					(size 0.7 0.7)
					(thickness 0.15)
				)
				(justify right top mirror)
			)
		)
		(property "Value" "C_100n_0402"
			(at -1.022927 -2.155213 90)
			(layer "B.Fab")
			(effects
				(font
					(size 0.7 0.7)
					(thickness 0.15)
				)
				(justify right top mirror)
			)
		)
		(property "Footprint" "antmicro-footprints:C_0402_1005Metric"
			(at 0 0 90)
			(layer "B.Fab")
			(hide yes)
			(effects
				(font
					(size 1.27 1.27)
					(thickness 0.15)
				)
				(justify mirror)
			)
		)
		(property "Datasheet" "https://www.murata.com/products/productdetail?partno=GRM155R61H104KE14%23"
			(at 0 0 90)
			(layer "B.Fab")
			(hide yes)
			(effects
				(font
					(size 1.27 1.27)
					(thickness 0.15)
				)
				(justify mirror)
			)
		)
		(property "Description" "SMD Multilayer Ceramic Capacitor, 0.1 µF, 50 V, 0402 [1005 Metric], ± 10%, X5R, GRM Series"
			(at 0 0 90)
			(layer "B.Fab")
			(hide yes)
			(effects
				(font
					(size 1.27 1.27)
					(thickness 0.15)
				)
				(justify mirror)
			)
		)
		(property "MPN" "GRM155R61H104KE14D"
			(at 0 0 -90)
			(unlocked yes)
			(layer "B.Fab")
			(hide yes)
			(effects
				(font
					(size 1 1)
					(thickness 0.15)
				)
				(justify mirror)
			)
		)
		(property "Manufacturer" "Murata"
			(at 0 0 -90)
			(unlocked yes)
			(layer "B.Fab")
			(hide yes)
			(effects
				(font
					(size 1 1)
					(thickness 0.15)
				)
				(justify mirror)
			)
		)
		(property "License" "Apache-2.0"
			(at 0 0 -90)
			(unlocked yes)
			(layer "B.Fab")
			(hide yes)
			(effects
				(font
					(size 1 1)
					(thickness 0.15)
				)
				(justify mirror)
			)
		)
		(property "Author" "Antmicro"
			(at 0 0 -90)
			(unlocked yes)
			(layer "B.Fab")
			(hide yes)
			(effects
				(font
					(size 1 1)
					(thickness 0.15)
				)
				(justify mirror)
			)
		)
		(property "Val" "100n"
			(at 0 0 -90)
			(unlocked yes)
			(layer "B.Fab")
			(hide yes)
			(effects
				(font
					(size 1 1)
					(thickness 0.15)
				)
				(justify mirror)
			)
		)
		(property "Voltage" "50V"
			(at 0 0 -90)
			(unlocked yes)
			(layer "B.Fab")
			(hide yes)
			(effects
				(font
					(size 1 1)
					(thickness 0.15)
				)
				(justify mirror)
			)
		)
		(property "Dielectric" "X5R"
			(at 0 0 -90)
			(unlocked yes)
			(layer "B.Fab")
			(hide yes)
			(effects
				(font
					(size 1 1)
					(thickness 0.15)
				)
				(justify mirror)
			)
		)
		(property "Public" "False"
			(at 0 0 -90)
			(unlocked yes)
			(layer "B.Fab")
			(hide yes)
			(effects
				(font
					(size 1 1)
					(thickness 0.15)
				)
				(justify mirror)
			)
		)
		(sheetname "Root")
		(sheetfile "jetson-orin-baseboard-oculink-expansion.kicad_sch")
		(attr smd)
		(fp_rect
			(start -0.925 0.47)
			(end 0.925 -0.47)
			(stroke
				(width 0.05)
				(type default)
			)
			(fill none)
			(layer "B.CrtYd")
		)
		(fp_line
			(start 0.504 -0.248)
			(end 0.504 0.25)
			(stroke
				(width 0.15)
				(type solid)
			)
			(layer "B.Fab")
		)
		(fp_line
			(start -0.494 -0.248)
			(end 0.504 -0.248)
			(stroke
				(width 0.15)
				(type solid)
			)
			(layer "B.Fab")
		)
		(fp_line
			(start 0.504 0.25)
			(end -0.494 0.25)
			(stroke
				(width 0.15)
				(type solid)
			)
			(layer "B.Fab")
		)
		(fp_line
			(start -0.494 0.25)
			(end -0.494 -0.248)
			(stroke
				(width 0.15)
				(type solid)
			)
			(layer "B.Fab")
		)
		(fp_text user "${REFERENCE}"
			(at -0.939 -4.599 90)
			(layer "B.Fab")
			(hide yes)
			(effects
				(font
					(size 0.7 0.7)
					(thickness 0.15)
				)
				(justify right top mirror)
			)
		)
		(fp_text user "Author: Antmicro"
			(at -0.939 -3.399 90)
			(layer "B.Fab")
			(hide yes)
			(effects
				(font
					(size 0.7 0.7)
					(thickness 0.15)
				)
				(justify right top mirror)
			)
		)
		(fp_text user "License: Apache-2.0"
			(at -0.939 -5.799 90)
			(layer "B.Fab")
			(hide yes)
			(effects
				(font
					(size 0.7 0.7)
					(thickness 0.15)
				)
				(justify right top mirror)
			)
		)
		(pad "1" smd roundrect
			(at -0.48 0 90)
			(size 0.59 0.64)
			(layers "B.Cu" "B.Paste" "B.Mask")
			(roundrect_rratio 0.25)
			(net 51 "GND")
			(pintype "passive")
		)
		(pad "2" smd roundrect
			(at 0.48 0 90)
			(size 0.59 0.64)
			(layers "B.Cu" "B.Paste" "B.Mask")
			(roundrect_rratio 0.25)
			(net 23 "+3V3")
			(pintype "passive")
		)
	)
	(footprint "antmicro-footprints:C_0402_1005Metric"
		(layer "B.Cu")
		(at 122.005 114.568251 90)
		(descr "Capacitor SMD 0402")
		(tags "capacitor SMD 0402")
		(property "Reference" "C27"
			(at 1.778251 -0.215 90)
			(layer "B.SilkS")
			(effects
				(font
					(size 0.7 0.7)
					(thickness 0.15)
				)
				(justify right top mirror)
			)
		)
		(property "Value" "C_100n_0402"
			(at -1.022927 -2.155213 90)
			(layer "B.Fab")
			(effects
				(font
					(size 0.7 0.7)
					(thickness 0.15)
				)
				(justify right top mirror)
			)
		)
		(property "Footprint" "antmicro-footprints:C_0402_1005Metric"
			(at 0 0 90)
			(layer "B.Fab")
			(hide yes)
			(effects
				(font
					(size 1.27 1.27)
					(thickness 0.15)
				)
				(justify mirror)
			)
		)
		(property "Datasheet" "https://www.murata.com/products/productdetail?partno=GRM155R61H104KE14%23"
			(at 0 0 90)
			(layer "B.Fab")
			(hide yes)
			(effects
				(font
					(size 1.27 1.27)
					(thickness 0.15)
				)
				(justify mirror)
			)
		)
		(property "Description" "SMD Multilayer Ceramic Capacitor, 0.1 µF, 50 V, 0402 [1005 Metric], ± 10%, X5R, GRM Series"
			(at 0 0 90)
			(layer "B.Fab")
			(hide yes)
			(effects
				(font
					(size 1.27 1.27)
					(thickness 0.15)
				)
				(justify mirror)
			)
		)
		(property "MPN" "GRM155R61H104KE14D"
			(at 0 0 -90)
			(unlocked yes)
			(layer "B.Fab")
			(hide yes)
			(effects
				(font
					(size 1 1)
					(thickness 0.15)
				)
				(justify mirror)
			)
		)
		(property "Manufacturer" "Murata"
			(at 0 0 -90)
			(unlocked yes)
			(layer "B.Fab")
			(hide yes)
			(effects
				(font
					(size 1 1)
					(thickness 0.15)
				)
				(justify mirror)
			)
		)
		(property "License" "Apache-2.0"
			(at 0 0 -90)
			(unlocked yes)
			(layer "B.Fab")
			(hide yes)
			(effects
				(font
					(size 1 1)
					(thickness 0.15)
				)
				(justify mirror)
			)
		)
		(property "Author" "Antmicro"
			(at 0 0 -90)
			(unlocked yes)
			(layer "B.Fab")
			(hide yes)
			(effects
				(font
					(size 1 1)
					(thickness 0.15)
				)
				(justify mirror)
			)
		)
		(property "Val" "100n"
			(at 0 0 -90)
			(unlocked yes)
			(layer "B.Fab")
			(hide yes)
			(effects
				(font
					(size 1 1)
					(thickness 0.15)
				)
				(justify mirror)
			)
		)
		(property "Voltage" "50V"
			(at 0 0 -90)
			(unlocked yes)
			(layer "B.Fab")
			(hide yes)
			(effects
				(font
					(size 1 1)
					(thickness 0.15)
				)
				(justify mirror)
			)
		)
		(property "Dielectric" "X5R"
			(at 0 0 -90)
			(unlocked yes)
			(layer "B.Fab")
			(hide yes)
			(effects
				(font
					(size 1 1)
					(thickness 0.15)
				)
				(justify mirror)
			)
		)
		(property "Public" "False"
			(at 0 0 -90)
			(unlocked yes)
			(layer "B.Fab")
			(hide yes)
			(effects
				(font
					(size 1 1)
					(thickness 0.15)
				)
				(justify mirror)
			)
		)
		(sheetname "Root")
		(sheetfile "jetson-orin-baseboard-oculink-expansion.kicad_sch")
		(attr smd)
		(fp_rect
			(start -0.925 0.47)
			(end 0.925 -0.47)
			(stroke
				(width 0.05)
				(type default)
			)
			(fill none)
			(layer "B.CrtYd")
		)
		(fp_line
			(start 0.504 -0.248)
			(end 0.504 0.25)
			(stroke
				(width 0.15)
				(type solid)
			)
			(layer "B.Fab")
		)
		(fp_line
			(start -0.494 -0.248)
			(end 0.504 -0.248)
			(stroke
				(width 0.15)
				(type solid)
			)
			(layer "B.Fab")
		)
		(fp_line
			(start 0.504 0.25)
			(end -0.494 0.25)
			(stroke
				(width 0.15)
				(type solid)
			)
			(layer "B.Fab")
		)
		(fp_line
			(start -0.494 0.25)
			(end -0.494 -0.248)
			(stroke
				(width 0.15)
				(type solid)
			)
			(layer "B.Fab")
		)
		(fp_text user "License: Apache-2.0"
			(at -0.939 -5.799 90)
			(layer "B.Fab")
			(hide yes)
			(effects
				(font
					(size 0.7 0.7)
					(thickness 0.15)
				)
				(justify right top mirror)
			)
		)
		(fp_text user "Author: Antmicro"
			(at -0.939 -3.399 90)
			(layer "B.Fab")
			(hide yes)
			(effects
				(font
					(size 0.7 0.7)
					(thickness 0.15)
				)
				(justify right top mirror)
			)
		)
		(fp_text user "${REFERENCE}"
			(at -0.939 -4.599 90)
			(layer "B.Fab")
			(hide yes)
			(effects
				(font
					(size 0.7 0.7)
					(thickness 0.15)
				)
				(justify right top mirror)
			)
		)
		(pad "1" smd roundrect
			(at -0.48 0 90)
			(size 0.59 0.64)
			(layers "B.Cu" "B.Paste" "B.Mask")
			(roundrect_rratio 0.25)
			(net 51 "GND")
			(pintype "passive")
		)
		(pad "2" smd roundrect
			(at 0.48 0 90)
			(size 0.59 0.64)
			(layers "B.Cu" "B.Paste" "B.Mask")
			(roundrect_rratio 0.25)
			(net 23 "+3V3")
			(pintype "passive")
		)
	)
	(footprint "antmicro-footprints:R_0402_1005Metric"
		(layer "B.Cu")
		(at 129.804 123.78775 180)
		(descr "Resistor SMD 0402")
		(tags "resistor SMD 0402")
		(property "Reference" "R30"
			(at -3.326 -0.43225 0)
			(layer "B.SilkS")
			(effects
				(font
					(size 0.7 0.7)
					(thickness 0.15)
				)
				(justify left bottom mirror)
			)
		)
		(property "Value" "R_1k_0402"
			(at -1.011843 -1.772047 0)
			(layer "B.Fab")
			(effects
				(font
					(size 0.7 0.7)
					(thickness 0.15)
				)
				(justify left bottom mirror)
			)
		)
		(property "Footprint" "antmicro-footprints:R_0402_1005Metric"
			(at 0 0 0)
			(layer "B.Fab")
			(hide yes)
			(effects
				(font
					(size 1.27 1.27)
					(thickness 0.15)
				)
				(justify mirror)
			)
		)
		(property "Datasheet" "https://www.bourns.com/docs/product-datasheets/cr.pdf"
			(at 0 0 0)
			(layer "B.Fab")
			(hide yes)
			(effects
				(font
					(size 1.27 1.27)
					(thickness 0.15)
				)
				(justify mirror)
			)
		)
		(property "Description" "SMD Chip Resistor, 1 kohm, ± 1%, 63 mW, 0402 [1005 Metric], Thick Film, General Purpose"
			(at 0 0 0)
			(layer "B.Fab")
			(hide yes)
			(effects
				(font
					(size 1.27 1.27)
					(thickness 0.15)
				)
				(justify mirror)
			)
		)
		(property "MPN" "CR0402-FX-1001GLF"
			(at 0 0 0)
			(unlocked yes)
			(layer "B.Fab")
			(hide yes)
			(effects
				(font
					(size 1 1)
					(thickness 0.15)
				)
				(justify mirror)
			)
		)
		(property "Manufacturer" "Bourns"
			(at 0 0 0)
			(unlocked yes)
			(layer "B.Fab")
			(hide yes)
			(effects
				(font
					(size 1 1)
					(thickness 0.15)
				)
				(justify mirror)
			)
		)
		(property "License" "Apache-2.0"
			(at 0 0 0)
			(unlocked yes)
			(layer "B.Fab")
			(hide yes)
			(effects
				(font
					(size 1 1)
					(thickness 0.15)
				)
				(justify mirror)
			)
		)
		(property "Author" "Antmicro"
			(at 0 0 0)
			(unlocked yes)
			(layer "B.Fab")
			(hide yes)
			(effects
				(font
					(size 1 1)
					(thickness 0.15)
				)
				(justify mirror)
			)
		)
		(property "Val" "1k"
			(at 0 0 0)
			(unlocked yes)
			(layer "B.Fab")
			(hide yes)
			(effects
				(font
					(size 1 1)
					(thickness 0.15)
				)
				(justify mirror)
			)
		)
		(property "Tolerance" "1%"
			(at 0 0 0)
			(unlocked yes)
			(layer "B.Fab")
			(hide yes)
			(effects
				(font
					(size 1 1)
					(thickness 0.15)
				)
				(justify mirror)
			)
		)
		(property "Public" "False"
			(at 0 0 0)
			(unlocked yes)
			(layer "B.Fab")
			(hide yes)
			(effects
				(font
					(size 1 1)
					(thickness 0.15)
				)
				(justify mirror)
			)
		)
		(sheetname "Root")
		(sheetfile "jetson-orin-baseboard-oculink-expansion.kicad_sch")
		(attr smd dnp)
		(fp_rect
			(start -0.925 0.47)
			(end 0.925 -0.47)
			(stroke
				(width 0.05)
				(type default)
			)
			(fill none)
			(layer "B.CrtYd")
		)
		(fp_rect
			(start -0.5 0.25)
			(end 0.5 -0.25)
			(stroke
				(width 0.15)
				(type solid)
			)
			(fill none)
			(layer "B.Fab")
		)
		(fp_text user "License: Apache-2.0"
			(at -0.95 -5.169 0)
			(layer "B.Fab")
			(hide yes)
			(effects
				(font
					(size 0.7 0.7)
					(thickness 0.15)
				)
				(justify left bottom mirror)
			)
		)
		(fp_text user "${REFERENCE}"
			(at -0.95 -3.168 0)
			(layer "B.Fab")
			(hide yes)
			(effects
				(font
					(size 0.7 0.7)
					(thickness 0.15)
				)
				(justify left bottom mirror)
			)
		)
		(fp_text user "Author: Antmicro"
			(at -0.95 -4.169 0)
			(layer "B.Fab")
			(hide yes)
			(effects
				(font
					(size 0.7 0.7)
					(thickness 0.15)
				)
				(justify left bottom mirror)
			)
		)
		(pad "1" smd roundrect
			(at -0.48 0 180)
			(size 0.59 0.64)
			(layers "B.Cu" "B.Paste" "B.Mask")
			(roundrect_rratio 0.25)
			(net 51 "GND")
			(pintype "passive")
		)
		(pad "2" smd roundrect
			(at 0.48 0 180)
			(size 0.59 0.64)
			(layers "B.Cu" "B.Paste" "B.Mask")
			(roundrect_rratio 0.25)
			(net 102 "/TX_SW")
			(pintype "passive")
		)
	)
	(footprint "antmicro-footprints:C_0402_1005Metric"
		(layer "B.Cu")
		(at 125.005 116.687251 -90)
		(descr "Capacitor SMD 0402")
		(tags "capacitor SMD 0402")
		(property "Reference" "C12"
			(at 1.782749 -0.435 90)
			(layer "B.SilkS")
			(effects
				(font
					(size 0.7 0.7)
					(thickness 0.15)
				)
				(justify left bottom mirror)
			)
		)
		(property "Value" "C_100n_0402"
			(at -1.022927 -2.155213 90)
			(layer "B.Fab")
			(effects
				(font
					(size 0.7 0.7)
					(thickness 0.15)
				)
				(justify left bottom mirror)
			)
		)
		(property "Footprint" "antmicro-footprints:C_0402_1005Metric"
			(at 0 0 90)
			(layer "B.Fab")
			(hide yes)
			(effects
				(font
					(size 1.27 1.27)
					(thickness 0.15)
				)
				(justify mirror)
			)
		)
		(property "Datasheet" "https://www.murata.com/products/productdetail?partno=GRM155R61H104KE14%23"
			(at 0 0 90)
			(layer "B.Fab")
			(hide yes)
			(effects
				(font
					(size 1.27 1.27)
					(thickness 0.15)
				)
				(justify mirror)
			)
		)
		(property "Description" "SMD Multilayer Ceramic Capacitor, 0.1 µF, 50 V, 0402 [1005 Metric], ± 10%, X5R, GRM Series"
			(at 0 0 90)
			(layer "B.Fab")
			(hide yes)
			(effects
				(font
					(size 1.27 1.27)
					(thickness 0.15)
				)
				(justify mirror)
			)
		)
		(property "MPN" "GRM155R61H104KE14D"
			(at 0 0 90)
			(unlocked yes)
			(layer "B.Fab")
			(hide yes)
			(effects
				(font
					(size 1 1)
					(thickness 0.15)
				)
				(justify mirror)
			)
		)
		(property "Manufacturer" "Murata"
			(at 0 0 90)
			(unlocked yes)
			(layer "B.Fab")
			(hide yes)
			(effects
				(font
					(size 1 1)
					(thickness 0.15)
				)
				(justify mirror)
			)
		)
		(property "License" "Apache-2.0"
			(at 0 0 90)
			(unlocked yes)
			(layer "B.Fab")
			(hide yes)
			(effects
				(font
					(size 1 1)
					(thickness 0.15)
				)
				(justify mirror)
			)
		)
		(property "Author" "Antmicro"
			(at 0 0 90)
			(unlocked yes)
			(layer "B.Fab")
			(hide yes)
			(effects
				(font
					(size 1 1)
					(thickness 0.15)
				)
				(justify mirror)
			)
		)
		(property "Val" "100n"
			(at 0 0 90)
			(unlocked yes)
			(layer "B.Fab")
			(hide yes)
			(effects
				(font
					(size 1 1)
					(thickness 0.15)
				)
				(justify mirror)
			)
		)
		(property "Voltage" "50V"
			(at 0 0 90)
			(unlocked yes)
			(layer "B.Fab")
			(hide yes)
			(effects
				(font
					(size 1 1)
					(thickness 0.15)
				)
				(justify mirror)
			)
		)
		(property "Dielectric" "X5R"
			(at 0 0 90)
			(unlocked yes)
			(layer "B.Fab")
			(hide yes)
			(effects
				(font
					(size 1 1)
					(thickness 0.15)
				)
				(justify mirror)
			)
		)
		(property "Public" "False"
			(at 0 0 90)
			(unlocked yes)
			(layer "B.Fab")
			(hide yes)
			(effects
				(font
					(size 1 1)
					(thickness 0.15)
				)
				(justify mirror)
			)
		)
		(sheetname "Root")
		(sheetfile "jetson-orin-baseboard-oculink-expansion.kicad_sch")
		(attr smd)
		(fp_rect
			(start -0.925 0.47)
			(end 0.925 -0.47)
			(stroke
				(width 0.05)
				(type default)
			)
			(fill none)
			(layer "B.CrtYd")
		)
		(fp_line
			(start -0.494 0.25)
			(end -0.494 -0.248)
			(stroke
				(width 0.15)
				(type solid)
			)
			(layer "B.Fab")
		)
		(fp_line
			(start 0.504 0.25)
			(end -0.494 0.25)
			(stroke
				(width 0.15)
				(type solid)
			)
			(layer "B.Fab")
		)
		(fp_line
			(start -0.494 -0.248)
			(end 0.504 -0.248)
			(stroke
				(width 0.15)
				(type solid)
			)
			(layer "B.Fab")
		)
		(fp_line
			(start 0.504 -0.248)
			(end 0.504 0.25)
			(stroke
				(width 0.15)
				(type solid)
			)
			(layer "B.Fab")
		)
		(fp_text user "${REFERENCE}"
			(at -0.939 -4.599 90)
			(layer "B.Fab")
			(hide yes)
			(effects
				(font
					(size 0.7 0.7)
					(thickness 0.15)
				)
				(justify left bottom mirror)
			)
		)
		(fp_text user "Author: Antmicro"
			(at -0.939 -3.399 90)
			(layer "B.Fab")
			(hide yes)
			(effects
				(font
					(size 0.7 0.7)
					(thickness 0.15)
				)
				(justify left bottom mirror)
			)
		)
		(fp_text user "License: Apache-2.0"
			(at -0.939 -5.799 90)
			(layer "B.Fab")
			(hide yes)
			(effects
				(font
					(size 0.7 0.7)
					(thickness 0.15)
				)
				(justify left bottom mirror)
			)
		)
		(pad "1" smd roundrect
			(at -0.48 0 270)
			(size 0.59 0.64)
			(layers "B.Cu" "B.Paste" "B.Mask")
			(roundrect_rratio 0.25)
			(net 51 "GND")
			(pintype "passive")
		)
		(pad "2" smd roundrect
			(at 0.48 0 270)
			(size 0.59 0.64)
			(layers "B.Cu" "B.Paste" "B.Mask")
			(roundrect_rratio 0.25)
			(net 23 "+3V3")
			(pintype "passive")
		)
	)
	(footprint "antmicro-footprints:TP_SMD_1.5mm"
		(layer "B.Cu")
		(at 142.4 139.25 90)
		(property "Reference" "TP6"
			(at -8.05568 -1.3 0)
			(layer "B.SilkS")
			(hide yes)
			(effects
				(font
					(size 0.7 0.7)
					(thickness 0.15)
				)
				(justify right top mirror)
			)
		)
		(property "Value" "TP_1.5mm_SMD"
			(at 0.11744 -9.932221 0)
			(layer "B.Fab")
			(effects
				(font
					(size 0.7 0.7)
					(thickness 0.15)
				)
				(justify right top mirror)
			)
		)
		(property "Footprint" "antmicro-footprints:TP_SMD_1.5mm"
			(at 0 0 90)
			(layer "B.Fab")
			(hide yes)
			(effects
				(font
					(size 1.27 1.27)
					(thickness 0.15)
				)
				(justify mirror)
			)
		)
		(property "Description" "test point, SMT"
			(at 0 0 90)
			(layer "B.Fab")
			(hide yes)
			(effects
				(font
					(size 1.27 1.27)
					(thickness 0.15)
				)
				(justify mirror)
			)
		)
		(property "MPN" ""
			(at 0 0 -90)
			(unlocked yes)
			(layer "B.Fab")
			(hide yes)
			(effects
				(font
					(size 1 1)
					(thickness 0.15)
				)
				(justify mirror)
			)
		)
		(property "Manufacturer" ""
			(at 0 0 -90)
			(unlocked yes)
			(layer "B.Fab")
			(hide yes)
			(effects
				(font
					(size 1 1)
					(thickness 0.15)
				)
				(justify mirror)
			)
		)
		(property "Author" "Antmicro"
			(at 0 0 -90)
			(unlocked yes)
			(layer "B.Fab")
			(hide yes)
			(effects
				(font
					(size 1 1)
					(thickness 0.15)
				)
				(justify mirror)
			)
		)
		(property "License" "Apache-2.0"
			(at 0 0 -90)
			(unlocked yes)
			(layer "B.Fab")
			(hide yes)
			(effects
				(font
					(size 1 1)
					(thickness 0.15)
				)
				(justify mirror)
			)
		)
		(sheetname "Root")
		(sheetfile "jetson-orin-baseboard-oculink-expansion.kicad_sch")
		(attr exclude_from_pos_files exclude_from_bom)
		(fp_circle
			(center 0 0)
			(end 0.85 0)
			(stroke
				(width 0.05)
				(type default)
			)
			(fill none)
			(layer "B.CrtYd")
		)
		(fp_text user "License: Apache-2.0"
			(at -0.7 -5.301 90)
			(layer "B.Fab")
			(hide yes)
			(effects
				(font
					(size 0.7 0.7)
					(thickness 0.15)
				)
				(justify right top mirror)
			)
		)
		(fp_text user "${REFERENCE}"
			(at -0.7 -2.9 90)
			(layer "B.Fab")
			(hide yes)
			(effects
				(font
					(size 0.7 0.7)
					(thickness 0.15)
				)
				(justify right top mirror)
			)
		)
		(fp_text user "Author: Antmicro"
			(at -0.7 -4.101 90)
			(layer "B.Fab")
			(hide yes)
			(effects
				(font
					(size 0.7 0.7)
					(thickness 0.15)
				)
				(justify right top mirror)
			)
		)
		(pad "1" smd circle
			(at 0 0 180)
			(size 1.5 1.5)
			(layers "B.Cu" "B.Mask")
			(net 65 "/JOB_GPIO09")
			(pinfunction "1")
			(pintype "passive")
		)
	)
	(footprint "antmicro-footprints:R_0402_1005Metric"
		(layer "B.Cu")
		(at 118.325 111.093751 180)
		(descr "Resistor SMD 0402")
		(tags "resistor SMD 0402")
		(property "Reference" "R10"
			(at -3.255 -0.47725 0)
			(layer "B.SilkS")
			(effects
				(font
					(size 0.7 0.7)
					(thickness 0.15)
				)
				(justify left bottom mirror)
			)
		)
		(property "Value" "R_1k_0402"
			(at -1.011843 -1.772047 0)
			(layer "B.Fab")
			(effects
				(font
					(size 0.7 0.7)
					(thickness 0.15)
				)
				(justify left bottom mirror)
			)
		)
		(property "Footprint" "antmicro-footprints:R_0402_1005Metric"
			(at 0 0 0)
			(layer "B.Fab")
			(hide yes)
			(effects
				(font
					(size 1.27 1.27)
					(thickness 0.15)
				)
				(justify mirror)
			)
		)
		(property "Datasheet" "https://www.bourns.com/docs/product-datasheets/cr.pdf"
			(at 0 0 0)
			(layer "B.Fab")
			(hide yes)
			(effects
				(font
					(size 1.27 1.27)
					(thickness 0.15)
				)
				(justify mirror)
			)
		)
		(property "Description" "SMD Chip Resistor, 1 kohm, ± 1%, 63 mW, 0402 [1005 Metric], Thick Film, General Purpose"
			(at 0 0 0)
			(layer "B.Fab")
			(hide yes)
			(effects
				(font
					(size 1.27 1.27)
					(thickness 0.15)
				)
				(justify mirror)
			)
		)
		(property "MPN" "CR0402-FX-1001GLF"
			(at 0 0 0)
			(unlocked yes)
			(layer "B.Fab")
			(hide yes)
			(effects
				(font
					(size 1 1)
					(thickness 0.15)
				)
				(justify mirror)
			)
		)
		(property "Manufacturer" "Bourns"
			(at 0 0 0)
			(unlocked yes)
			(layer "B.Fab")
			(hide yes)
			(effects
				(font
					(size 1 1)
					(thickness 0.15)
				)
				(justify mirror)
			)
		)
		(property "License" "Apache-2.0"
			(at 0 0 0)
			(unlocked yes)
			(layer "B.Fab")
			(hide yes)
			(effects
				(font
					(size 1 1)
					(thickness 0.15)
				)
				(justify mirror)
			)
		)
		(property "Author" "Antmicro"
			(at 0 0 0)
			(unlocked yes)
			(layer "B.Fab")
			(hide yes)
			(effects
				(font
					(size 1 1)
					(thickness 0.15)
				)
				(justify mirror)
			)
		)
		(property "Val" "1k"
			(at 0 0 0)
			(unlocked yes)
			(layer "B.Fab")
			(hide yes)
			(effects
				(font
					(size 1 1)
					(thickness 0.15)
				)
				(justify mirror)
			)
		)
		(property "Tolerance" "1%"
			(at 0 0 0)
			(unlocked yes)
			(layer "B.Fab")
			(hide yes)
			(effects
				(font
					(size 1 1)
					(thickness 0.15)
				)
				(justify mirror)
			)
		)
		(property "Public" "False"
			(at 0 0 0)
			(unlocked yes)
			(layer "B.Fab")
			(hide yes)
			(effects
				(font
					(size 1 1)
					(thickness 0.15)
				)
				(justify mirror)
			)
		)
		(sheetname "Root")
		(sheetfile "jetson-orin-baseboard-oculink-expansion.kicad_sch")
		(attr smd dnp)
		(fp_rect
			(start -0.925 0.47)
			(end 0.925 -0.47)
			(stroke
				(width 0.05)
				(type default)
			)
			(fill none)
			(layer "B.CrtYd")
		)
		(fp_rect
			(start -0.5 0.25)
			(end 0.5 -0.25)
			(stroke
				(width 0.15)
				(type solid)
			)
			(fill none)
			(layer "B.Fab")
		)
		(fp_text user "Author: Antmicro"
			(at -0.95 -4.169 0)
			(layer "B.Fab")
			(hide yes)
			(effects
				(font
					(size 0.7 0.7)
					(thickness 0.15)
				)
				(justify left bottom mirror)
			)
		)
		(fp_text user "${REFERENCE}"
			(at -0.95 -3.168 0)
			(layer "B.Fab")
			(hide yes)
			(effects
				(font
					(size 0.7 0.7)
					(thickness 0.15)
				)
				(justify left bottom mirror)
			)
		)
		(fp_text user "License: Apache-2.0"
			(at -0.95 -5.169 0)
			(layer "B.Fab")
			(hide yes)
			(effects
				(font
					(size 0.7 0.7)
					(thickness 0.15)
				)
				(justify left bottom mirror)
			)
		)
		(pad "1" smd roundrect
			(at -0.48 0 180)
			(size 0.59 0.64)
			(layers "B.Cu" "B.Paste" "B.Mask")
			(roundrect_rratio 0.25)
			(net 23 "+3V3")
			(pintype "passive")
		)
		(pad "2" smd roundrect
			(at 0.48 0 180)
			(size 0.59 0.64)
			(layers "B.Cu" "B.Paste" "B.Mask")
			(roundrect_rratio 0.25)
			(net 92 "/RX_FG0")
			(pintype "passive")
		)
	)
	(footprint "antmicro-footprints:R_0402_1005Metric"
		(layer "B.Cu")
		(at 116.475 115.313751)
		(descr "Resistor SMD 0402")
		(tags "resistor SMD 0402")
		(property "Reference" "R7"
			(at -2.585 -0.383751 0)
			(layer "B.SilkS")
			(effects
				(font
					(size 0.7 0.7)
					(thickness 0.15)
				)
				(justify right top mirror)
			)
		)
		(property "Value" "R_1k_0402"
			(at -1.011843 -1.772047 0)
			(layer "B.Fab")
			(effects
				(font
					(size 0.7 0.7)
					(thickness 0.15)
				)
				(justify right top mirror)
			)
		)
		(property "Footprint" "antmicro-footprints:R_0402_1005Metric"
			(at 0 0 0)
			(layer "B.Fab")
			(hide yes)
			(effects
				(font
					(size 1.27 1.27)
					(thickness 0.15)
				)
				(justify mirror)
			)
		)
		(property "Datasheet" "https://www.bourns.com/docs/product-datasheets/cr.pdf"
			(at 0 0 0)
			(layer "B.Fab")
			(hide yes)
			(effects
				(font
					(size 1.27 1.27)
					(thickness 0.15)
				)
				(justify mirror)
			)
		)
		(property "Description" "SMD Chip Resistor, 1 kohm, ± 1%, 63 mW, 0402 [1005 Metric], Thick Film, General Purpose"
			(at 0 0 0)
			(layer "B.Fab")
			(hide yes)
			(effects
				(font
					(size 1.27 1.27)
					(thickness 0.15)
				)
				(justify mirror)
			)
		)
		(property "MPN" "CR0402-FX-1001GLF"
			(at 0 0 180)
			(unlocked yes)
			(layer "B.Fab")
			(hide yes)
			(effects
				(font
					(size 1 1)
					(thickness 0.15)
				)
				(justify mirror)
			)
		)
		(property "Manufacturer" "Bourns"
			(at 0 0 180)
			(unlocked yes)
			(layer "B.Fab")
			(hide yes)
			(effects
				(font
					(size 1 1)
					(thickness 0.15)
				)
				(justify mirror)
			)
		)
		(property "License" "Apache-2.0"
			(at 0 0 180)
			(unlocked yes)
			(layer "B.Fab")
			(hide yes)
			(effects
				(font
					(size 1 1)
					(thickness 0.15)
				)
				(justify mirror)
			)
		)
		(property "Author" "Antmicro"
			(at 0 0 180)
			(unlocked yes)
			(layer "B.Fab")
			(hide yes)
			(effects
				(font
					(size 1 1)
					(thickness 0.15)
				)
				(justify mirror)
			)
		)
		(property "Val" "1k"
			(at 0 0 180)
			(unlocked yes)
			(layer "B.Fab")
			(hide yes)
			(effects
				(font
					(size 1 1)
					(thickness 0.15)
				)
				(justify mirror)
			)
		)
		(property "Tolerance" "1%"
			(at 0 0 180)
			(unlocked yes)
			(layer "B.Fab")
			(hide yes)
			(effects
				(font
					(size 1 1)
					(thickness 0.15)
				)
				(justify mirror)
			)
		)
		(property "Public" "False"
			(at 0 0 180)
			(unlocked yes)
			(layer "B.Fab")
			(hide yes)
			(effects
				(font
					(size 1 1)
					(thickness 0.15)
				)
				(justify mirror)
			)
		)
		(sheetname "Root")
		(sheetfile "jetson-orin-baseboard-oculink-expansion.kicad_sch")
		(attr smd dnp)
		(fp_rect
			(start -0.925 0.47)
			(end 0.925 -0.47)
			(stroke
				(width 0.05)
				(type default)
			)
			(fill none)
			(layer "B.CrtYd")
		)
		(fp_rect
			(start -0.5 0.25)
			(end 0.5 -0.25)
			(stroke
				(width 0.15)
				(type solid)
			)
			(fill none)
			(layer "B.Fab")
		)
		(fp_text user "Author: Antmicro"
			(at -0.95 -4.169 0)
			(layer "B.Fab")
			(hide yes)
			(effects
				(font
					(size 0.7 0.7)
					(thickness 0.15)
				)
				(justify right top mirror)
			)
		)
		(fp_text user "License: Apache-2.0"
			(at -0.95 -5.169 0)
			(layer "B.Fab")
			(hide yes)
			(effects
				(font
					(size 0.7 0.7)
					(thickness 0.15)
				)
				(justify right top mirror)
			)
		)
		(fp_text user "${REFERENCE}"
			(at -0.95 -3.168 0)
			(layer "B.Fab")
			(hide yes)
			(effects
				(font
					(size 0.7 0.7)
					(thickness 0.15)
				)
				(justify right top mirror)
			)
		)
		(pad "1" smd roundrect
			(at -0.48 0)
			(size 0.59 0.64)
			(layers "B.Cu" "B.Paste" "B.Mask")
			(roundrect_rratio 0.25)
			(net 51 "GND")
			(pintype "passive")
		)
		(pad "2" smd roundrect
			(at 0.48 0)
			(size 0.59 0.64)
			(layers "B.Cu" "B.Paste" "B.Mask")
			(roundrect_rratio 0.25)
			(net 90 "/RX_EQ1")
			(pintype "passive")
		)
	)
	(footprint "antmicro-footprints:R_0402_1005Metric"
		(layer "B.Cu")
		(at 116.475 116.653751)
		(descr "Resistor SMD 0402")
		(tags "resistor SMD 0402")
		(property "Reference" "R9"
			(at -2.585 -0.383751 0)
			(layer "B.SilkS")
			(effects
				(font
					(size 0.7 0.7)
					(thickness 0.15)
				)
				(justify right top mirror)
			)
		)
		(property "Value" "R_1k_0402"
			(at -1.011843 -1.772047 0)
			(layer "B.Fab")
			(effects
				(font
					(size 0.7 0.7)
					(thickness 0.15)
				)
				(justify right top mirror)
			)
		)
		(property "Footprint" "antmicro-footprints:R_0402_1005Metric"
			(at 0 0 0)
			(layer "B.Fab")
			(hide yes)
			(effects
				(font
					(size 1.27 1.27)
					(thickness 0.15)
				)
				(justify mirror)
			)
		)
		(property "Datasheet" "https://www.bourns.com/docs/product-datasheets/cr.pdf"
			(at 0 0 0)
			(layer "B.Fab")
			(hide yes)
			(effects
				(font
					(size 1.27 1.27)
					(thickness 0.15)
				)
				(justify mirror)
			)
		)
		(property "Description" "SMD Chip Resistor, 1 kohm, ± 1%, 63 mW, 0402 [1005 Metric], Thick Film, General Purpose"
			(at 0 0 0)
			(layer "B.Fab")
			(hide yes)
			(effects
				(font
					(size 1.27 1.27)
					(thickness 0.15)
				)
				(justify mirror)
			)
		)
		(property "MPN" "CR0402-FX-1001GLF"
			(at 0 0 180)
			(unlocked yes)
			(layer "B.Fab")
			(hide yes)
			(effects
				(font
					(size 1 1)
					(thickness 0.15)
				)
				(justify mirror)
			)
		)
		(property "Manufacturer" "Bourns"
			(at 0 0 180)
			(unlocked yes)
			(layer "B.Fab")
			(hide yes)
			(effects
				(font
					(size 1 1)
					(thickness 0.15)
				)
				(justify mirror)
			)
		)
		(property "License" "Apache-2.0"
			(at 0 0 180)
			(unlocked yes)
			(layer "B.Fab")
			(hide yes)
			(effects
				(font
					(size 1 1)
					(thickness 0.15)
				)
				(justify mirror)
			)
		)
		(property "Author" "Antmicro"
			(at 0 0 180)
			(unlocked yes)
			(layer "B.Fab")
			(hide yes)
			(effects
				(font
					(size 1 1)
					(thickness 0.15)
				)
				(justify mirror)
			)
		)
		(property "Val" "1k"
			(at 0 0 180)
			(unlocked yes)
			(layer "B.Fab")
			(hide yes)
			(effects
				(font
					(size 1 1)
					(thickness 0.15)
				)
				(justify mirror)
			)
		)
		(property "Tolerance" "1%"
			(at 0 0 180)
			(unlocked yes)
			(layer "B.Fab")
			(hide yes)
			(effects
				(font
					(size 1 1)
					(thickness 0.15)
				)
				(justify mirror)
			)
		)
		(property "Public" "False"
			(at 0 0 180)
			(unlocked yes)
			(layer "B.Fab")
			(hide yes)
			(effects
				(font
					(size 1 1)
					(thickness 0.15)
				)
				(justify mirror)
			)
		)
		(sheetname "Root")
		(sheetfile "jetson-orin-baseboard-oculink-expansion.kicad_sch")
		(attr smd dnp)
		(fp_rect
			(start -0.925 0.47)
			(end 0.925 -0.47)
			(stroke
				(width 0.05)
				(type default)
			)
			(fill none)
			(layer "B.CrtYd")
		)
		(fp_rect
			(start -0.5 0.25)
			(end 0.5 -0.25)
			(stroke
				(width 0.15)
				(type solid)
			)
			(fill none)
			(layer "B.Fab")
		)
		(fp_text user "License: Apache-2.0"
			(at -0.95 -5.169 0)
			(layer "B.Fab")
			(hide yes)
			(effects
				(font
					(size 0.7 0.7)
					(thickness 0.15)
				)
				(justify right top mirror)
			)
		)
		(fp_text user "Author: Antmicro"
			(at -0.95 -4.169 0)
			(layer "B.Fab")
			(hide yes)
			(effects
				(font
					(size 0.7 0.7)
					(thickness 0.15)
				)
				(justify right top mirror)
			)
		)
		(fp_text user "${REFERENCE}"
			(at -0.95 -3.168 0)
			(layer "B.Fab")
			(hide yes)
			(effects
				(font
					(size 0.7 0.7)
					(thickness 0.15)
				)
				(justify right top mirror)
			)
		)
		(pad "1" smd roundrect
			(at -0.48 0)
			(size 0.59 0.64)
			(layers "B.Cu" "B.Paste" "B.Mask")
			(roundrect_rratio 0.25)
			(net 51 "GND")
			(pintype "passive")
		)
		(pad "2" smd roundrect
			(at 0.48 0)
			(size 0.59 0.64)
			(layers "B.Cu" "B.Paste" "B.Mask")
			(roundrect_rratio 0.25)
			(net 91 "/RX_EQ2")
			(pintype "passive")
		)
	)
	(footprint "antmicro-footprints:R_0402_1005Metric"
		(layer "B.Cu")
		(at 118.325 115.313751 180)
		(descr "Resistor SMD 0402")
		(tags "resistor SMD 0402")
		(property "Reference" "R6"
			(at -2.588333 -0.47725 0)
			(layer "B.SilkS")
			(effects
				(font
					(size 0.7 0.7)
					(thickness 0.15)
				)
				(justify left bottom mirror)
			)
		)
		(property "Value" "R_1k_0402"
			(at -1.011843 -1.772047 0)
			(layer "B.Fab")
			(effects
				(font
					(size 0.7 0.7)
					(thickness 0.15)
				)
				(justify left bottom mirror)
			)
		)
		(property "Footprint" "antmicro-footprints:R_0402_1005Metric"
			(at 0 0 0)
			(layer "B.Fab")
			(hide yes)
			(effects
				(font
					(size 1.27 1.27)
					(thickness 0.15)
				)
				(justify mirror)
			)
		)
		(property "Datasheet" "https://www.bourns.com/docs/product-datasheets/cr.pdf"
			(at 0 0 0)
			(layer "B.Fab")
			(hide yes)
			(effects
				(font
					(size 1.27 1.27)
					(thickness 0.15)
				)
				(justify mirror)
			)
		)
		(property "Description" "SMD Chip Resistor, 1 kohm, ± 1%, 63 mW, 0402 [1005 Metric], Thick Film, General Purpose"
			(at 0 0 0)
			(layer "B.Fab")
			(hide yes)
			(effects
				(font
					(size 1.27 1.27)
					(thickness 0.15)
				)
				(justify mirror)
			)
		)
		(property "MPN" "CR0402-FX-1001GLF"
			(at 0 0 0)
			(unlocked yes)
			(layer "B.Fab")
			(hide yes)
			(effects
				(font
					(size 1 1)
					(thickness 0.15)
				)
				(justify mirror)
			)
		)
		(property "Manufacturer" "Bourns"
			(at 0 0 0)
			(unlocked yes)
			(layer "B.Fab")
			(hide yes)
			(effects
				(font
					(size 1 1)
					(thickness 0.15)
				)
				(justify mirror)
			)
		)
		(property "License" "Apache-2.0"
			(at 0 0 0)
			(unlocked yes)
			(layer "B.Fab")
			(hide yes)
			(effects
				(font
					(size 1 1)
					(thickness 0.15)
				)
				(justify mirror)
			)
		)
		(property "Author" "Antmicro"
			(at 0 0 0)
			(unlocked yes)
			(layer "B.Fab")
			(hide yes)
			(effects
				(font
					(size 1 1)
					(thickness 0.15)
				)
				(justify mirror)
			)
		)
		(property "Val" "1k"
			(at 0 0 0)
			(unlocked yes)
			(layer "B.Fab")
			(hide yes)
			(effects
				(font
					(size 1 1)
					(thickness 0.15)
				)
				(justify mirror)
			)
		)
		(property "Tolerance" "1%"
			(at 0 0 0)
			(unlocked yes)
			(layer "B.Fab")
			(hide yes)
			(effects
				(font
					(size 1 1)
					(thickness 0.15)
				)
				(justify mirror)
			)
		)
		(property "Public" "False"
			(at 0 0 0)
			(unlocked yes)
			(layer "B.Fab")
			(hide yes)
			(effects
				(font
					(size 1 1)
					(thickness 0.15)
				)
				(justify mirror)
			)
		)
		(sheetname "Root")
		(sheetfile "jetson-orin-baseboard-oculink-expansion.kicad_sch")
		(attr smd)
		(fp_rect
			(start -0.925 0.47)
			(end 0.925 -0.47)
			(stroke
				(width 0.05)
				(type default)
			)
			(fill none)
			(layer "B.CrtYd")
		)
		(fp_rect
			(start -0.5 0.25)
			(end 0.5 -0.25)
			(stroke
				(width 0.15)
				(type solid)
			)
			(fill none)
			(layer "B.Fab")
		)
		(fp_text user "${REFERENCE}"
			(at -0.95 -3.168 0)
			(layer "B.Fab")
			(hide yes)
			(effects
				(font
					(size 0.7 0.7)
					(thickness 0.15)
				)
				(justify left bottom mirror)
			)
		)
		(fp_text user "License: Apache-2.0"
			(at -0.95 -5.169 0)
			(layer "B.Fab")
			(hide yes)
			(effects
				(font
					(size 0.7 0.7)
					(thickness 0.15)
				)
				(justify left bottom mirror)
			)
		)
		(fp_text user "Author: Antmicro"
			(at -0.95 -4.169 0)
			(layer "B.Fab")
			(hide yes)
			(effects
				(font
					(size 0.7 0.7)
					(thickness 0.15)
				)
				(justify left bottom mirror)
			)
		)
		(pad "1" smd roundrect
			(at -0.48 0 180)
			(size 0.59 0.64)
			(layers "B.Cu" "B.Paste" "B.Mask")
			(roundrect_rratio 0.25)
			(net 23 "+3V3")
			(pintype "passive")
		)
		(pad "2" smd roundrect
			(at 0.48 0 180)
			(size 0.59 0.64)
			(layers "B.Cu" "B.Paste" "B.Mask")
			(roundrect_rratio 0.25)
			(net 90 "/RX_EQ1")
			(pintype "passive")
		)
	)
	(footprint "antmicro-footprints:C_0402_1005Metric"
		(layer "B.Cu")
		(at 121.275 127.913 -90)
		(descr "Capacitor SMD 0402")
		(tags "capacitor SMD 0402")
		(property "Reference" "C21"
			(at 1.627 -0.465 90)
			(layer "B.SilkS")
			(effects
				(font
					(size 0.7 0.7)
					(thickness 0.15)
				)
				(justify left bottom mirror)
			)
		)
		(property "Value" "C_100n_0402"
			(at -1.022927 -2.155213 90)
			(layer "B.Fab")
			(effects
				(font
					(size 0.7 0.7)
					(thickness 0.15)
				)
				(justify left bottom mirror)
			)
		)
		(property "Footprint" "antmicro-footprints:C_0402_1005Metric"
			(at 0 0 90)
			(layer "B.Fab")
			(hide yes)
			(effects
				(font
					(size 1.27 1.27)
					(thickness 0.15)
				)
				(justify mirror)
			)
		)
		(property "Datasheet" "https://www.murata.com/products/productdetail?partno=GRM155R61H104KE14%23"
			(at 0 0 90)
			(layer "B.Fab")
			(hide yes)
			(effects
				(font
					(size 1.27 1.27)
					(thickness 0.15)
				)
				(justify mirror)
			)
		)
		(property "Description" "SMD Multilayer Ceramic Capacitor, 0.1 µF, 50 V, 0402 [1005 Metric], ± 10%, X5R, GRM Series"
			(at 0 0 90)
			(layer "B.Fab")
			(hide yes)
			(effects
				(font
					(size 1.27 1.27)
					(thickness 0.15)
				)
				(justify mirror)
			)
		)
		(property "MPN" "GRM155R61H104KE14D"
			(at 0 0 90)
			(unlocked yes)
			(layer "B.Fab")
			(hide yes)
			(effects
				(font
					(size 1 1)
					(thickness 0.15)
				)
				(justify mirror)
			)
		)
		(property "Manufacturer" "Murata"
			(at 0 0 90)
			(unlocked yes)
			(layer "B.Fab")
			(hide yes)
			(effects
				(font
					(size 1 1)
					(thickness 0.15)
				)
				(justify mirror)
			)
		)
		(property "License" "Apache-2.0"
			(at 0 0 90)
			(unlocked yes)
			(layer "B.Fab")
			(hide yes)
			(effects
				(font
					(size 1 1)
					(thickness 0.15)
				)
				(justify mirror)
			)
		)
		(property "Author" "Antmicro"
			(at 0 0 90)
			(unlocked yes)
			(layer "B.Fab")
			(hide yes)
			(effects
				(font
					(size 1 1)
					(thickness 0.15)
				)
				(justify mirror)
			)
		)
		(property "Val" "100n"
			(at 0 0 90)
			(unlocked yes)
			(layer "B.Fab")
			(hide yes)
			(effects
				(font
					(size 1 1)
					(thickness 0.15)
				)
				(justify mirror)
			)
		)
		(property "Voltage" "50V"
			(at 0 0 90)
			(unlocked yes)
			(layer "B.Fab")
			(hide yes)
			(effects
				(font
					(size 1 1)
					(thickness 0.15)
				)
				(justify mirror)
			)
		)
		(property "Dielectric" "X5R"
			(at 0 0 90)
			(unlocked yes)
			(layer "B.Fab")
			(hide yes)
			(effects
				(font
					(size 1 1)
					(thickness 0.15)
				)
				(justify mirror)
			)
		)
		(property "Public" "False"
			(at 0 0 90)
			(unlocked yes)
			(layer "B.Fab")
			(hide yes)
			(effects
				(font
					(size 1 1)
					(thickness 0.15)
				)
				(justify mirror)
			)
		)
		(sheetname "Root")
		(sheetfile "jetson-orin-baseboard-oculink-expansion.kicad_sch")
		(attr smd)
		(fp_rect
			(start -0.925 0.47)
			(end 0.925 -0.47)
			(stroke
				(width 0.05)
				(type default)
			)
			(fill none)
			(layer "B.CrtYd")
		)
		(fp_line
			(start -0.494 0.25)
			(end -0.494 -0.248)
			(stroke
				(width 0.15)
				(type solid)
			)
			(layer "B.Fab")
		)
		(fp_line
			(start 0.504 0.25)
			(end -0.494 0.25)
			(stroke
				(width 0.15)
				(type solid)
			)
			(layer "B.Fab")
		)
		(fp_line
			(start -0.494 -0.248)
			(end 0.504 -0.248)
			(stroke
				(width 0.15)
				(type solid)
			)
			(layer "B.Fab")
		)
		(fp_line
			(start 0.504 -0.248)
			(end 0.504 0.25)
			(stroke
				(width 0.15)
				(type solid)
			)
			(layer "B.Fab")
		)
		(fp_text user "License: Apache-2.0"
			(at -0.939 -5.799 90)
			(layer "B.Fab")
			(hide yes)
			(effects
				(font
					(size 0.7 0.7)
					(thickness 0.15)
				)
				(justify left bottom mirror)
			)
		)
		(fp_text user "${REFERENCE}"
			(at -0.939 -4.599 90)
			(layer "B.Fab")
			(hide yes)
			(effects
				(font
					(size 0.7 0.7)
					(thickness 0.15)
				)
				(justify left bottom mirror)
			)
		)
		(fp_text user "Author: Antmicro"
			(at -0.939 -3.399 90)
			(layer "B.Fab")
			(hide yes)
			(effects
				(font
					(size 0.7 0.7)
					(thickness 0.15)
				)
				(justify left bottom mirror)
			)
		)
		(pad "1" smd roundrect
			(at -0.48 0 270)
			(size 0.59 0.64)
			(layers "B.Cu" "B.Paste" "B.Mask")
			(roundrect_rratio 0.25)
			(net 51 "GND")
			(pintype "passive")
		)
		(pad "2" smd roundrect
			(at 0.48 0 270)
			(size 0.59 0.64)
			(layers "B.Cu" "B.Paste" "B.Mask")
			(roundrect_rratio 0.25)
			(net 23 "+3V3")
			(pintype "passive")
		)
	)
	(footprint "antmicro-footprints:R_0402_1005Metric"
		(layer "B.Cu")
		(at 118.325 112.433751 180)
		(descr "Resistor SMD 0402")
		(tags "resistor SMD 0402")
		(property "Reference" "R12"
			(at -3.255 -0.47725 0)
			(layer "B.SilkS")
			(effects
				(font
					(size 0.7 0.7)
					(thickness 0.15)
				)
				(justify left bottom mirror)
			)
		)
		(property "Value" "R_1k_0402"
			(at -1.011843 -1.772047 0)
			(layer "B.Fab")
			(effects
				(font
					(size 0.7 0.7)
					(thickness 0.15)
				)
				(justify left bottom mirror)
			)
		)
		(property "Footprint" "antmicro-footprints:R_0402_1005Metric"
			(at 0 0 0)
			(layer "B.Fab")
			(hide yes)
			(effects
				(font
					(size 1.27 1.27)
					(thickness 0.15)
				)
				(justify mirror)
			)
		)
		(property "Datasheet" "https://www.bourns.com/docs/product-datasheets/cr.pdf"
			(at 0 0 0)
			(layer "B.Fab")
			(hide yes)
			(effects
				(font
					(size 1.27 1.27)
					(thickness 0.15)
				)
				(justify mirror)
			)
		)
		(property "Description" "SMD Chip Resistor, 1 kohm, ± 1%, 63 mW, 0402 [1005 Metric], Thick Film, General Purpose"
			(at 0 0 0)
			(layer "B.Fab")
			(hide yes)
			(effects
				(font
					(size 1.27 1.27)
					(thickness 0.15)
				)
				(justify mirror)
			)
		)
		(property "MPN" "CR0402-FX-1001GLF"
			(at 0 0 0)
			(unlocked yes)
			(layer "B.Fab")
			(hide yes)
			(effects
				(font
					(size 1 1)
					(thickness 0.15)
				)
				(justify mirror)
			)
		)
		(property "Manufacturer" "Bourns"
			(at 0 0 0)
			(unlocked yes)
			(layer "B.Fab")
			(hide yes)
			(effects
				(font
					(size 1 1)
					(thickness 0.15)
				)
				(justify mirror)
			)
		)
		(property "License" "Apache-2.0"
			(at 0 0 0)
			(unlocked yes)
			(layer "B.Fab")
			(hide yes)
			(effects
				(font
					(size 1 1)
					(thickness 0.15)
				)
				(justify mirror)
			)
		)
		(property "Author" "Antmicro"
			(at 0 0 0)
			(unlocked yes)
			(layer "B.Fab")
			(hide yes)
			(effects
				(font
					(size 1 1)
					(thickness 0.15)
				)
				(justify mirror)
			)
		)
		(property "Val" "1k"
			(at 0 0 0)
			(unlocked yes)
			(layer "B.Fab")
			(hide yes)
			(effects
				(font
					(size 1 1)
					(thickness 0.15)
				)
				(justify mirror)
			)
		)
		(property "Tolerance" "1%"
			(at 0 0 0)
			(unlocked yes)
			(layer "B.Fab")
			(hide yes)
			(effects
				(font
					(size 1 1)
					(thickness 0.15)
				)
				(justify mirror)
			)
		)
		(property "Public" "False"
			(at 0 0 0)
			(unlocked yes)
			(layer "B.Fab")
			(hide yes)
			(effects
				(font
					(size 1 1)
					(thickness 0.15)
				)
				(justify mirror)
			)
		)
		(sheetname "Root")
		(sheetfile "jetson-orin-baseboard-oculink-expansion.kicad_sch")
		(attr smd)
		(fp_rect
			(start -0.925 0.47)
			(end 0.925 -0.47)
			(stroke
				(width 0.05)
				(type default)
			)
			(fill none)
			(layer "B.CrtYd")
		)
		(fp_rect
			(start -0.5 0.25)
			(end 0.5 -0.25)
			(stroke
				(width 0.15)
				(type solid)
			)
			(fill none)
			(layer "B.Fab")
		)
		(fp_text user "Author: Antmicro"
			(at -0.95 -4.169 0)
			(layer "B.Fab")
			(hide yes)
			(effects
				(font
					(size 0.7 0.7)
					(thickness 0.15)
				)
				(justify left bottom mirror)
			)
		)
		(fp_text user "${REFERENCE}"
			(at -0.95 -3.168 0)
			(layer "B.Fab")
			(hide yes)
			(effects
				(font
					(size 0.7 0.7)
					(thickness 0.15)
				)
				(justify left bottom mirror)
			)
		)
		(fp_text user "License: Apache-2.0"
			(at -0.95 -5.169 0)
			(layer "B.Fab")
			(hide yes)
			(effects
				(font
					(size 0.7 0.7)
					(thickness 0.15)
				)
				(justify left bottom mirror)
			)
		)
		(pad "1" smd roundrect
			(at -0.48 0 180)
			(size 0.59 0.64)
			(layers "B.Cu" "B.Paste" "B.Mask")
			(roundrect_rratio 0.25)
			(net 23 "+3V3")
			(pintype "passive")
		)
		(pad "2" smd roundrect
			(at 0.48 0 180)
			(size 0.59 0.64)
			(layers "B.Cu" "B.Paste" "B.Mask")
			(roundrect_rratio 0.25)
			(net 93 "/RX_FG1")
			(pintype "passive")
		)
	)
	(footprint "antmicro-footprints:R_0402_1005Metric"
		(layer "B.Cu")
		(at 127.944 126.66775)
		(descr "Resistor SMD 0402")
		(tags "resistor SMD 0402")
		(property "Reference" "R21"
			(at -3.274 -0.37775 0)
			(layer "B.SilkS")
			(effects
				(font
					(size 0.7 0.7)
					(thickness 0.15)
				)
				(justify right top mirror)
			)
		)
		(property "Value" "R_1k_0402"
			(at -1.011843 -1.772047 0)
			(layer "B.Fab")
			(effects
				(font
					(size 0.7 0.7)
					(thickness 0.15)
				)
				(justify right top mirror)
			)
		)
		(property "Footprint" "antmicro-footprints:R_0402_1005Metric"
			(at 0 0 0)
			(layer "B.Fab")
			(hide yes)
			(effects
				(font
					(size 1.27 1.27)
					(thickness 0.15)
				)
				(justify mirror)
			)
		)
		(property "Datasheet" "https://www.bourns.com/docs/product-datasheets/cr.pdf"
			(at 0 0 0)
			(layer "B.Fab")
			(hide yes)
			(effects
				(font
					(size 1.27 1.27)
					(thickness 0.15)
				)
				(justify mirror)
			)
		)
		(property "Description" "SMD Chip Resistor, 1 kohm, ± 1%, 63 mW, 0402 [1005 Metric], Thick Film, General Purpose"
			(at 0 0 0)
			(layer "B.Fab")
			(hide yes)
			(effects
				(font
					(size 1.27 1.27)
					(thickness 0.15)
				)
				(justify mirror)
			)
		)
		(property "MPN" "CR0402-FX-1001GLF"
			(at 0 0 180)
			(unlocked yes)
			(layer "B.Fab")
			(hide yes)
			(effects
				(font
					(size 1 1)
					(thickness 0.15)
				)
				(justify mirror)
			)
		)
		(property "Manufacturer" "Bourns"
			(at 0 0 180)
			(unlocked yes)
			(layer "B.Fab")
			(hide yes)
			(effects
				(font
					(size 1 1)
					(thickness 0.15)
				)
				(justify mirror)
			)
		)
		(property "License" "Apache-2.0"
			(at 0 0 180)
			(unlocked yes)
			(layer "B.Fab")
			(hide yes)
			(effects
				(font
					(size 1 1)
					(thickness 0.15)
				)
				(justify mirror)
			)
		)
		(property "Author" "Antmicro"
			(at 0 0 180)
			(unlocked yes)
			(layer "B.Fab")
			(hide yes)
			(effects
				(font
					(size 1 1)
					(thickness 0.15)
				)
				(justify mirror)
			)
		)
		(property "Val" "1k"
			(at 0 0 180)
			(unlocked yes)
			(layer "B.Fab")
			(hide yes)
			(effects
				(font
					(size 1 1)
					(thickness 0.15)
				)
				(justify mirror)
			)
		)
		(property "Tolerance" "1%"
			(at 0 0 180)
			(unlocked yes)
			(layer "B.Fab")
			(hide yes)
			(effects
				(font
					(size 1 1)
					(thickness 0.15)
				)
				(justify mirror)
			)
		)
		(property "Public" "False"
			(at 0 0 180)
			(unlocked yes)
			(layer "B.Fab")
			(hide yes)
			(effects
				(font
					(size 1 1)
					(thickness 0.15)
				)
				(justify mirror)
			)
		)
		(sheetname "Root")
		(sheetfile "jetson-orin-baseboard-oculink-expansion.kicad_sch")
		(attr smd)
		(fp_rect
			(start -0.925 0.47)
			(end 0.925 -0.47)
			(stroke
				(width 0.05)
				(type default)
			)
			(fill none)
			(layer "B.CrtYd")
		)
		(fp_rect
			(start -0.5 0.25)
			(end 0.5 -0.25)
			(stroke
				(width 0.15)
				(type solid)
			)
			(fill none)
			(layer "B.Fab")
		)
		(fp_text user "${REFERENCE}"
			(at -0.95 -3.168 0)
			(layer "B.Fab")
			(hide yes)
			(effects
				(font
					(size 0.7 0.7)
					(thickness 0.15)
				)
				(justify right top mirror)
			)
		)
		(fp_text user "Author: Antmicro"
			(at -0.95 -4.169 0)
			(layer "B.Fab")
			(hide yes)
			(effects
				(font
					(size 0.7 0.7)
					(thickness 0.15)
				)
				(justify right top mirror)
			)
		)
		(fp_text user "License: Apache-2.0"
			(at -0.95 -5.169 0)
			(layer "B.Fab")
			(hide yes)
			(effects
				(font
					(size 0.7 0.7)
					(thickness 0.15)
				)
				(justify right top mirror)
			)
		)
		(pad "1" smd roundrect
			(at -0.48 0)
			(size 0.59 0.64)
			(layers "B.Cu" "B.Paste" "B.Mask")
			(roundrect_rratio 0.25)
			(net 23 "+3V3")
			(pintype "passive")
		)
		(pad "2" smd roundrect
			(at 0.48 0)
			(size 0.59 0.64)
			(layers "B.Cu" "B.Paste" "B.Mask")
			(roundrect_rratio 0.25)
			(net 98 "/TX_EQ1")
			(pintype "passive")
		)
	)
	(footprint "antmicro-footprints:R_0402_1005Metric"
		(layer "B.Cu")
		(at 116.475 111.093751)
		(descr "Resistor SMD 0402")
		(tags "resistor SMD 0402")
		(property "Reference" "R11"
			(at -3.251667 -0.383751 0)
			(layer "B.SilkS")
			(effects
				(font
					(size 0.7 0.7)
					(thickness 0.15)
				)
				(justify right top mirror)
			)
		)
		(property "Value" "R_1k_0402"
			(at -1.011843 -1.772047 0)
			(layer "B.Fab")
			(effects
				(font
					(size 0.7 0.7)
					(thickness 0.15)
				)
				(justify right top mirror)
			)
		)
		(property "Footprint" "antmicro-footprints:R_0402_1005Metric"
			(at 0 0 0)
			(layer "B.Fab")
			(hide yes)
			(effects
				(font
					(size 1.27 1.27)
					(thickness 0.15)
				)
				(justify mirror)
			)
		)
		(property "Datasheet" "https://www.bourns.com/docs/product-datasheets/cr.pdf"
			(at 0 0 0)
			(layer "B.Fab")
			(hide yes)
			(effects
				(font
					(size 1.27 1.27)
					(thickness 0.15)
				)
				(justify mirror)
			)
		)
		(property "Description" "SMD Chip Resistor, 1 kohm, ± 1%, 63 mW, 0402 [1005 Metric], Thick Film, General Purpose"
			(at 0 0 0)
			(layer "B.Fab")
			(hide yes)
			(effects
				(font
					(size 1.27 1.27)
					(thickness 0.15)
				)
				(justify mirror)
			)
		)
		(property "MPN" "CR0402-FX-1001GLF"
			(at 0 0 180)
			(unlocked yes)
			(layer "B.Fab")
			(hide yes)
			(effects
				(font
					(size 1 1)
					(thickness 0.15)
				)
				(justify mirror)
			)
		)
		(property "Manufacturer" "Bourns"
			(at 0 0 180)
			(unlocked yes)
			(layer "B.Fab")
			(hide yes)
			(effects
				(font
					(size 1 1)
					(thickness 0.15)
				)
				(justify mirror)
			)
		)
		(property "License" "Apache-2.0"
			(at 0 0 180)
			(unlocked yes)
			(layer "B.Fab")
			(hide yes)
			(effects
				(font
					(size 1 1)
					(thickness 0.15)
				)
				(justify mirror)
			)
		)
		(property "Author" "Antmicro"
			(at 0 0 180)
			(unlocked yes)
			(layer "B.Fab")
			(hide yes)
			(effects
				(font
					(size 1 1)
					(thickness 0.15)
				)
				(justify mirror)
			)
		)
		(property "Val" "1k"
			(at 0 0 180)
			(unlocked yes)
			(layer "B.Fab")
			(hide yes)
			(effects
				(font
					(size 1 1)
					(thickness 0.15)
				)
				(justify mirror)
			)
		)
		(property "Tolerance" "1%"
			(at 0 0 180)
			(unlocked yes)
			(layer "B.Fab")
			(hide yes)
			(effects
				(font
					(size 1 1)
					(thickness 0.15)
				)
				(justify mirror)
			)
		)
		(property "Public" "False"
			(at 0 0 180)
			(unlocked yes)
			(layer "B.Fab")
			(hide yes)
			(effects
				(font
					(size 1 1)
					(thickness 0.15)
				)
				(justify mirror)
			)
		)
		(sheetname "Root")
		(sheetfile "jetson-orin-baseboard-oculink-expansion.kicad_sch")
		(attr smd)
		(fp_rect
			(start -0.925 0.47)
			(end 0.925 -0.47)
			(stroke
				(width 0.05)
				(type default)
			)
			(fill none)
			(layer "B.CrtYd")
		)
		(fp_rect
			(start -0.5 0.25)
			(end 0.5 -0.25)
			(stroke
				(width 0.15)
				(type solid)
			)
			(fill none)
			(layer "B.Fab")
		)
		(fp_text user "${REFERENCE}"
			(at -0.95 -3.168 0)
			(layer "B.Fab")
			(hide yes)
			(effects
				(font
					(size 0.7 0.7)
					(thickness 0.15)
				)
				(justify right top mirror)
			)
		)
		(fp_text user "License: Apache-2.0"
			(at -0.95 -5.169 0)
			(layer "B.Fab")
			(hide yes)
			(effects
				(font
					(size 0.7 0.7)
					(thickness 0.15)
				)
				(justify right top mirror)
			)
		)
		(fp_text user "Author: Antmicro"
			(at -0.95 -4.169 0)
			(layer "B.Fab")
			(hide yes)
			(effects
				(font
					(size 0.7 0.7)
					(thickness 0.15)
				)
				(justify right top mirror)
			)
		)
		(pad "1" smd roundrect
			(at -0.48 0)
			(size 0.59 0.64)
			(layers "B.Cu" "B.Paste" "B.Mask")
			(roundrect_rratio 0.25)
			(net 51 "GND")
			(pintype "passive")
		)
		(pad "2" smd roundrect
			(at 0.48 0)
			(size 0.59 0.64)
			(layers "B.Cu" "B.Paste" "B.Mask")
			(roundrect_rratio 0.25)
			(net 92 "/RX_FG0")
			(pintype "passive")
		)
	)
	(footprint "antmicro-footprints:TP_SMD_1.5mm"
		(layer "B.Cu")
		(at 142.4 131.231062 180)
		(property "Reference" "TP8"
			(at -0.8 -12.588398 180)
			(layer "B.SilkS")
			(hide yes)
			(effects
				(font
					(size 0.7 0.7)
					(thickness 0.15)
				)
				(justify left bottom mirror)
			)
		)
		(property "Value" "TP_1.5mm_SMD"
			(at 1.438222 -0.794949 0)
			(layer "B.Fab")
			(effects
				(font
					(size 0.7 0.7)
					(thickness 0.15)
				)
				(justify left bottom mirror)
			)
		)
		(property "Footprint" "antmicro-footprints:TP_SMD_1.5mm"
			(at 0 0 0)
			(layer "B.Fab")
			(hide yes)
			(effects
				(font
					(size 1.27 1.27)
					(thickness 0.15)
				)
				(justify mirror)
			)
		)
		(property "Description" "test point, SMT"
			(at 0 0 0)
			(layer "B.Fab")
			(hide yes)
			(effects
				(font
					(size 1.27 1.27)
					(thickness 0.15)
				)
				(justify mirror)
			)
		)
		(property "MPN" ""
			(at 0 0 0)
			(unlocked yes)
			(layer "B.Fab")
			(hide yes)
			(effects
				(font
					(size 1 1)
					(thickness 0.15)
				)
				(justify mirror)
			)
		)
		(property "Manufacturer" ""
			(at 0 0 0)
			(unlocked yes)
			(layer "B.Fab")
			(hide yes)
			(effects
				(font
					(size 1 1)
					(thickness 0.15)
				)
				(justify mirror)
			)
		)
		(property "Author" "Antmicro"
			(at 0 0 0)
			(unlocked yes)
			(layer "B.Fab")
			(hide yes)
			(effects
				(font
					(size 1 1)
					(thickness 0.15)
				)
				(justify mirror)
			)
		)
		(property "License" "Apache-2.0"
			(at 0 0 0)
			(unlocked yes)
			(layer "B.Fab")
			(hide yes)
			(effects
				(font
					(size 1 1)
					(thickness 0.15)
				)
				(justify mirror)
			)
		)
		(sheetname "Root")
		(sheetfile "jetson-orin-baseboard-oculink-expansion.kicad_sch")
		(attr exclude_from_pos_files exclude_from_bom)
		(fp_circle
			(center 0 0)
			(end 0.85 0)
			(stroke
				(width 0.05)
				(type default)
			)
			(fill none)
			(layer "B.CrtYd")
		)
		(fp_text user "License: Apache-2.0"
			(at -0.7 -5.301 0)
			(layer "B.Fab")
			(hide yes)
			(effects
				(font
					(size 0.7 0.7)
					(thickness 0.15)
				)
				(justify left bottom mirror)
			)
		)
		(fp_text user "${REFERENCE}"
			(at -0.7 -2.9 0)
			(layer "B.Fab")
			(hide yes)
			(effects
				(font
					(size 0.7 0.7)
					(thickness 0.15)
				)
				(justify left bottom mirror)
			)
		)
		(fp_text user "Author: Antmicro"
			(at -0.7 -4.101 0)
			(layer "B.Fab")
			(hide yes)
			(effects
				(font
					(size 0.7 0.7)
					(thickness 0.15)
				)
				(justify left bottom mirror)
			)
		)
		(pad "1" smd circle
			(at 0 0 270)
			(size 1.5 1.5)
			(layers "B.Cu" "B.Mask")
			(net 23 "+3V3")
			(pinfunction "1")
			(pintype "passive")
		)
	)
	(footprint "antmicro-footprints:R_0402_1005Metric"
		(layer "B.Cu")
		(at 129.72 112.85)
		(descr "Resistor SMD 0402")
		(tags "resistor SMD 0402")
		(property "Reference" "R39"
			(at 0.66 -0.356249 0)
			(layer "B.SilkS")
			(effects
				(font
					(size 0.7 0.7)
					(thickness 0.15)
				)
				(justify right top mirror)
			)
		)
		(property "Value" "R_0R_0402"
			(at -1.011843 -1.772047 0)
			(layer "B.Fab")
			(effects
				(font
					(size 0.7 0.7)
					(thickness 0.15)
				)
				(justify right top mirror)
			)
		)
		(property "Footprint" "antmicro-footprints:R_0402_1005Metric"
			(at 0 0 0)
			(layer "B.Fab")
			(hide yes)
			(effects
				(font
					(size 1.27 1.27)
					(thickness 0.15)
				)
				(justify mirror)
			)
		)
		(property "Datasheet" "https://industrial.panasonic.com/cdbs/www-data/pdf/RDA0000/AOA0000C301.pdf"
			(at 0 0 0)
			(layer "B.Fab")
			(hide yes)
			(effects
				(font
					(size 1.27 1.27)
					(thickness 0.15)
				)
				(justify mirror)
			)
		)
		(property "Description" "SMD Chip Resistor, Jumper, 0 ohm, 100 mW, 0402 [1005 Metric], Thick Film, General Purpose"
			(at 0 0 0)
			(layer "B.Fab")
			(hide yes)
			(effects
				(font
					(size 1.27 1.27)
					(thickness 0.15)
				)
				(justify mirror)
			)
		)
		(property "MPN" "ERJ2GE0R00X"
			(at 0 0 180)
			(unlocked yes)
			(layer "B.Fab")
			(hide yes)
			(effects
				(font
					(size 1 1)
					(thickness 0.15)
				)
				(justify mirror)
			)
		)
		(property "Manufacturer" "Panasonic"
			(at 0 0 180)
			(unlocked yes)
			(layer "B.Fab")
			(hide yes)
			(effects
				(font
					(size 1 1)
					(thickness 0.15)
				)
				(justify mirror)
			)
		)
		(property "License" "Apache-2.0"
			(at 0 0 180)
			(unlocked yes)
			(layer "B.Fab")
			(hide yes)
			(effects
				(font
					(size 1 1)
					(thickness 0.15)
				)
				(justify mirror)
			)
		)
		(property "Author" "Antmicro"
			(at 0 0 180)
			(unlocked yes)
			(layer "B.Fab")
			(hide yes)
			(effects
				(font
					(size 1 1)
					(thickness 0.15)
				)
				(justify mirror)
			)
		)
		(property "Val" "0R"
			(at 0 0 180)
			(unlocked yes)
			(layer "B.Fab")
			(hide yes)
			(effects
				(font
					(size 1 1)
					(thickness 0.15)
				)
				(justify mirror)
			)
		)
		(property "Tolerance" ""
			(at 0 0 180)
			(unlocked yes)
			(layer "B.Fab")
			(hide yes)
			(effects
				(font
					(size 1 1)
					(thickness 0.15)
				)
				(justify mirror)
			)
		)
		(property "Current" "1A"
			(at 0 0 180)
			(unlocked yes)
			(layer "B.Fab")
			(hide yes)
			(effects
				(font
					(size 1 1)
					(thickness 0.15)
				)
				(justify mirror)
			)
		)
		(property "Public" "False"
			(at 0 0 180)
			(unlocked yes)
			(layer "B.Fab")
			(hide yes)
			(effects
				(font
					(size 1 1)
					(thickness 0.15)
				)
				(justify mirror)
			)
		)
		(sheetname "Root")
		(sheetfile "jetson-orin-baseboard-oculink-expansion.kicad_sch")
		(attr smd dnp)
		(fp_rect
			(start -0.925 0.47)
			(end 0.925 -0.47)
			(stroke
				(width 0.05)
				(type default)
			)
			(fill none)
			(layer "B.CrtYd")
		)
		(fp_rect
			(start -0.5 0.25)
			(end 0.5 -0.25)
			(stroke
				(width 0.15)
				(type solid)
			)
			(fill none)
			(layer "B.Fab")
		)
		(fp_text user "${REFERENCE}"
			(at -0.95 -3.168 0)
			(layer "B.Fab")
			(hide yes)
			(effects
				(font
					(size 0.7 0.7)
					(thickness 0.15)
				)
				(justify right top mirror)
			)
		)
		(fp_text user "Author: Antmicro"
			(at -0.95 -4.169 0)
			(layer "B.Fab")
			(hide yes)
			(effects
				(font
					(size 0.7 0.7)
					(thickness 0.15)
				)
				(justify right top mirror)
			)
		)
		(fp_text user "License: Apache-2.0"
			(at -0.95 -5.169 0)
			(layer "B.Fab")
			(hide yes)
			(effects
				(font
					(size 0.7 0.7)
					(thickness 0.15)
				)
				(justify right top mirror)
			)
		)
		(pad "1" smd roundrect
			(at -0.48 0)
			(size 0.59 0.64)
			(layers "B.Cu" "B.Paste" "B.Mask")
			(roundrect_rratio 0.25)
			(net 23 "+3V3")
			(pintype "passive")
		)
		(pad "2" smd roundrect
			(at 0.48 0)
			(size 0.59 0.64)
			(layers "B.Cu" "B.Paste" "B.Mask")
			(roundrect_rratio 0.25)
			(net 103 "Net-(U2-EN_{I2C})")
			(pintype "passive")
		)
	)
	(footprint "antmicro-footprints:R_0402_1005Metric"
		(layer "B.Cu")
		(at 116.475 112.433751)
		(descr "Resistor SMD 0402")
		(tags "resistor SMD 0402")
		(property "Reference" "R13"
			(at -3.251667 -0.383751 0)
			(layer "B.SilkS")
			(effects
				(font
					(size 0.7 0.7)
					(thickness 0.15)
				)
				(justify right top mirror)
			)
		)
		(property "Value" "R_1k_0402"
			(at -1.011843 -1.772047 0)
			(layer "B.Fab")
			(effects
				(font
					(size 0.7 0.7)
					(thickness 0.15)
				)
				(justify right top mirror)
			)
		)
		(property "Footprint" "antmicro-footprints:R_0402_1005Metric"
			(at 0 0 0)
			(layer "B.Fab")
			(hide yes)
			(effects
				(font
					(size 1.27 1.27)
					(thickness 0.15)
				)
				(justify mirror)
			)
		)
		(property "Datasheet" "https://www.bourns.com/docs/product-datasheets/cr.pdf"
			(at 0 0 0)
			(layer "B.Fab")
			(hide yes)
			(effects
				(font
					(size 1.27 1.27)
					(thickness 0.15)
				)
				(justify mirror)
			)
		)
		(property "Description" "SMD Chip Resistor, 1 kohm, ± 1%, 63 mW, 0402 [1005 Metric], Thick Film, General Purpose"
			(at 0 0 0)
			(layer "B.Fab")
			(hide yes)
			(effects
				(font
					(size 1.27 1.27)
					(thickness 0.15)
				)
				(justify mirror)
			)
		)
		(property "MPN" "CR0402-FX-1001GLF"
			(at 0 0 180)
			(unlocked yes)
			(layer "B.Fab")
			(hide yes)
			(effects
				(font
					(size 1 1)
					(thickness 0.15)
				)
				(justify mirror)
			)
		)
		(property "Manufacturer" "Bourns"
			(at 0 0 180)
			(unlocked yes)
			(layer "B.Fab")
			(hide yes)
			(effects
				(font
					(size 1 1)
					(thickness 0.15)
				)
				(justify mirror)
			)
		)
		(property "License" "Apache-2.0"
			(at 0 0 180)
			(unlocked yes)
			(layer "B.Fab")
			(hide yes)
			(effects
				(font
					(size 1 1)
					(thickness 0.15)
				)
				(justify mirror)
			)
		)
		(property "Author" "Antmicro"
			(at 0 0 180)
			(unlocked yes)
			(layer "B.Fab")
			(hide yes)
			(effects
				(font
					(size 1 1)
					(thickness 0.15)
				)
				(justify mirror)
			)
		)
		(property "Val" "1k"
			(at 0 0 180)
			(unlocked yes)
			(layer "B.Fab")
			(hide yes)
			(effects
				(font
					(size 1 1)
					(thickness 0.15)
				)
				(justify mirror)
			)
		)
		(property "Tolerance" "1%"
			(at 0 0 180)
			(unlocked yes)
			(layer "B.Fab")
			(hide yes)
			(effects
				(font
					(size 1 1)
					(thickness 0.15)
				)
				(justify mirror)
			)
		)
		(property "Public" "False"
			(at 0 0 180)
			(unlocked yes)
			(layer "B.Fab")
			(hide yes)
			(effects
				(font
					(size 1 1)
					(thickness 0.15)
				)
				(justify mirror)
			)
		)
		(sheetname "Root")
		(sheetfile "jetson-orin-baseboard-oculink-expansion.kicad_sch")
		(attr smd dnp)
		(fp_rect
			(start -0.925 0.47)
			(end 0.925 -0.47)
			(stroke
				(width 0.05)
				(type default)
			)
			(fill none)
			(layer "B.CrtYd")
		)
		(fp_rect
			(start -0.5 0.25)
			(end 0.5 -0.25)
			(stroke
				(width 0.15)
				(type solid)
			)
			(fill none)
			(layer "B.Fab")
		)
		(fp_text user "License: Apache-2.0"
			(at -0.95 -5.169 0)
			(layer "B.Fab")
			(hide yes)
			(effects
				(font
					(size 0.7 0.7)
					(thickness 0.15)
				)
				(justify right top mirror)
			)
		)
		(fp_text user "${REFERENCE}"
			(at -0.95 -3.168 0)
			(layer "B.Fab")
			(hide yes)
			(effects
				(font
					(size 0.7 0.7)
					(thickness 0.15)
				)
				(justify right top mirror)
			)
		)
		(fp_text user "Author: Antmicro"
			(at -0.95 -4.169 0)
			(layer "B.Fab")
			(hide yes)
			(effects
				(font
					(size 0.7 0.7)
					(thickness 0.15)
				)
				(justify right top mirror)
			)
		)
		(pad "1" smd roundrect
			(at -0.48 0)
			(size 0.59 0.64)
			(layers "B.Cu" "B.Paste" "B.Mask")
			(roundrect_rratio 0.25)
			(net 51 "GND")
			(pintype "passive")
		)
		(pad "2" smd roundrect
			(at 0.48 0)
			(size 0.59 0.64)
			(layers "B.Cu" "B.Paste" "B.Mask")
			(roundrect_rratio 0.25)
			(net 93 "/RX_FG1")
			(pintype "passive")
		)
	)
	(gr_rect
		(start 110 90)
		(end 148 150)
		(stroke
			(width 0.05)
			(type default)
		)
		(fill none)
		(layer "Edge.Cuts")
	)
	(gr_text "JOB OCuLink Expansion\nRev. ${REVISION}   04/2025"
		(at 116.28 102.155 90)
		(layer "F.Cu")
		(effects
			(font
				(size 0.5 0.5)
				(thickness 0.125)
			)
			(justify left)
		)
	)
	(gr_text "JOB OCuLink Expansion\nRev. ${REVISION}   04/2025"
		(at 122.15 96.3 0)
		(layer "B.Cu")
		(effects
			(font
				(size 0.5 0.5)
				(thickness 0.125)
			)
			(justify left mirror)
		)
	)
	(segment
		(start 146.708 142.036)
		(end 145.461 142.036)
		(width 0.2)
		(layer "F.Cu")
		(net 20)
	)
	(segment
		(start 147.25 142)
		(end 147.214 142.036)
		(width 0.2)
		(layer "F.Cu")
		(net 20)
	)
	(segment
		(start 147.214 142.036)
		(end 146.708 142.036)
		(width 0.2)
		(layer "F.Cu")
		(net 20)
	)
	(segment
		(start 143.5 133.197)
		(end 138.802 133.197)
		(width 0.2)
		(layer "F.Cu")
		(net 20)
	)
	(via
		(at 143.5 133.197)
		(size 0.45)
		(drill 0.1)
		(layers "F.Cu" "B.Cu")
		(net 20)
	)
	(via
		(at 147.25 142)
		(size 0.45)
		(drill 0.1)
		(layers "F.Cu" "B.Cu")
		(net 20)
	)
	(segment
		(start 143.5 133.197)
		(end 143.497 133.2)
		(width 0.2)
		(layer "B.Cu")
		(net 20)
	)
	(segment
		(start 143.497 133.2)
		(end 142.4 133.2)
		(width 0.2)
		(layer "B.Cu")
		(net 20)
	)
	(segment
		(start 142.123107 142.624)
		(end 142.799 142.624)
		(width 0.4)
		(layer "F.Cu")
		(net 23)
	)
	(segment
		(start 123.505 117.316251)
		(end 123.505 118.164751)
		(width 0.2)
		(layer "F.Cu")
		(net 23)
	)
	(segment
		(start 145.554 110.251)
		(end 145.554 111.096)
		(width 0.4)
		(layer "F.Cu")
		(net 23)
	)
	(segment
		(start 118.275 128.541)
		(end 118.275 130.135)
		(width 0.2)
		(layer "F.Cu")
		(net 23)
	)
	(segment
		(start 122.005 113.083751)
		(end 122.005 113.941251)
		(width 0.2)
		(layer "F.Cu")
		(net 23)
	)
	(segment
		(start 125.005 117.312251)
		(end 125.005 118.169751)
		(width 0.2)
		(layer "F.Cu")
		(net 23)
	)
	(segment
		(start 128.005 117.312251)
		(end 128.005 118.169751)
		(width 0.2)
		(layer "F.Cu")
		(net 23)
	)
	(segment
		(start 122.775 128.541)
		(end 122.775 129.3985)
		(width 0.2)
		(layer "F.Cu")
		(net 23)
	)
	(segment
		(start 145.554 110.251)
		(end 145.554 109.08)
		(width 0.4)
		(layer "F.Cu")
		(net 23)
	)
	(segment
		(start 125.005 113.941251)
		(end 125.005 113.083751)
		(width 0.2)
		(layer "F.Cu")
		(net 23)
	)
	(segment
		(start 140.697 131.597)
		(end 140.7 131.6)
		(width 0.4)
		(layer "F.Cu")
		(net 23)
	)
	(segment
		(start 145.554 111.096)
		(end 145.55 111.1)
		(width 0.4)
		(layer "F.Cu")
		(net 23)
	)
	(segment
		(start 138.802 130.799)
		(end 139.793893 130.799)
		(width 0.4)
		(layer "F.Cu")
		(net 23)
	)
	(segment
		(start 140.147447 130.652553)
		(end 140.2 130.6)
		(width 0.4)
		(layer "F.Cu")
		(net 23)
	)
	(segment
		(start 128.005 113.941251)
		(end 128.005 112.365)
		(width 0.2)
		(layer "F.Cu")
		(net 23)
	)
	(segment
		(start 121.275 128.541)
		(end 121.275 129.3985)
		(width 0.2)
		(layer "F.Cu")
		(net 23)
	)
	(segment
		(start 140.525 142.996)
		(end 141.247 142.996)
		(width 0.4)
		(layer "F.Cu")
		(net 23)
	)
	(segment
		(start 123.505 113.941251)
		(end 123.505 113.083751)
		(width 0.2)
		(layer "F.Cu")
		(net 23)
	)
	(segment
		(start 124.276 129.399)
		(end 124.276 128.5415)
		(width 0.2)
		(layer "F.Cu")
		(net 23)
	)
	(segment
		(start 143.65 110.251)
		(end 143.65 111.096)
		(width 0.4)
		(layer "F.Cu")
		(net 23)
	)
	(segment
		(start 124.275 128.541)
		(end 124.275 129.39675)
		(width 0.2)
		(layer "F.Cu")
		(net 23)
	)
	(segment
		(start 141.690447 142.849553)
		(end 141.769554 142.770446)
		(width 0.4)
		(layer "F.Cu")
		(net 23)
	)
	(segment
		(start 118.275 125.17)
		(end 118.275 124.3125)
		(width 0.2)
		(layer "F.Cu")
		(net 23)
	)
	(segment
		(start 119.775 128.541)
		(end 119.775 129.3985)
		(width 0.2)
		(layer "F.Cu")
		(net 23)
	)
	(segment
		(start 138.802 131.597)
		(end 140.697 131.597)
		(width 0.4)
		(layer "F.Cu")
		(net 23)
	)
	(segment
		(start 126.505 117.312251)
		(end 126.505 118.169751)
		(width 0.2)
		(layer "F.Cu")
		(net 23)
	)
	(segment
		(start 122.005 118.153751)
		(end 122.005 117.316251)
		(width 0.2)
		(layer "F.Cu")
		(net 23)
	)
	(segment
		(start 124.276 124.329)
		(end 124.276 125.1665)
		(width 0.2)
		(layer "F.Cu")
		(net 23)
	)
	(segment
		(start 121.275 125.17)
		(end 121.275 124.3125)
		(width 0.2)
		(layer "F.Cu")
		(net 23)
	)
	(segment
		(start 122.775 125.17)
		(end 122.775 124.4125)
		(width 0.2)
		(layer "F.Cu")
		(net 23)
	)
	(segment
		(start 126.505 113.941251)
		(end 126.505 113.083751)
		(width 0.2)
		(layer "F.Cu")
		(net 23)
	)
	(segment
		(start 146.1 115.04)
		(end 145.554 115.04)
		(width 0.4)
		(layer "F.Cu")
		(net 23)
	)
	(segment
		(start 119.775 125.17)
		(end 119.775 124.3125)
		(width 0.2)
		(layer "F.Cu")
		(net 23)
	)
	(via
		(at 123.505 118.164751)
		(size 0.45)
		(drill 0.1)
		(layers "F.Cu" "B.Cu")
		(net 23)
	)
	(via
		(at 122.005 118.153751)
		(size 0.45)
		(drill 0.1)
		(layers "F.Cu" "B.Cu")
		(net 23)
	)
	(via
		(at 121.275 124.3125)
		(size 0.45)
		(drill 0.1)
		(layers "F.Cu" "B.Cu")
		(net 23)
	)
	(via
		(at 126.964 126.66775)
		(size 0.45)
		(drill 0.1)
		(layers "F.Cu" "B.Cu")
		(free yes)
		(net 23)
	)
	(via
		(at 126.964 125.32775)
		(size 0.45)
		(drill 0.1)
		(layers "F.Cu" "B.Cu")
		(free yes)
		(net 23)
	)
	(via
		(at 125.005 113.083751)
		(size 0.45)
		(drill 0.1)
		(layers "F.Cu" "B.Cu")
		(net 23)
	)
	(via
		(at 126.505 118.169751)
		(size 0.45)
		(drill 0.1)
		(layers "F.Cu" "B.Cu")
		(net 23)
	)
	(via
		(at 143.646 111.1)
		(size 0.45)
		(drill 0.1)
		(layers "F.Cu" "B.Cu")
		(net 23)
	)
	(via
		(at 126.974 123.78775)
		(size 0.45)
		(drill 0.1)
		(layers "F.Cu" "B.Cu")
		(free yes)
		(net 23)
	)
	(via
		(at 119.775 129.3985)
		(size 0.45)
		(drill 0.1)
		(layers "F.Cu" "B.Cu")
		(net 23)
	)
	(via
		(at 126.965 129.54775)
		(size 0.45)
		(drill 0.1)
		(layers "F.Cu" "B.Cu")
		(free yes)
		(net 23)
	)
	(via
		(at 126.505 113.083751)
		(size 0.45)
		(drill 0.1)
		(layers "F.Cu" "B.Cu")
		(net 23)
	)
	(via
		(at 118.275 124.3125)
		(size 0.45)
		(drill 0.1)
		(layers "F.Cu" "B.Cu")
		(net 23)
	)
	(via
		(at 119.305 112.433751)
		(size 0.45)
		(drill 0.1)
		(layers "F.Cu" "B.Cu")
		(net 23)
	)
	(via
		(at 140.7 131.6)
		(size 0.45)
		(drill 0.1)
		(layers "F.Cu" "B.Cu")
		(net 23)
	)
	(via
		(at 119.775 124.3125)
		(size 0.45)
		(drill 0.1)
		(layers "F.Cu" "B.Cu")
		(net 23)
	)
	(via
		(at 122.775 129.3985)
		(size 0.45)
		(drill 0.1)
		(layers "F.Cu" "B.Cu")
		(net 23)
	)
	(via
		(at 125.005 118.169751)
		(size 0.45)
		(drill 0.1)
		(layers "F.Cu" "B.Cu")
		(net 23)
	)
	(via
		(at 121.275 129.3985)
		(size 0.45)
		(drill 0.1)
		(layers "F.Cu" "B.Cu")
		(net 23)
	)
	(via
		(at 140.525 142.996)
		(size 0.45)
		(drill 0.1)
		(layers "F.Cu" "B.Cu")
		(net 23)
	)
	(via
		(at 118.275 129.3985)
		(size 0.45)
		(drill 0.1)
		(layers "F.Cu" "B.Cu")
		(net 23)
	)
	(via
		(at 119.305 113.973751)
		(size 0.45)
		(drill 0.1)
		(layers "F.Cu" "B.Cu")
		(net 23)
	)
	(via
		(at 119.304 118.193751)
		(size 0.45)
		(drill 0.1)
		(layers "F.Cu" "B.Cu")
		(net 23)
	)
	(via
		(at 141.2 130.6)
		(size 0.45)
		(drill 0.1)
		(layers "F.Cu" "B.Cu")
		(net 23)
	)
	(via
		(at 123.505 113.083751)
		(size 0.45)
		(drill 0.1)
		(layers "F.Cu" "B.Cu")
		(net 23)
	)
	(via
		(at 140.2 130.6)
		(size 0.45)
		(drill 0.1)
		(layers "F.Cu" "B.Cu")
		(net 23)
	)
	(via
		(at 119.305 111.093751)
		(size 0.45)
		(drill 0.1)
		(layers "F.Cu" "B.Cu")
		(net 23)
	)
	(via
		(at 128.005 118.169751)
		(size 0.45)
		(drill 0.1)
		(layers "F.Cu" "B.Cu")
		(net 23)
	)
	(via
		(at 126.964 128.00775)
		(size 0.45)
		(drill 0.1)
		(layers "F.Cu" "B.Cu")
		(free yes)
		(net 23)
	)
	(via
		(at 128.005 113.083751)
		(size 0.45)
		(drill 0.1)
		(layers "F.Cu" "B.Cu")
		(net 23)
	)
	(via
		(at 122.775 124.3125)
		(size 0.45)
		(drill 0.1)
		(layers "F.Cu" "B.Cu")
		(net 23)
	)
	(via
		(at 119.305 115.313751)
		(size 0.45)
		(drill 0.1)
		(layers "F.Cu" "B.Cu")
		(net 23)
	)
	(via
		(at 126.965 130.88775)
		(size 0.45)
		(drill 0.1)
		(layers "F.Cu" "B.Cu")
		(free yes)
		(net 23)
	)
	(via
		(at 122.005 113.083751)
		(size 0.45)
		(drill 0.1)
		(layers "F.Cu" "B.Cu")
		(net 23)
	)
	(via
		(at 145.55 111.1)
		(size 0.45)
		(drill 0.1)
		(layers "F.Cu" "B.Cu")
		(net 23)
	)
	(via
		(at 124.275 129.39675)
		(size 0.45)
		(drill 0.1)
		(layers "F.Cu" "B.Cu")
		(net 23)
	)
	(via
		(at 119.304 116.653751)
		(size 0.45)
		(drill 0.1)
		(layers "F.Cu" "B.Cu")
		(net 23)
	)
	(via
		(at 146.1 115.04)
		(size 0.45)
		(drill 0.1)
		(layers "F.Cu" "B.Cu")
		(net 23)
	)
	(via
		(at 124.276 124.329)
		(size 0.45)
		(drill 0.1)
		(layers "F.Cu" "B.Cu")
		(net 23)
	)
	(arc
		(start 139.793893 130.799)
		(mid 139.985235 130.76094)
		(end 140.147447 130.652553)
		(width 0.4)
		(layer "F.Cu")
		(net 23)
	)
	(arc
		(start 141.690447 142.849553)
		(mid 141.528235 142.95794)
		(end 141.336893 142.996)
		(width 0.4)
		(layer "F.Cu")
		(net 23)
	)
	(arc
		(start 142.123107 142.624)
		(mid 141.931766 142.66206)
		(end 141.769554 142.770446)
		(width 0.4)
		(layer "F.Cu")
		(net 23)
	)
	(segment
		(start 126.964 125.32775)
		(end 127.464 125.32775)
		(width 0.4)
		(layer "B.Cu")
		(net 23)
	)
	(segment
		(start 124.276 129.399)
		(end 124.276 128.3945)
		(width 0.4)
		(layer "B.Cu")
		(net 23)
	)
	(segment
		(start 121.275 129.3985)
		(end 121.275 128.393)
		(width 0.4)
		(layer "B.Cu")
		(net 23)
	)
	(segment
		(start 117.2085 129.3985)
		(end 117.03 129.22)
		(width 0.4)
		(layer "B.Cu")
		(net 23)
	)
	(segment
		(start 128.092304 112.996447)
		(end 128.005 113.083751)
		(width 0.4)
		(layer "B.Cu")
		(net 23)
	)
	(segment
		(start 119.305 113.973751)
		(end 118.805 113.973751)
		(width 0.4)
		(layer "B.Cu")
		(net 23)
	)
	(segment
		(start 126.965 129.54775)
		(end 127.465 129.54775)
		(width 0.4)
		(layer "B.Cu")
		(net 23)
	)
	(segment
		(start 124.275 128.394)
		(end 124.275 129.39675)
		(width 0.4)
		(layer "B.Cu")
		(net 23)
	)
	(segment
		(start 126.974 123.78775)
		(end 127.474 123.78775)
		(width 0.4)
		(layer "B.Cu")
		(net 23)
	)
	(segment
		(start 123.505 118.164751)
		(end 123.505 117.159251)
		(width 0.4)
		(layer "B.Cu")
		(net 23)
	)
	(segment
		(start 142.4 131.231062)
		(end 141.915384 130.746446)
		(width 0.4)
		(layer "B.Cu")
		(net 23)
	)
	(segment
		(start 119.304 116.653751)
		(end 118.804 116.653751)
		(width 0.4)
		(layer "B.Cu")
		(net 23)
	)
	(segment
		(start 119.305 111.093751)
		(end 118.805 111.093751)
		(width 0.4)
		(layer "B.Cu")
		(net 23)
	)
	(segment
		(start 126.964 126.66775)
		(end 127.464 126.66775)
		(width 0.4)
		(layer "B.Cu")
		(net 23)
	)
	(segment
		(start 125.005 118.169751)
		(end 125.005 117.164251)
		(width 0.4)
		(layer "B.Cu")
		(net 23)
	)
	(segment
		(start 116.25 125.874)
		(end 116.511107 125.612893)
		(width 0.4)
		(layer "B.Cu")
		(net 23)
	)
	(segment
		(start 128.005 114.089251)
		(end 128.005 113.083751)
		(width 0.4)
		(layer "B.Cu")
		(net 23)
	)
	(segment
		(start 130.02 116.23)
		(end 130.02 117.16)
		(width 0.4)
		(layer "B.Cu")
		(net 23)
	)
	(segment
		(start 126.505 118.169751)
		(end 126.505 117.164251)
		(width 0.4)
		(layer "B.Cu")
		(net 23)
	)
	(segment
		(start 118.275 124.3125)
		(end 118.275 125.318)
		(width 0.4)
		(layer "B.Cu")
		(net 23)
	)
	(segment
		(start 141.561831 130.6)
		(end 141.2 130.6)
		(width 0.4)
		(layer "B.Cu")
		(net 23)
	)
	(segment
		(start 126.964 128.00775)
		(end 127.464 128.00775)
		(width 0.4)
		(layer "B.Cu")
		(net 23)
	)
	(segment
		(start 119.305 115.313751)
		(end 118.805 115.313751)
		(width 0.4)
		(layer "B.Cu")
		(net 23)
	)
	(segment
		(start 119.775 129.3985)
		(end 119.775 128.393)
		(width 0.4)
		(layer "B.Cu")
		(net 23)
	)
	(segment
		(start 117.218214 125.32)
		(end 118.27 125.32)
		(width 0.4)
		(layer "B.Cu")
		(net 23)
	)
	(segment
		(start 121.275 124.3125)
		(end 121.275 125.318)
		(width 0.4)
		(layer "B.Cu")
		(net 23)
	)
	(segment
		(start 119.775 124.3125)
		(end 119.775 125.318)
		(width 0.4)
		(layer "B.Cu")
		(net 23)
	)
	(segment
		(start 118.275 129.3985)
		(end 117.2085 129.3985)
		(width 0.4)
		(layer "B.Cu")
		(net 23)
	)
	(segment
		(start 122.005 118.153751)
		(end 122.005 117.164751)
		(width 0.4)
		(layer "B.Cu")
		(net 23)
	)
	(segment
		(start 119.304 118.193751)
		(end 118.804 118.193751)
		(width 0.4)
		(layer "B.Cu")
		(net 23)
	)
	(segment
		(start 122.005 113.083751)
		(end 122.005 114.088251)
		(width 0.4)
		(layer "B.Cu")
		(net 23)
	)
	(segment
		(start 128.005 118.169751)
		(end 128.005 117.164251)
		(width 0.4)
		(layer "B.Cu")
		(net 23)
	)
	(segment
		(start 123.505 113.083751)
		(end 123.505 114.089251)
		(width 0.4)
		(layer "B.Cu")
		(net 23)
	)
	(segment
		(start 122.775 124.3125)
		(end 122.775 125.318)
		(width 0.4)
		(layer "B.Cu")
		(net 23)
	)
	(segment
		(start 126.505 113.083751)
		(end 126.505 114.089251)
		(width 0.4)
		(layer "B.Cu")
		(net 23)
	)
	(segment
		(start 129.24 112.85)
		(end 128.445858 112.85)
		(width 0.4)
		(layer "B.Cu")
		(net 23)
	)
	(segment
		(start 118.275 128.393)
		(end 118.275 129.3985)
		(width 0.4)
		(layer "B.Cu")
		(net 23)
	)
	(segment
		(start 126.965 130.88775)
		(end 127.465 130.88775)
		(width 0.4)
		(layer "B.Cu")
		(net 23)
	)
	(segment
		(start 119.305 112.433751)
		(end 118.805 112.433751)
		(width 0.4)
		(layer "B.Cu")
		(net 23)
	)
	(segment
		(start 125.005 113.083751)
		(end 125.005 114.089251)
		(width 0.4)
		(layer "B.Cu")
		(net 23)
	)
	(segment
		(start 124.276 124.329)
		(end 124.276 125.318)
		(width 0.4)
		(layer "B.Cu")
		(net 23)
	)
	(segment
		(start 128.005 117.167251)
		(end 130.007251 117.167251)
		(width 0.4)
		(layer "B.Cu")
		(net 23)
	)
	(segment
		(start 116.25 125.874)
		(end 116.25 126.828)
		(width 0.4)
		(layer "B.Cu")
		(net 23)
	)
	(segment
		(start 122.775 129.3985)
		(end 122.775 128.393)
		(width 0.4)
		(layer "B.Cu")
		(net 23)
	)
	(arc
		(start 128.445858 112.85)
		(mid 128.254516 112.88806)
		(end 128.092304 112.996447)
		(width 0.4)
		(layer "B.Cu")
		(net 23)
	)
	(arc
		(start 141.915384 130.746446)
		(mid 141.753172 130.63806)
		(end 141.561831 130.6)
		(width 0.4)
		(layer "B.Cu")
		(net 23)
	)
	(arc
		(start 116.511107 125.612893)
		(mid 116.83553 125.39612)
		(end 117.218214 125.32)
		(width 0.4)
		(layer "B.Cu")
		(net 23)
	)
	(segment
		(start 122.275 129.197251)
		(end 122.275 128.541)
		(width 0.185)
		(layer "F.Cu")
		(net 31)
	)
	(segment
		(start 116.289989 135.713357)
		(end 121.897108 130.106252)
		(width 0.185)
		(layer "F.Cu")
		(net 31)
	)
	(segment
		(start 116.41875 137.17)
		(end 116.41875 136.689999)
		(width 0.185)
		(layer "F.Cu")
		(net 31)
	)
	(segment
		(start 122.19 129.282251)
		(end 122.275 129.197251)
		(width 0.185)
		(layer "F.Cu")
		(net 31)
	)
	(segment
		(start 116.41875 136.689999)
		(end 116.09375 136.364999)
		(width 0.185)
		(layer "F.Cu")
		(net 31)
	)
	(segment
		(start 122.190002 129.399123)
		(end 122.19 129.282251)
		(width 0.185)
		(layer "F.Cu")
		(net 31)
	)
	(segment
		(start 116.09375 136.364999)
		(end 116.09375 136.18712)
		(width 0.185)
		(layer "F.Cu")
		(net 31)
	)
	(arc
		(start 116.289989 135.713357)
		(mid 116.144751 135.930721)
		(end 116.09375 136.18712)
		(width 0.185)
		(layer "F.Cu")
		(net 31)
	)
	(arc
		(start 121.897108 130.106252)
		(mid 122.113886 129.781819)
		(end 122.190002 129.399123)
		(width 0.185)
		(layer "F.Cu")
		(net 31)
	)
	(segment
		(start 140.1 132.6)
		(end 140.045446 132.545446)
		(width 0.4)
		(layer "F.Cu")
		(net 51)
	)
	(segment
		(start 133.871 105.315)
		(end 133.988 105.198)
		(width 0.4)
		(layer "F.Cu")
		(net 51)
	)
	(segment
		(start 135.003 128.399)
		(end 133.901 128.399)
		(width 0.4)
		(layer "F.Cu")
		(net 51)
	)
	(segment
		(start 133.9 112.398)
		(end 133.871 112.427)
		(width 0.4)
		(layer "F.Cu")
		(net 51)
	)
	(segment
		(start 133.983 109.999)
		(end 135.003 109.999)
		(width 0.4)
		(layer "F.Cu")
		(net 51)
	)
	(segment
		(start 133.896492 133.998)
		(end 133.877658 133.979166)
		(width 0.4)
		(layer "F.Cu")
		(net 51)
	)
	(segment
		(start 120.567 115.878251)
		(end 121.7405 115.878251)
		(width 0.2)
		(layer "F.Cu")
		(net 51)
	)
	(segment
		(start 142.5 116.499)
		(end 141.651 116.499)
		(width 0.4)
		(layer "F.Cu")
		(net 51)
	)
	(segment
		(start 133.988 105.198)
		(end 135.003 105.198)
		(width 0.4)
		(layer "F.Cu")
		(net 51)
	)
	(segment
		(start 115.456486 145.958861)
		(end 115.456486 145.757778)
		(width 0.2)
		(layer "F.Cu")
		(net 51)
	)
	(segment
		(start 140.2 109.4)
		(end 139.998 109.198)
		(width 0.4)
		(layer "F.Cu")
		(net 51)
	)
	(segment
		(start 118.17875 142.625466)
		(end 118.17875 143.551569)
		(width 0.2)
		(layer "F.Cu")
		(net 51)
	)
	(segment
		(start 117.18175 143.955466)
		(end 117.17875 143.958466)
		(width 0.2)
		(layer "F.Cu")
		(net 51)
	)
	(segment
		(start 128.858553 116.718553)
		(end 128.005 115.865)
		(width 0.2)
		(layer "F.Cu")
		(net 51)
	)
	(segment
		(start 128.26175 147.735466)
		(end 126.83875 147.735466)
		(width 0.4)
		(layer "F.Cu")
		(net 51)
	)
	(segment
		(start 138.802 113.999)
		(end 139.792 113.999)
		(width 0.4)
		(layer "F.Cu")
		(net 51)
	)
	(segment
		(start 140.62 140.5)
		(end 140.1 140.5)
		(width 0.4)
		(layer "F.Cu")
		(net 51)
	)
	(segment
		(start 145.399 142.624)
		(end 146.128892 142.623998)
		(width 0.4)
		(layer "F.Cu")
		(net 51)
	)
	(segment
		(start 133.901 128.399)
		(end 133.871 128.429)
		(width 0.4)
		(layer "F.Cu")
		(net 51)
	)
	(segment
		(start 133.903622 132.399)
		(end 133.89648 132.391858)
		(width 0.4)
		(layer "F.Cu")
		(net 51)
	)
	(segment
		(start 139.798 106.797)
		(end 139.84 106.839)
		(width 0.4)
		(layer "F.Cu")
		(net 51)
	)
	(segment
		(start 128.75 145.13)
		(end 128.75 145.8)
		(width 0.4)
		(layer "F.Cu")
		(net 51)
	)
	(segment
		(start 124.17875 142.625466)
		(end 124.17875 141.815466)
		(width 0.2)
		(layer "F.Cu")
		(net 51)
	)
	(segment
		(start 138.802 123.599)
		(end 139.836 123.599)
		(width 0.4)
		(layer "F.Cu")
		(net 51)
	)
	(segment
		(start 144.604 112.851)
		(end 144.604 114.071)
		(width 0.4)
		(layer "F.Cu")
		(net 51)
	)
	(segment
		(start 134.151 104.4)
		(end 134.125 104.426)
		(width 0.4)
		(layer "F.Cu")
		(net 51)
	)
	(segment
		(start 124.68175 145.955466)
		(end 124.68175 144.818466)
		(width 0.2)
		(layer "F.Cu")
		(net 51)
	)
	(segment
		(start 138.802 133.998)
		(end 140.202 133.998)
		(width 0.4)
		(layer "F.Cu")
		(net 51)
	)
	(segment
		(start 113.01875 146.467466)
		(end 113.05075 146.435466)
		(width 0.4)
		(layer "F.Cu")
		(net 51)
	)
	(segment
		(start 135.003 112.398)
		(end 133.9 112.398)
		(width 0.4)
		(layer "F.Cu")
		(net 51)
	)
	(segment
		(start 143.996 123.697)
		(end 143.996 122.9)
		(width 0.4)
		(layer "F.Cu")
		(net 51)
	)
	(segment
		(start 115.95 143.95)
		(end 115.354486 143.354486)
		(width 0.2)
		(layer "F.Cu")
		(net 51)
	)
	(segment
		(start 121.825197 143.884019)
		(end 121.94075 143.768466)
		(width 0.2)
		(layer "F.Cu")
		(net 51)
	)
	(segment
		(start 139.691893 132.399)
		(end 138.802 132.399)
		(width 0.4)
		(layer "F.Cu")
		(net 51)
	)
	(segment
		(start 138.802 104.4)
		(end 139.814 104.4)
		(width 0.4)
		(layer "F.Cu")
		(net 51)
	)
	(segment
		(start 120.032303 143.892019)
		(end 119.90875 143.768466)
		(width 0.2)
		(layer "F.Cu")
		(net 51)
	)
	(segment
		(start 140.202 133.998)
		(end 140.221 134.017)
		(width 0.4)
		(layer "F.Cu")
		(net 51)
	)
	(segment
		(start 125.713 126.104)
		(end 125.0395 126.104)
		(width 0.2)
		(layer "F.Cu")
		(net 51)
	)
	(segment
		(start 115.17875 142.930222)
		(end 115.17875 142.625466)
		(width 0.2)
		(layer "F.Cu")
		(net 51)
	)
	(segment
		(start 135.003 114.797)
		(end 133.914 114.797)
		(width 0.4)
		(layer "F.Cu")
		(net 51)
	)
	(segment
		(start 146.7 143.8)
		(end 146.7 143.004)
		(width 0.4)
		(layer "F.Cu")
		(net 51)
	)
	(segment
		(start 123.18175 143.755466)
		(end 123.17875 143.758466)
		(width 0.2)
		(layer "F.Cu")
		(net 51)
	)
	(segment
		(start 115.544354 145.545646)
		(end 115.590882 145.499118)
		(width 0.2)
		(layer "F.Cu")
		(net 51)
	)
	(segment
		(start 140.2 111.4)
		(end 140.002 111.598)
		(width 0.4)
		(layer "F.Cu")
		(net 51)
	)
	(segment
		(start 143.10832 119.45832)
		(end 142.9 119.25)
		(width 0.4)
		(layer "F.Cu")
		(net 51)
	)
	(segment
		(start 111.1 146.786)
		(end 111.1 147.467)
		(width 0.4)
		(layer "F.Cu")
		(net 51)
	)
	(segment
		(start 113.01875 147.735466)
		(end 113.01875 146.467466)
		(width 0.4)
		(layer "F.Cu")
		(net 51)
	)
	(segment
		(start 135.003 118.799)
		(end 133.893 118.799)
		(width 0.4)
		(layer "F.Cu")
		(net 51)
	)
	(segment
		(start 119.67875 141.760466)
		(end 119.67875 142.625466)
		(width 0.2)
		(layer "F.Cu")
		(net 51)
	)
	(segment
		(start 139.793893 128.399)
		(end 138.802 128.399)
		(width 0.4)
		(layer "F.Cu")
		(net 51)
	)
	(segment
		(start 123.17875 143.758466)
		(end 123.17875 144.815466)
		(width 0.2)
		(layer "F.Cu")
		(net 51)
	)
	(segment
		(start 141.651 116.499)
		(end 141.65 116.5)
		(width 0.4)
		(layer "F.Cu")
		(net 51)
	)
	(segment
		(start 133.893 118.799)
		(end 133.871 118.777)
		(width 0.4)
		(layer "F.Cu")
		(net 51)
	)
	(segment
		(start 143.046 127.631)
		(end 144 127.631)
		(width 0.2)
		(layer "F.Cu")
		(net 51)
	)
	(segment
		(start 133.747 107.598)
		(end 133.744 107.601)
		(width 0.4)
		(layer "F.Cu")
		(net 51)
	)
	(segment
		(start 144 128.151)
		(end 144 127.631)
		(width 0.4)
		(layer "F.Cu")
		(net 51)
	)
	(segment
		(start 128.375 143)
		(end 126.854216 143)
		(width 0.4)
		(layer "F.Cu")
		(net 51)
	)
	(segment
		(start 133.871 109.887)
		(end 133.983 109.999)
		(width 0.4)
		(layer "F.Cu")
		(net 51)
	)
	(segment
		(start 122.9 141.736466)
		(end 122.854486 141.78198)
		(width 0.2)
		(layer "F.Cu")
		(net 51)
	)
	(segment
		(start 121.2405 116.378251)
		(end 122.005 115.613751)
		(width 0.2)
		(layer "F.Cu")
		(net 51)
	)
	(segment
		(start 121.67875 144.815466)
		(end 121.67875 144.237573)
		(width 0.2)
		(layer "F.Cu")
		(net 51)
	)
	(segment
		(start 145.554 107.6)
		(end 145.554 108.12)
		(width 0.4)
		(layer "F.Cu")
		(net 51)
	)
	(segment
		(start 133.875 123.599)
		(end 133.871 123.603)
		(width 0.4)
		(layer "F.Cu")
		(net 51)
	)
	(segment
		(start 112.484534 143.015466)
		(end 111.8 143.7)
		(width 0.4)
		(layer "F.Cu")
		(net 51)
	)
	(segment
		(start 135.003 133.998)
		(end 133.896492 133.998)
		(width 0.4)
		(layer "F.Cu")
		(net 51)
	)
	(segment
		(start 135.003 132.399)
		(end 133.903622 132.399)
		(width 0.4)
		(layer "F.Cu")
		(net 51)
	)
	(segment
		(start 116.35 143.55)
		(end 116.503014 143.396986)
		(width 0.2)
		(layer "F.Cu")
		(net 51)
	)
	(segment
		(start 144.6 108.12)
		(end 144.6 107.6)
		(width 0.4)
		(layer "F.Cu")
		(net 51)
	)
	(segment
		(start 140.002 111.598)
		(end 138.802 111.598)
		(width 0.4)
		(layer "F.Cu")
		(net 51)
	)
	(segment
		(start 116.67875 142.972722)
		(end 116.67875 142.625466)
		(width 0.2)
		(layer "F.Cu")
		(net 51)
	)
	(segment
		(start 135.003 107.598)
		(end 133.747 107.598)
		(width 0.4)
		(layer "F.Cu")
		(net 51)
	)
	(segment
		(start 125.0395 126.104)
		(end 124.275 126.8685)
		(width 0.2)
		(layer "F.Cu")
		(net 51)
	)
	(segment
		(start 135.003 123.599)
		(end 133.875 123.599)
		(width 0.4)
		(layer "F.Cu")
		(net 51)
	)
	(segment
		(start 146.7 143.8)
		(end 146.7 144.66)
		(width 0.4)
		(layer "F.Cu")
		(net 51)
	)
	(segment
		(start 140.7 141.45)
		(end 141.247 141.997)
		(width 0.4)
		(layer "F.Cu")
		(net 51)
	)
	(segment
		(start 113.02 141.25)
		(end 112.35 141.25)
		(width 0.4)
		(layer "F.Cu")
		(net 51)
	)
	(segment
		(start 139.792 113.999)
		(end 139.84 113.951)
		(width 0.4)
		(layer "F.Cu")
		(net 51)
	)
	(segment
		(start 146.482448 142.770446)
		(end 146.708 142.996)
		(width 0.4)
		(layer "F.Cu")
		(net 51)
	)
	(segment
		(start 120.567 116.378251)
		(end 121.2405 116.378251)
		(width 0.2)
		(layer "F.Cu")
		(net 51)
	)
	(segment
		(start 115.67875 145.286986)
		(end 115.67875 144.815466)
		(width 0.2)
		(layer "F.Cu")
		(net 51)
	)
	(segment
		(start 128.28175 147.755466)
		(end 128.26175 147.735466)
		(width 0.4)
		(layer "F.Cu")
		(net 51)
	)
	(segment
		(start 133.914 114.797)
		(end 133.871 114.84)
		(width 0.4)
		(layer "F.Cu")
		(net 51)
	)
	(segment
		(start 117.17875 143.958466)
		(end 117.17875 144.815466)
		(width 0.2)
		(layer "F.Cu")
		(net 51)
	)
	(segment
		(start 125.713 126.604)
		(end 124.5395 126.604)
		(width 0.2)
		(layer "F.Cu")
		(net 51)
	)
	(segment
		(start 138.802 106.797)
		(end 139.798 106.797)
		(width 0.4)
		(layer "F.Cu")
		(net 51)
	)
	(segment
		(start 121.471643 141.570573)
		(end 121.68675 141.355466)
		(width 0.2)
		(layer "F.Cu")
		(net 51)
	)
	(segment
		(start 123.72 141.1)
		(end 123.2 141.1)
		(width 0.4)
		(layer "F.Cu")
		(net 51)
	)
	(segment
		(start 124.17875 141.815466)
		(end 124.09975 141.736466)
		(width 0.2)
		(layer "F.Cu")
		(net 51)
	)
	(segment
		(start 140.3 128.1)
		(end 140.147446 128.252554)
		(width 0.4)
		(layer "F.Cu")
		(net 51)
	)
	(segment
		(start 120.17875 144.815466)
		(end 120.17875 144.245573)
		(width 0.2)
		(layer "F.Cu")
		(net 51)
	)
	(segment
		(start 118.835303 145.495303)
		(end 118.825196 145.485196)
		(width 0.2)
		(layer "F.Cu")
		(net 51)
	)
	(segment
		(start 135.003 104.4)
		(end 134.151 104.4)
		(width 0.4)
		(layer "F.Cu")
		(net 51)
	)
	(segment
		(start 144.604 112.851)
		(end 144.604 112.001)
		(width 0.4)
		(layer "F.Cu")
		(net 51)
	)
	(segment
		(start 143.996 122.9)
		(end 143.996 121.68)
		(width 0.4)
		(layer "F.Cu")
		(net 51)
	)
	(segment
		(start 143.987 121.671)
		(end 143.987 121.579641)
		(width 0.4)
		(layer "F.Cu")
		(net 51)
	)
	(segment
		(start 139.814 104.4)
		(end 139.84 104.426)
		(width 0.4)
		(layer "F.Cu")
		(net 51)
	)
	(segment
		(start 139.836 123.599)
		(end 139.84 123.603)
		(width 0.4)
		(layer "F.Cu")
		(net 51)
	)
	(segment
		(start 139.818 118.799)
		(end 138.802 118.799)
		(width 0.4)
		(layer "F.Cu")
		(net 51)
	)
	(segment
		(start 118.98175 145.955466)
		(end 118.98175 145.848857)
		(width 0.2)
		(layer "F.Cu")
		(net 51)
	)
	(segment
		(start 139.998 109.198)
		(end 138.802 109.198)
		(width 0.4)
		(layer "F.Cu")
		(net 51)
	)
	(segment
		(start 122.67875 142.206244)
		(end 122.67875 142.625466)
		(width 0.2)
		(layer "F.Cu")
		(net 51)
	)
	(via
		(at 123.525 127.434)
		(size 0.45)
		(drill 0.1)
		(layers "F.Cu" "B.Cu")
		(net 51)
	)
	(via
		(at 117 132)
		(size 0.45)
		(drill 0.1)
		(layers "F.Cu" "B.Cu")
		(free yes)
		(net 51)
	)
	(via
		(at 122.025 127.433)
		(size 0.45)
		(drill 0.1)
		(layers "F.Cu" "B.Cu")
		(net 51)
	)
	(via
		(at 111.88 113.22)
		(size 0.45)
		(drill 0.1)
		(layers "F.Cu" "B.Cu")
		(net 51)
	)
	(via
		(at 124.29 102.95)
		(size 0.45)
		(drill 0.1)
		(layers "F.Cu" "B.Cu")
		(net 51)
	)
	(via
		(at 127.8 99.8)
		(size 0.45)
		(drill 0.1)
		(layers "F.Cu" "B.Cu")
		(net 51)
	)
	(via
		(at 123.2 141.1)
		(size 0.45)
		(drill 0.1)
		(layers "F.Cu" "B.Cu")
		(net 51)
	)
	(via
		(at 130.5825 140.1)
		(size 0.45)
		(drill 0.1)
		(layers "F.Cu" "B.Cu")
		(free yes)
		(net 51)
	)
	(via
		(at 130.774 128.00775)
		(size 0.45)
		(drill 0.1)
		(layers "F.Cu" "B.Cu")
		(net 51)
	)
	(via
		(at 144.6 107.6)
		(size 0.45)
		(drill 0.1)
		(layers "F.Cu" "B.Cu")
		(net 51)
	)
	(via
		(at 119.67875 141.760466)
		(size 0.45)
		(drill 0.1)
		(layers "F.Cu" "B.Cu")
		(net 51)
	)
	(via
		(at 115.495 112.433751)
		(size 0.45)
		(drill 0.1)
		(layers "F.Cu" "B.Cu")
		(net 51)
	)
	(via
		(at 124.255 115.049251)
		(size 0.45)
		(drill 0.1)
		(layers "F.Cu" "B.Cu")
		(net 51)
	)
	(via
		(at 122.005 115.613751)
		(size 0.45)
		(drill 0.1)
		(layers "F.Cu" "B.Cu")
		(net 51)
	)
	(via
		(at 122.2 133.5)
		(size 0.45)
		(drill 0.1)
		(layers "F.Cu" "B.Cu")
		(free yes)
		(net 51)
	)
	(via
		(at 122.95 107.58)
		(size 0.45)
		(drill 0.1)
		(layers "F.Cu" "B.Cu")
		(free yes)
		(net 51)
	)
	(via
		(at 139.84 106.839)
		(size 0.45)
		(drill 0.1)
		(layers "F.Cu" "B.Cu")
		(net 51)
	)
	(via
		(at 120.525 127.433)
		(size 0.45)
		(drill 0.1)
		(layers "F.Cu" "B.Cu")
		(net 51)
	)
	(via
		(at 116.35 143.55)
		(size 0.45)
		(drill 0.1)
		(layers "F.Cu" "B.Cu")
		(net 51)
	)
	(via
		(at 133.871 112.427)
		(size 0.45)
		(drill 0.1)
		(layers "F.Cu" "B.Cu")
		(net 51)
	)
	(via
		(at 125.44 131.59)
		(size 0.45)
		(drill 0.1)
		(layers "F.Cu" "B.Cu")
		(free yes)
		(net 51)
	)
	(via
		(at 143.996 123.697)
		(size 0.45)
		(drill 0.1)
		(layers "F.Cu" "B.Cu")
		(net 51)
	)
	(via
		(at 117.17 146.5)
		(size 0.45)
		(drill 0.1)
		(layers "F.Cu" "B.Cu")
		(net 51)
	)
	(via
		(at 128.375 143)
		(size 0.45)
		(drill 0.1)
		(layers "F.Cu" "B.Cu")
		(net 51)
	)
	(via
		(at 111.133 147.5)
		(size 0.45)
		(drill 0.1)
		(layers "F.Cu" "B.Cu")
		(net 51)
	)
	(via
		(at 128.28175 147.755466)
		(size 0.45)
		(drill 0.1)
		(layers "F.Cu" "B.Cu")
		(net 51)
	)
	(via
		(at 120.39 107.04)
		(size 0.45)
		(drill 0.1)
		(layers "F.Cu" "B.Cu")
		(net 51)
	)
	(via
		(at 130.784 123.78775)
		(size 0.45)
		(drill 0.1)
		(layers "F.Cu" "B.Cu")
		(net 51)
	)
	(via
		(at 121.275 126.8675)
		(size 0.45)
		(drill 0.1)
		(layers "F.Cu" "B.Cu")
		(net 51)
	)
	(via
		(at 144 128.151)
		(size 0.45)
		(drill 0.1)
		(layers "F.Cu" "B.Cu")
		(net 51)
	)
	(via
		(at 113.05075 146.435466)
		(size 0.45)
		(drill 0.1)
		(layers "F.Cu" "B.Cu")
		(net 51)
	)
	(via
		(at 115.495 116.653751)
		(size 0.45)
		(drill 0.1)
		(layers "F.Cu" "B.Cu")
		(net 51)
	)
	(via
		(at 114.2 137.55)
		(size 0.45)
		(drill 0.1)
		(layers "F.Cu" "B.Cu")
		(net 51)
	)
	(via
		(at 140.221 134.017)
		(size 0.45)
		(drill 0.1)
		(layers "F.Cu" "B.Cu")
		(net 51)
	)
	(via
		(at 139.818 118.799)
		(size 0.45)
		(drill 0.1)
		(layers "F.Cu" "B.Cu")
		(net 51)
	)
	(via
		(at 130.25 110.62)
		(size 0.45)
		(drill 0.1)
		(layers "F.Cu" "B.Cu")
		(free yes)
		(net 51)
	)
	(via
		(at 124.09975 141.736466)
		(size 0.45)
		(drill 0.1)
		(layers "F.Cu" "B.Cu")
		(net 51)
	)
	(via
		(at 133.871 114.84)
		(size 0.45)
		(drill 0.1)
		(layers "F.Cu" "B.Cu")
		(net 51)
	)
	(via
		(at 140.2 111.4)
		(size 0.45)
		(drill 0.1)
		(layers "F.Cu" "B.Cu")
		(net 51)
	)
	(via
		(at 130.774 130.88775)
		(size 0.45)
		(drill 0.1)
		(layers "F.Cu" "B.Cu")
		(net 51)
	)
	(via
		(at 122.755 116.207251)
		(size 0.45)
		(drill 0.1)
		(layers "F.Cu" "B.Cu")
		(net 51)
	)
	(via
		(at 125.375 122.55)
		(size 0.45)
		(drill 0.1)
		(layers "F.Cu" "B.Cu")
		(free yes)
		(net 51)
	)
	(via
		(at 121 100.5)
		(size 0.45)
		(drill 0.1)
		(layers "F.Cu" "B.Cu")
		(net 51)
	)
	(via
		(at 132.8 107.2)
		(size 0.45)
		(drill 0.1)
		(layers "F.Cu" "B.Cu")
		(net 51)
	)
	(via
		(at 123.505 115.614751)
		(size 0.45)
		(drill 0.1)
		(layers "F.Cu" "B.Cu")
		(net 51)
	)
	(via
		(at 118.275 126.8675)
		(size 0.45)
		(drill 0.1)
		(layers "F.Cu" "B.Cu")
		(net 51)
	)
	(via
		(at 124.275 126.8685)
		(size 0.45)
		(drill 0.1)
		(layers "F.Cu" "B.Cu")
		(net 51)
	)
	(via
		(at 130.774 125.32775)
		(size 0.45)
		(drill 0.1)
		(layers "F.Cu" "B.Cu")
		(net 51)
	)
	(via
		(at 140.2 109.4)
		(size 0.45)
		(drill 0.1)
		(layers "F.Cu" "B.Cu")
		(net 51)
	)
	(via
		(at 122.9 141.736466)
		(size 0.45)
		(drill 0.1)
		(layers "F.Cu" "B.Cu")
		(net 51)
	)
	(via
		(at 123.18175 143.755466)
		(size 0.45)
		(drill 0.1)
		(layers "F.Cu" "B.Cu")
		(net 51)
	)
	(via
		(at 114.7 139.6)
		(size 0.45)
		(drill 0.1)
		(layers "F.Cu" "B.Cu")
		(net 51)
	)
	(via
		(at 119.76 137.01)
		(size 0.45)
		(drill 0.1)
		(layers "F.Cu" "B.Cu")
		(net 51)
	)
	(via
		(at 132.8 105.6)
		(size 0.45)
		(drill 0.1)
		(layers "F.Cu" "B.Cu")
		(net 51)
	)
	(via
		(at 133.871 128.429)
		(size 0.45)
		(drill 0.1)
		(layers "F.Cu" "B.Cu")
		(net 51)
	)
	(via
		(at 115.495 118.193751)
		(size 0.45)
		(drill 0.1)
		(layers "F.Cu" "B.Cu")
		(net 51)
	)
	(via
		(at 133.871 123.603)
		(size 0.45)
		(drill 0.1)
		(layers "F.Cu" "B.Cu")
		(net 51)
	)
	(via
		(at 133.877658 133.979166)
		(size 0.45)
		(drill 0.1)
		(layers "F.Cu" "B.Cu")
		(net 51)
	)
	(via
		(at 125.755 115.049251)
		(size 0.45)
		(drill 0.1)
		(layers "F.Cu" "B.Cu")
		(net 51)
	)
	(via
		(at 125.005 115.614751)
		(size 0.45)
		(drill 0.1)
		(layers "F.Cu" "B.Cu")
		(net 51)
	)
	(via
		(at 121.68675 141.355466)
		(size 0.45)
		(drill 0.1)
		(layers "F.Cu" "B.Cu")
		(net 51)
	)
	(via
		(at 124.68175 145.955466)
		(size 0.45)
		(drill 0.1)
		(layers "F.Cu" "B.Cu")
		(net 51)
	)
	(via
		(at 127.255 115.049251)
		(size 0.45)
		(drill 0.1)
		(layers "F.Cu" "B.Cu")
		(net 51)
	)
	(via
		(at 140.1 132.6)
		(size 0.45)
		(drill 0.1)
		(layers "F.Cu" "B.Cu")
		(net 51)
	)
	(via
		(at 118.98175 145.955466)
		(size 0.45)
		(drill 0.1)
		(layers "F.Cu" "B.Cu")
		(net 51)
	)
	(via
		(at 115.456486 145.958861)
		(size 0.45)
		(drill 0.1)
		(layers "F.Cu" "B.Cu")
		(net 51)
	)
	(via
		(at 128.005 115.614751)
		(size 0.45)
		(drill 0.1)
		(layers "F.Cu" "B.Cu")
		(net 51)
	)
	(via
		(at 132.363 140.100499)
		(size 0.45)
		(drill 0.1)
		(layers "F.Cu" "B.Cu")
		(free yes)
		(net 51)
	)
	(via
		(at 131.25 102.3)
		(size 0.45)
		(drill 0.1)
		(layers "F.Cu" "B.Cu")
		(net 51)
	)
	(via
		(at 120.69 119.73)
		(size 0.45)
		(drill 0.1)
		(layers "F.Cu" "B.Cu")
		(free yes)
		(net 51)
	)
	(via
		(at 139.84 104.426)
		(size 0.45)
		(drill 0.1)
		(layers "F.Cu" "B.Cu")
		(net 51)
	)
	(via
		(at 119.90875 143.768466)
		(size 0.45)
		(drill 0.1)
		(layers "F.Cu" "B.Cu")
		(net 51)
	)
	(via
		(at 111.72 133.44)
		(size 0.45)
		(drill 0.1)
		(layers "F.Cu" "B.Cu")
		(free yes)
		(net 51)
	)
	(via
		(at 112.35 141.25)
		(size 0.45)
		(drill 0.1)
		(layers "F.Cu" "B.Cu")
		(net 51)
	)
	(via
		(at 133.871 105.315)
		(size 0.45)
		(drill 0.1)
		(layers "F.Cu" "B.Cu")
		(net 51)
	)
	(via
		(at 128.75 145.8)
		(size 0.45)
		(drill 0.1)
		(layers "F.Cu" "B.Cu")
		(net 51)
	)
	(via
		(at 119.025 127.433)
		(size 0.45)
		(drill 0.1)
		(layers "F.Cu" "B.Cu")
		(net 51)
	)
	(via
		(at 140.1 140.5)
		(size 0.45)
		(drill 0.1)
		(layers "F.Cu" "B.Cu")
		(net 51)
	)
	(via
		(at 141.7 129.6)
		(size 0.45)
		(drill 0.1)
		(layers "F.Cu" "B.Cu")
		(net 51)
	)
	(via
		(at 116.74 122.74)
		(size 0.45)
		(drill 0.1)
		(layers "F.Cu" "B.Cu")
		(net 51)
	)
	(via
		(at 115.495 111.093751)
		(size 0.45)
		(drill 0.1)
		(layers "F.Cu" "B.Cu")
		(net 51)
	)
	(via
		(at 119.025 126.275)
		(size 0.45)
		(drill 0.1)
		(layers "F.Cu" "B.Cu")
		(net 51)
	)
	(via
		(at 115.95 143.95)
		(size 0.45)
		(drill 0.1)
		(layers "F.Cu" "B.Cu")
		(net 51)
	)
	(via
		(at 123.525 126.275)
		(size 0.45)
		(drill 0.1)
		(layers "F.Cu" "B.Cu")
		(net 51)
	)
	(via
		(at 124.255 116.207251)
		(size 0.45)
		(drill 0.1)
		(layers "F.Cu" "B.Cu")
		(net 51)
	)
	(via
		(at 140.7 141.45)
		(size 0.45)
		(drill 0.1)
		(layers "F.Cu" "B.Cu")
		(net 51)
	)
	(via
		(at 111.8 143.7)
		(size 0.45)
		(drill 0.1)
		(layers "F.Cu" "B.Cu")
		(net 51)
	)
	(via
		(at 146.7 143.8)
		(size 0.45)
		(drill 0.1)
		(layers "F.Cu" "B.Cu")
		(net 51)
	)
	(via
		(at 144.604 112.001)
		(size 0.45)
		(drill 0.1)
		(layers "F.Cu" "B.Cu")
		(net 51)
	)
	(via
		(at 126.505 115.614751)
		(size 0.45)
		(drill 0.1)
		(layers "F.Cu" "B.Cu")
		(net 51)
	)
	(via
		(at 115.495 113.973751)
		(size 0.45)
		(drill 0.1)
		(layers "F.Cu" "B.Cu")
		(net 51)
	)
	(via
		(at 117.18175 143.955466)
		(size 0.45)
		(drill 0.1)
		(layers "F.Cu" "B.Cu")
		(net 51)
	)
	(via
		(at 125.755 116.207251)
		(size 0.45)
		(drill 0.1)
		(layers "F.Cu" "B.Cu")
		(net 51)
	)
	(via
		(at 139.84 123.603)
		(size 0.45)
		(drill 0.1)
		(layers "F.Cu" "B.Cu")
		(net 51)
	)
	(via
		(at 134.125 104.426)
		(size 0.45)
		(drill 0.1)
		(layers "F.Cu" "B.Cu")
		(net 51)
	)
	(via
		(at 141.65 116.5)
		(size 0.45)
		(drill 0.1)
		(layers "F.Cu" "B.Cu")
		(net 51)
	)
	(via
		(at 130.774 129.54775)
		(size 0.45)
		(drill 0.1)
		(layers "F.Cu" "B.Cu")
		(net 51)
	)
	(via
		(at 119.775 126.8675)
		(size 0.45)
		(drill 0.1)
		(layers "F.Cu" "B.Cu")
		(net 51)
	)
	(via
		(at 120.525 126.275)
		(size 0.45)
		(drill 0.1)
		(layers "F.Cu" "B.Cu")
		(net 51)
	)
	(via
		(at 112 122)
		(size 0.45)
		(drill 0.1)
		(layers "F.Cu" "B.Cu")
		(free yes)
		(net 51)
	)
	(via
		(at 136.15 100.4)
		(size 0.45)
		(drill 0.1)
		(layers "F.Cu" "B.Cu")
		(net 51)
	)
	(via
		(at 133.871 109.887)
		(size 0.45)
		(drill 0.1)
		(layers "F.Cu" "B.Cu")
		(net 51)
	)
	(via
		(at 130.774 126.66775)
		(size 0.45)
		(drill 0.1)
		(layers "F.Cu" "B.Cu")
		(net 51)
	)
	(via
		(at 128.4 103.75)
		(size 0.45)
		(drill 0.1)
		(layers "F.Cu" "B.Cu")
		(net 51)
	)
	(via
		(at 118.17875 143.551569)
		(size 0.45)
		(drill 0.1)
		(layers "F.Cu" "B.Cu")
		(net 51)
	)
	(via
		(at 145.554 107.6)
		(size 0.45)
		(drill 0.1)
		(layers "F.Cu" "B.Cu")
		(net 51)
	)
	(via
		(at 133.871 118.777)
		(size 0.45)
		(drill 0.1)
		(layers "F.Cu" "B.Cu")
		(net 51)
	)
	(via
		(at 127.255 116.207251)
		(size 0.45)
		(drill 0.1)
		(layers "F.Cu" "B.Cu")
		(net 51)
	)
	(via
		(at 122.755 115.048251)
		(size 0.45)
		(drill 0.1)
		(layers "F.Cu" "B.Cu")
		(net 51)
	)
	(via
		(at 128.817501 140.1)
		(size 0.45)
		(drill 0.1)
		(layers "F.Cu" "B.Cu")
		(free yes)
		(net 51)
	)
	(via
		(at 139.84 113.951)
		(size 0.45)
		(drill 0.1)
		(layers "F.Cu" "B.Cu")
		(net 51)
	)
	(via
		(at 146.2 103.7)
		(size 0.45)
		(drill 0.1)
		(layers "F.Cu" "B.Cu")
		(net 51)
	)
	(via
		(at 140.3 128.1)
		(size 0.45)
		(drill 0.1)
		(layers "F.Cu" "B.Cu")
		(net 51)
	)
	(via
		(at 115.495 115.313751)
		(size 0.45)
		(drill 0.1)
		(layers "F.Cu" "B.Cu")
		(net 51)
	)
	(via
		(at 133.744 107.601)
		(size 0.45)
		(drill 0.1)
		(layers "F.Cu" "B.Cu")
		(net 51)
	)
	(via
		(at 122.775 126.8675)
		(size 0.45)
		(drill 0.1)
		(layers "F.Cu" "B.Cu")
		(net 51)
	)
	(via
		(at 121.94075 143.768466)
		(size 0.45)
		(drill 0.1)
		(layers "F.Cu" "B.Cu")
		(net 51)
	)
	(via
		(at 133.89648 132.391858)
		(size 0.45)
		(drill 0.1)
		(layers "F.Cu" "B.Cu")
		(net 51)
	)
	(via
		(at 123.2 136.9)
		(size 0.45)
		(drill 0.1)
		(layers "F.Cu" "B.Cu")
		(net 51)
	)
	(via
		(at 122.025 126.275)
		(size 0.45)
		(drill 0.1)
		(layers "F.Cu" "B.Cu")
		(net 51)
	)
	(arc
		(start 120.17875 144.245573)
		(mid 120.14069 144.054231)
		(end 120.032303 143.892019)
		(width 0.2)
		(layer "F.Cu")
		(net 51)
	)
	(arc
		(start 115.590882 145.499118)
		(mid 115.655914 145.401791)
		(end 115.67875 145.286986)
		(width 0.2)
		(layer "F.Cu")
		(net 51)
	)
	(arc
		(start 121.471643 141.570573)
		(mid 121.25487 141.894996)
		(end 121.17875 142.27768)
		(width 0.2)
		(layer "F.Cu")
		(net 51)
	)
	(arc
		(start 143.10832 119.45832)
		(mid 143.758639 120.43159)
		(end 143.987 121.579641)
		(width 0.4)
		(layer "F.Cu")
		(net 51)
	)
	(arc
		(start 116.503014 143.396986)
		(mid 116.633078 143.202332)
		(end 116.67875 142.972722)
		(width 0.2)
		(layer "F.Cu")
		(net 51)
	)
	(arc
		(start 122.67875 142.206244)
		(mid 122.724422 141.976634)
		(end 122.854486 141.78198)
		(width 0.2)
		(layer "F.Cu")
		(net 51)
	)
	(arc
		(start 115.456486 145.757778)
		(mid 115.479322 145.642973)
		(end 115.544354 145.545646)
		(width 0.2)
		(layer "F.Cu")
		(net 51)
	)
	(arc
		(start 140.045446 132.545446)
		(mid 139.883234 132.43706)
		(end 139.691893 132.399)
		(width 0.4)
		(layer "F.Cu")
		(net 51)
	)
	(arc
		(start 115.354486 143.354486)
		(mid 115.224422 143.159832)
		(end 115.17875 142.930222)
		(width 0.2)
		(layer "F.Cu")
		(net 51)
	)
	(arc
		(start 118.835303 145.495303)
		(mid 118.94369 145.657515)
		(end 118.98175 145.848857)
		(width 0.2)
		(layer "F.Cu")
		(net 51)
	)
	(arc
		(start 140.147446 128.252554)
		(mid 139.985234 128.36094)
		(end 139.793893 128.399)
		(width 0.4)
		(layer "F.Cu")
		(net 51)
	)
	(arc
		(start 121.67875 144.237573)
		(mid 121.71681 144.046231)
		(end 121.825197 143.884019)
		(width 0.2)
		(layer "F.Cu")
		(net 51)
	)
	(arc
		(start 118.825196 145.485196)
		(mid 118.71681 145.322984)
		(end 118.67875 145.131643)
		(width 0.2)
		(layer "F.Cu")
		(net 51)
	)
	(arc
		(start 129.005 117.072107)
		(mid 128.96694 116.880765)
		(end 128.858553 116.718553)
		(width 0.2)
		(layer "F.Cu")
		(net 51)
	)
	(arc
		(start 146.128892 142.623998)
		(mid 146.320235 142.662058)
		(end 146.482448 142.770446)
		(width 0.4)
		(layer "F.Cu")
		(net 51)
	)
	(segment
		(start 117.03 128.28)
		(end 117.18 128.28)
		(width 0.4)
		(layer "B.Cu")
		(net 51)
	)
	(segment
		(start 130.274 126.66775)
		(end 130.774 126.66775)
		(width 0.4)
		(layer "B.Cu")
		(net 51)
	)
	(segment
		(start 130.274 128.00775)
		(end 130.774 128.00775)
		(width 0.4)
		(layer "B.Cu")
		(net 51)
	)
	(segment
		(start 115.495 111.093751)
		(end 115.995 111.093751)
		(width 0.4)
		(layer "B.Cu")
		(net 51)
	)
	(segment
		(start 128.547196 114.902804)
		(end 129.093554 114.356446)
		(width 0.4)
		(layer "B.Cu")
		(net 51)
	)
	(segment
		(start 115.495 116.653751)
		(end 115.995 116.653751)
		(width 0.4)
		(layer "B.Cu")
		(net 51)
	)
	(segment
		(start 117.18 128.28)
		(end 118.027 127.433)
		(width 0.4)
		(layer "B.Cu")
		(net 51)
	)
	(segment
		(start 130.274 130.88775)
		(end 130.774 130.88775)
		(width 0.4)
		(layer "B.Cu")
		(net 51)
	)
	(segment
		(start 115.495 112.433751)
		(end 115.995 112.433751)
		(width 0.4)
		(layer "B.Cu")
		(net 51)
	)
	(segment
		(start 130.274 125.32775)
		(end 130.774 125.32775)
		(width 0.4)
		(layer "B.Cu")
		(net 51)
	)
	(segment
		(start 115.495 115.313751)
		(end 115.995 115.313751)
		(width 0.4)
		(layer "B.Cu")
		(net 51)
	)
	(segment
		(start 118.027 127.433)
		(end 118.275 127.433)
		(width 0.4)
		(layer "B.Cu")
		(net 51)
	)
	(segment
		(start 128.005 115.049251)
		(end 128.193642 115.049251)
		(width 0.4)
		(layer "B.Cu")
		(net 51)
	)
	(segment
		(start 115.495 113.973751)
		(end 115.995 113.973751)
		(width 0.4)
		(layer "B.Cu")
		(net 51)
	)
	(segment
		(start 129.24 114.002893)
		(end 129.24 113.79)
		(width 0.4)
		(layer "B.Cu")
		(net 51)
	)
	(segment
		(start 130.284 123.78775)
		(end 130.784 123.78775)
		(width 0.4)
		(layer "B.Cu")
		(net 51)
	)
	(segment
		(start 130.274 129.54775)
		(end 130.774 129.54775)
		(width 0.4)
		(layer "B.Cu")
		(net 51)
	)
	(segment
		(start 115.995 118.193751)
		(end 115.495 118.193751)
		(width 0.4)
		(layer "B.Cu")
		(net 51)
	)
	(arc
		(start 128.547196 114.902804)
		(mid 128.384984 115.011191)
		(end 128.193642 115.049251)
		(width 0.4)
		(layer "B.Cu")
		(net 51)
	)
	(arc
		(start 129.24 114.002893)
		(mid 129.20194 114.194234)
		(end 129.093554 114.356446)
		(width 0.4)
		(layer "B.Cu")
		(net 51)
	)
	(segment
		(start 142.05 121.398528)
		(end 142.05 125.034315)
		(width 0.2)
		(layer "F.Cu")
		(net 52)
	)
	(segment
		(start 142.167158 125.317158)
		(end 142.2 125.35)
		(width 0.2)
		(layer "F.Cu")
		(net 52)
	)
	(segment
		(start 143.046 125.5)
		(end 143.046 126.671)
		(width 0.4)
		(layer "F.Cu")
		(net 52)
	)
	(segment
		(start 142.313264 120.886736)
		(end 142.225736 120.974264)
		(width 0.2)
		(layer "F.Cu")
		(net 52)
	)
	(segment
		(start 143.046 120.711)
		(end 142.737528 120.711)
		(width 0.2)
		(layer "F.Cu")
		(net 52)
	)
	(via
		(at 140.965531 135.268938)
		(size 0.45)
		(drill 0.1)
		(layers "F.Cu" "B.Cu")
		(net 52)
	)
	(arc
		(start 142.05 121.398528)
		(mid 142.095672 121.168918)
		(end 142.225736 120.974264)
		(width 0.2)
		(layer "F.Cu")
		(net 52)
	)
	(arc
		(start 142.05 125.034315)
		(mid 142.080448 125.187389)
		(end 142.167158 125.317158)
		(width 0.2)
		(layer "F.Cu")
		(net 52)
	)
	(arc
		(start 142.313264 120.886736)
		(mid 142.507918 120.756672)
		(end 142.737528 120.711)
		(width 0.2)
		(layer "F.Cu")
		(net 52)
	)
	(segment
		(start 140.965531 135.268938)
		(end 142.334469 135.268938)
		(width 0.2)
		(layer "B.Cu")
		(net 52)
	)
	(segment
		(start 120.67875 144.815466)
		(end 120.67875 143.780701)
		(width 0.185)
		(layer "F.Cu")
		(net 53)
	)
	(segment
		(start 139.861002 110.563001)
		(end 140.434045 110.563001)
		(width 0.185)
		(layer "F.Cu")
		(net 53)
	)
	(segment
		(start 140.434045 110.563001)
		(end 140.591544 110.7205)
		(width 0.185)
		(layer "F.Cu")
		(net 53)
	)
	(segment
		(start 139.627001 110.797)
		(end 139.861001 110.563)
		(width 0.185)
		(layer "F.Cu")
		(net 53)
	)
	(segment
		(start 120.67875 143.780701)
		(end 120.60625 143.708201)
		(width 0.185)
		(layer "F.Cu")
		(net 53)
	)
	(segment
		(start 138.802 110.797)
		(end 139.627001 110.797)
		(width 0.185)
		(layer "F.Cu")
		(net 53)
	)
	(segment
		(start 139.861001 110.563)
		(end 139.861002 110.563001)
		(width 0.185)
		(layer "F.Cu")
		(net 53)
	)
	(via
		(at 140.591544 110.7205)
		(size 0.45)
		(drill 0.1)
		(layers "F.Cu" "B.Cu")
		(net 53)
	)
	(via
		(at 120.60625 143.708201)
		(size 0.45)
		(drill 0.1)
		(layers "F.Cu" "B.Cu")
		(net 53)
	)
	(segment
		(start 140.591544 110.7205)
		(end 140.749043 110.563001)
		(width 0.185)
		(layer "B.Cu")
		(net 53)
	)
	(segment
		(start 140.749043 110.563001)
		(end 141.326133 110.562993)
		(width 0.185)
		(layer "B.Cu")
		(net 53)
	)
	(segment
		(start 140.774135 98.584991)
		(end 125.870865 98.584991)
		(width 0.185)
		(layer "B.Cu")
		(net 53)
	)
	(segment
		(start 143.834987 108.054128)
		(end 143.835008 101.645866)
		(width 0.185)
		(layer "B.Cu")
		(net 53)
	)
	(segment
		(start 142.033227 110.2701)
		(end 143.542094 108.761232)
		(width 0.185)
		(layer "B.Cu")
		(net 53)
	)
	(segment
		(start 112.882907 132.691233)
		(end 120.567514 140.375855)
		(width 0.185)
		(layer "B.Cu")
		(net 53)
	)
	(segment
		(start 125.163758 98.877884)
		(end 112.882884 111.158758)
		(width 0.185)
		(layer "B.Cu")
		(net 53)
	)
	(segment
		(start 143.542114 100.938756)
		(end 141.481242 98.877884)
		(width 0.185)
		(layer "B.Cu")
		(net 53)
	)
	(segment
		(start 112.589991 111.865865)
		(end 112.590014 131.984128)
		(width 0.185)
		(layer "B.Cu")
		(net 53)
	)
	(segment
		(start 120.763752 140.849617)
		(end 120.763749 143.550702)
		(width 0.185)
		(layer "B.Cu")
		(net 53)
	)
	(segment
		(start 120.763749 143.550702)
		(end 120.60625 143.708201)
		(width 0.185)
		(layer "B.Cu")
		(net 53)
	)
	(arc
		(start 120.763752 140.849617)
		(mid 120.712752 140.593219)
		(end 120.567514 140.375855)
		(width 0.185)
		(layer "B.Cu")
		(net 53)
	)
	(arc
		(start 125.870865 98.584991)
		(mid 125.488182 98.661111)
		(end 125.163758 98.877884)
		(width 0.185)
		(layer "B.Cu")
		(net 53)
	)
	(arc
		(start 143.542114 100.938756)
		(mid 143.758888 101.263181)
		(end 143.835008 101.645866)
		(width 0.185)
		(layer "B.Cu")
		(net 53)
	)
	(arc
		(start 143.542094 108.761232)
		(mid 143.758866 108.43681)
		(end 143.834987 108.054128)
		(width 0.185)
		(layer "B.Cu")
		(net 53)
	)
	(arc
		(start 142.033227 110.2701)
		(mid 141.70881 110.48687)
		(end 141.326133 110.562993)
		(width 0.185)
		(layer "B.Cu")
		(net 53)
	)
	(arc
		(start 140.774135 98.584991)
		(mid 141.156818 98.661111)
		(end 141.481242 98.877884)
		(width 0.185)
		(layer "B.Cu")
		(net 53)
	)
	(arc
		(start 112.590014 131.984128)
		(mid 112.666135 132.366811)
		(end 112.882907 132.691233)
		(width 0.185)
		(layer "B.Cu")
		(net 53)
	)
	(arc
		(start 112.589991 111.865865)
		(mid 112.666111 111.483181)
		(end 112.882884 111.158758)
		(width 0.185)
		(layer "B.Cu")
		(net 53)
	)
	(segment
		(start 119.825197 145.725197)
		(end 119.853554 145.753554)
		(width 0.2)
		(layer "F.Cu")
		(net 54)
	)
	(segment
		(start 119.67875 144.864536)
		(end 119.67875 145.371643)
		(width 0.2)
		(layer "F.Cu")
		(net 54)
	)
	(segment
		(start 141.247 146.753)
		(end 141.247 145.889)
		(width 0.2)
		(layer "F.Cu")
		(net 54)
	)
	(segment
		(start 120.207107 145.9)
		(end 120.3 145.9)
		(width 0.2)
		(layer "F.Cu")
		(net 54)
	)
	(via
		(at 120.3 145.9)
		(size 0.45)
		(drill 0.1)
		(layers "F.Cu" "B.Cu")
		(net 54)
	)
	(via
		(at 141.247 146.753)
		(size 0.45)
		(drill 0.1)
		(layers "F.Cu" "B.Cu")
		(net 54)
	)
	(arc
		(start 119.853554 145.753554)
		(mid 120.015766 145.86194)
		(end 120.207107 145.9)
		(width 0.2)
		(layer "F.Cu")
		(net 54)
	)
	(arc
		(start 119.67875 145.371643)
		(mid 119.71681 145.562985)
		(end 119.825197 145.725197)
		(width 0.2)
		(layer "F.Cu")
		(net 54)
	)
	(segment
		(start 130.245784 138.100004)
		(end 132.09579 138.100004)
		(width 0.2)
		(layer "B.Cu")
		(net 54)
	)
	(segment
		(start 134.224211 148.499997)
		(end 139.785787 148.499997)
		(width 0.2)
		(layer "B.Cu")
		(net 54)
	)
	(segment
		(start 134.05 140.054214)
		(end 134.05 140.725786)
		(width 0.2)
		(layer "B.Cu")
		(net 54)
	)
	(segment
		(start 132.802897 138.392897)
		(end 133.757107 139.347107)
		(width 0.2)
		(layer "B.Cu")
		(net 54)
	)
	(segment
		(start 120.3 145.9)
		(end 120.58579 145.899998)
		(width 0.2)
		(layer "B.Cu")
		(net 54)
	)
	(segment
		(start 122.495626 139.797235)
		(end 123.900001 138.392885)
		(width 0.2)
		(layer "B.Cu")
		(net 54)
	)
	(segment
		(start 124.607102 138.099998)
		(end 130.245784 138.100004)
		(width 0.2)
		(layer "B.Cu")
		(net 54)
	)
	(segment
		(start 140.492889 148.207108)
		(end 140.954104 147.745898)
		(width 0.2)
		(layer "B.Cu")
		(net 54)
	)
	(segment
		(start 141.247002 147.03878)
		(end 141.247 146.753)
		(width 0.2)
		(layer "B.Cu")
		(net 54)
	)
	(segment
		(start 122.353558 142.453565)
		(end 122.349189 142.449196)
		(width 0.2)
		(layer "B.Cu")
		(net 54)
	)
	(segment
		(start 132.392889 147.082889)
		(end 133.517104 148.207104)
		(width 0.2)
		(layer "B.Cu")
		(net 54)
	)
	(segment
		(start 122.202743 142.095648)
		(end 122.202727 140.504358)
		(width 0.2)
		(layer "B.Cu")
		(net 54)
	)
	(segment
		(start 133.757107 141.432893)
		(end 132.392889 142.797111)
		(width 0.2)
		(layer "B.Cu")
		(net 54)
	)
	(segment
		(start 132.099996 143.504218)
		(end 132.099996 146.375782)
		(width 0.2)
		(layer "B.Cu")
		(net 54)
	)
	(segment
		(start 122.500005 143.985785)
		(end 122.500005 142.807119)
		(width 0.2)
		(layer "B.Cu")
		(net 54)
	)
	(segment
		(start 121.292888 145.607108)
		(end 122.207109 144.692895)
		(width 0.2)
		(layer "B.Cu")
		(net 54)
	)
	(arc
		(start 122.349189 142.449196)
		(mid 122.240804 142.286987)
		(end 122.202743 142.095648)
		(width 0.2)
		(layer "B.Cu")
		(net 54)
	)
	(arc
		(start 132.099996 143.504218)
		(mid 132.176116 143.121535)
		(end 132.392889 142.797111)
		(width 0.2)
		(layer "B.Cu")
		(net 54)
	)
	(arc
		(start 122.202727 140.504358)
		(mid 122.278847 140.121665)
		(end 122.495626 139.797235)
		(width 0.2)
		(layer "B.Cu")
		(net 54)
	)
	(arc
		(start 133.517104 148.207104)
		(mid 133.841527 148.423877)
		(end 134.224211 148.499997)
		(width 0.2)
		(layer "B.Cu")
		(net 54)
	)
	(arc
		(start 132.09579 138.100004)
		(mid 132.478473 138.176124)
		(end 132.802897 138.392897)
		(width 0.2)
		(layer "B.Cu")
		(net 54)
	)
	(arc
		(start 122.500005 142.807119)
		(mid 122.461945 142.615777)
		(end 122.353558 142.453565)
		(width 0.2)
		(layer "B.Cu")
		(net 54)
	)
	(arc
		(start 120.58579 145.899998)
		(mid 120.968468 145.823877)
		(end 121.292888 145.607108)
		(width 0.2)
		(layer "B.Cu")
		(net 54)
	)
	(arc
		(start 133.757107 139.347107)
		(mid 133.97388 139.67153)
		(end 134.05 140.054214)
		(width 0.2)
		(layer "B.Cu")
		(net 54)
	)
	(arc
		(start 140.954104 147.745898)
		(mid 141.170881 147.42147)
		(end 141.247002 147.03878)
		(width 0.2)
		(layer "B.Cu")
		(net 54)
	)
	(arc
		(start 122.207109 144.692895)
		(mid 122.423884 144.368471)
		(end 122.500005 143.985785)
		(width 0.2)
		(layer "B.Cu")
		(net 54)
	)
	(arc
		(start 132.099996 146.375782)
		(mid 132.176116 146.758466)
		(end 132.392889 147.082889)
		(width 0.2)
		(layer "B.Cu")
		(net 54)
	)
	(arc
		(start 139.785787 148.499997)
		(mid 140.168467 148.423878)
		(end 140.492889 148.207108)
		(width 0.2)
		(layer "B.Cu")
		(net 54)
	)
	(arc
		(start 123.900001 138.392885)
		(mid 124.224422 138.176117)
		(end 124.607102 138.099998)
		(width 0.2)
		(layer "B.Cu")
		(net 54)
	)
	(arc
		(start 133.757107 141.432893)
		(mid 133.97388 141.10847)
		(end 134.05 140.725786)
		(width 0.2)
		(layer "B.Cu")
		(net 54)
	)
	(segment
		(start 138.802 109.999)
		(end 139.627001 109.999)
		(width 0.185)
		(layer "F.Cu")
		(net 55)
	)
	(segment
		(start 121.17875 144.815466)
		(end 121.17875 143.780701)
		(width 0.185)
		(layer "F.Cu")
		(net 55)
	)
	(segment
		(start 139.861001 110.233)
		(end 139.861002 110.232999)
		(width 0.185)
		(layer "F.Cu")
		(net 55)
	)
	(segment
		(start 139.861002 110.232999)
		(end 140.434045 110.232999)
		(width 0.185)
		(layer "F.Cu")
		(net 55)
	)
	(segment
		(start 139.627001 109.999)
		(end 139.861001 110.233)
		(width 0.185)
		(layer "F.Cu")
		(net 55)
	)
	(segment
		(start 140.434045 110.232999)
		(end 140.591544 110.0755)
		(width 0.185)
		(layer "F.Cu")
		(net 55)
	)
	(segment
		(start 121.17875 143.780701)
		(end 121.25125 143.708201)
		(width 0.185)
		(layer "F.Cu")
		(net 55)
	)
	(via
		(at 121.25125 143.708201)
		(size 0.45)
		(drill 0.1)
		(layers "F.Cu" "B.Cu")
		(net 55)
	)
	(via
		(at 140.591544 110.0755)
		(size 0.45)
		(drill 0.1)
		(layers "F.Cu" "B.Cu")
		(net 55)
	)
	(segment
		(start 119.474086 105.03426)
		(end 120.814063 103.694283)
		(width 0.185)
		(layer "B.Cu")
		(net 55)
	)
	(segment
		(start 122.815807 102.301915)
		(end 122.886517 102.231204)
		(width 0.185)
		(layer "B.Cu")
		(net 55)
	)
	(segment
		(start 122.86467 101.643672)
		(end 122.935383 101.572962)
		(width 0.185)
		(layer "B.Cu")
		(net 55)
	)
	(segment
		(start 119.474085 105.034259)
		(end 119.474086 105.03426)
		(width 0.185)
		(layer "B.Cu")
		(net 55)
	)
	(segment
		(start 141.326131 110.233007)
		(end 140.749043 110.232999)
		(width 0.185)
		(layer "B.Cu")
		(net 55)
	)
	(segment
		(start 121.521169 102.987176)
		(end 121.52117 102.987176)
		(width 0.185)
		(layer "B.Cu")
		(net 55)
	)
	(segment
		(start 121.093751 143.550702)
		(end 121.093759 140.849618)
		(width 0.185)
		(layer "B.Cu")
		(net 55)
	)
	(segment
		(start 122.108675 103.008996)
		(end 122.179385 102.938285)
		(width 0.185)
		(layer "B.Cu")
		(net 55)
	)
	(segment
		(start 143.505012 101.645865)
		(end 143.505012 108.054135)
		(width 0.185)
		(layer "B.Cu")
		(net 55)
	)
	(segment
		(start 124.37703 100.131369)
		(end 124.40089 100.107509)
		(width 0.185)
		(layer "B.Cu")
		(net 55)
	)
	(segment
		(start 121.450456 103.057886)
		(end 121.521169 102.987176)
		(width 0.185)
		(layer "B.Cu")
		(net 55)
	)
	(segment
		(start 123.256471 101.251955)
		(end 124.37703 100.131369)
		(width 0.185)
		(layer "B.Cu")
		(net 55)
	)
	(segment
		(start 122.886517 101.948361)
		(end 122.86467 101.926514)
		(width 0.185)
		(layer "B.Cu")
		(net 55)
	)
	(segment
		(start 123.256431 101.251915)
		(end 123.256471 101.251955)
		(width 0.185)
		(layer "B.Cu")
		(net 55)
	)
	(segment
		(start 122.157564 102.350778)
		(end 122.228276 102.280069)
		(width 0.185)
		(layer "B.Cu")
		(net 55)
	)
	(segment
		(start 121.401528 103.716064)
		(end 121.472238 103.645353)
		(width 0.185)
		(layer "B.Cu")
		(net 55)
	)
	(segment
		(start 140.749043 110.232999)
		(end 140.591544 110.0755)
		(width 0.185)
		(layer "B.Cu")
		(net 55)
	)
	(segment
		(start 121.096905 103.694283)
		(end 121.118686 103.716064)
		(width 0.185)
		(layer "B.Cu")
		(net 55)
	)
	(segment
		(start 122.228276 102.280069)
		(end 122.228277 102.280069)
		(width 0.185)
		(layer "B.Cu")
		(net 55)
	)
	(segment
		(start 120.800864 140.142507)
		(end 113.116227 132.457896)
		(width 0.185)
		(layer "B.Cu")
		(net 55)
	)
	(segment
		(start 122.179385 102.655442)
		(end 122.157564 102.633621)
		(width 0.185)
		(layer "B.Cu")
		(net 55)
	)
	(segment
		(start 112.919988 131.984134)
		(end 112.919988 111.865866)
		(width 0.185)
		(layer "B.Cu")
		(net 55)
	)
	(segment
		(start 121.472238 103.36251)
		(end 121.450456 103.340728)
		(width 0.185)
		(layer "B.Cu")
		(net 55)
	)
	(segment
		(start 122.935383 101.572962)
		(end 123.256431 101.251915)
		(width 0.185)
		(layer "B.Cu")
		(net 55)
	)
	(segment
		(start 125.870881 98.915016)
		(end 140.774134 98.914989)
		(width 0.185)
		(layer "B.Cu")
		(net 55)
	)
	(segment
		(start 121.25125 143.708201)
		(end 121.093751 143.550702)
		(width 0.185)
		(layer "B.Cu")
		(net 55)
	)
	(segment
		(start 143.308774 108.527896)
		(end 141.799902 110.036768)
		(width 0.185)
		(layer "B.Cu")
		(net 55)
	)
	(segment
		(start 124.40089 100.107509)
		(end 125.397115 99.11126)
		(width 0.185)
		(layer "B.Cu")
		(net 55)
	)
	(segment
		(start 121.804012 102.987176)
		(end 121.825832 103.008996)
		(width 0.185)
		(layer "B.Cu")
		(net 55)
	)
	(segment
		(start 113.116227 111.392104)
		(end 119.474085 105.034259)
		(width 0.185)
		(layer "B.Cu")
		(net 55)
	)
	(segment
		(start 141.247897 99.111227)
		(end 143.308773 101.172103)
		(width 0.185)
		(layer "B.Cu")
		(net 55)
	)
	(segment
		(start 122.511119 102.280069)
		(end 122.532965 102.301915)
		(width 0.185)
		(layer "B.Cu")
		(net 55)
	)
	(arc
		(start 121.118686 103.716064)
		(mid 121.260107 103.774642)
		(end 121.401528 103.716064)
		(width 0.185)
		(layer "B.Cu")
		(net 55)
	)
	(arc
		(start 122.886517 102.231204)
		(mid 122.945096 102.089782)
		(end 122.886517 101.948361)
		(width 0.185)
		(layer "B.Cu")
		(net 55)
	)
	(arc
		(start 121.472238 103.645353)
		(mid 121.530817 103.503931)
		(end 121.472238 103.36251)
		(width 0.185)
		(layer "B.Cu")
		(net 55)
	)
	(arc
		(start 120.814063 103.694283)
		(mid 120.955484 103.635705)
		(end 121.096905 103.694283)
		(width 0.185)
		(layer "B.Cu")
		(net 55)
	)
	(arc
		(start 122.86467 101.926514)
		(mid 122.806092 101.785093)
		(end 122.86467 101.643672)
		(width 0.185)
		(layer "B.Cu")
		(net 55)
	)
	(arc
		(start 121.450456 103.340728)
		(mid 121.391878 103.199307)
		(end 121.450456 103.057886)
		(width 0.185)
		(layer "B.Cu")
		(net 55)
	)
	(arc
		(start 143.505012 108.054135)
		(mid 143.454011 108.310533)
		(end 143.308774 108.527896)
		(width 0.185)
		(layer "B.Cu")
		(net 55)
	)
	(arc
		(start 113.116227 132.457896)
		(mid 112.970989 132.240532)
		(end 112.919988 131.984134)
		(width 0.185)
		(layer "B.Cu")
		(net 55)
	)
	(arc
		(start 121.825832 103.008996)
		(mid 121.967254 103.067574)
		(end 122.108675 103.008996)
		(width 0.185)
		(layer "B.Cu")
		(net 55)
	)
	(arc
		(start 122.532965 102.301915)
		(mid 122.674386 102.360493)
		(end 122.815807 102.301915)
		(width 0.185)
		(layer "B.Cu")
		(net 55)
	)
	(arc
		(start 121.093759 140.849618)
		(mid 121.017638 140.466932)
		(end 120.800864 140.142507)
		(width 0.185)
		(layer "B.Cu")
		(net 55)
	)
	(arc
		(start 143.308773 101.172103)
		(mid 143.454011 101.389467)
		(end 143.505012 101.645865)
		(width 0.185)
		(layer "B.Cu")
		(net 55)
	)
	(arc
		(start 140.774134 98.914989)
		(mid 141.030532 98.96599)
		(end 141.247897 99.111227)
		(width 0.185)
		(layer "B.Cu")
		(net 55)
	)
	(arc
		(start 122.179385 102.938285)
		(mid 122.237964 102.796863)
		(end 122.179385 102.655442)
		(width 0.185)
		(layer "B.Cu")
		(net 55)
	)
	(arc
		(start 112.919988 111.865866)
		(mid 112.970989 111.609468)
		(end 113.116227 111.392104)
		(width 0.185)
		(layer "B.Cu")
		(net 55)
	)
	(arc
		(start 121.52117 102.987176)
		(mid 121.662591 102.928598)
		(end 121.804012 102.987176)
		(width 0.185)
		(layer "B.Cu")
		(net 55)
	)
	(arc
		(start 122.157564 102.633621)
		(mid 122.098985 102.4922)
		(end 122.157564 102.350778)
		(width 0.185)
		(layer "B.Cu")
		(net 55)
	)
	(arc
		(start 125.397115 99.11126)
		(mid 125.61448 98.966018)
		(end 125.870881 98.915016)
		(width 0.185)
		(layer "B.Cu")
		(net 55)
	)
	(arc
		(start 122.228277 102.280069)
		(mid 122.369698 102.221491)
		(end 122.511119 102.280069)
		(width 0.185)
		(layer "B.Cu")
		(net 55)
	)
	(arc
		(start 141.799902 110.036768)
		(mid 141.582534 110.182008)
		(end 141.326131 110.233007)
		(width 0.185)
		(layer "B.Cu")
		(net 55)
	)
	(segment
		(start 116.17875 141.942965)
		(end 116.09375 141.857965)
		(width 0.185)
		(layer "F.Cu")
		(net 56)
	)
	(segment
		(start 116.09375 141.857965)
		(end 116.09375 138.935001)
		(width 0.185)
		(layer "F.Cu")
		(net 56)
	)
	(segment
		(start 116.17875 142.625466)
		(end 116.17875 141.942965)
		(width 0.185)
		(layer "F.Cu")
		(net 56)
	)
	(segment
		(start 116.09375 138.935001)
		(end 116.41875 138.610001)
		(width 0.185)
		(layer "F.Cu")
		(net 56)
	)
	(segment
		(start 116.41875 138.610001)
		(end 116.41875 138.13)
		(width 0.185)
		(layer "F.Cu")
		(net 56)
	)
	(segment
		(start 123.36 129.282251)
		(end 123.275 129.197251)
		(width 0.185)
		(layer "F.Cu")
		(net 57)
	)
	(segment
		(start 123.360009 130.10913)
		(end 123.36 129.282251)
		(width 0.185)
		(layer "F.Cu")
		(net 57)
	)
	(segment
		(start 117.65 136.679999)
		(end 117.955 136.374999)
		(width 0.185)
		(layer "F.Cu")
		(net 57)
	)
	(segment
		(start 117.65 137.16)
		(end 117.65 136.679999)
		(width 0.185)
		(layer "F.Cu")
		(net 57)
	)
	(segment
		(start 118.247892 135.498751)
		(end 123.163769 130.5829)
		(width 0.185)
		(layer "F.Cu")
		(net 57)
	)
	(segment
		(start 123.275 129.197251)
		(end 123.275 128.541)
		(width 0.185)
		(layer "F.Cu")
		(net 57)
	)
	(segment
		(start 117.955 136.374999)
		(end 117.954997 136.205875)
		(width 0.185)
		(layer "F.Cu")
		(net 57)
	)
	(arc
		(start 123.163769 130.5829)
		(mid 123.309009 130.365533)
		(end 123.360009 130.10913)
		(width 0.185)
		(layer "F.Cu")
		(net 57)
	)
	(arc
		(start 117.954997 136.205875)
		(mid 118.031115 135.823182)
		(end 118.247892 135.498751)
		(width 0.185)
		(layer "F.Cu")
		(net 57)
	)
	(segment
		(start 117.17875 142.625466)
		(end 117.17875 141.942965)
		(width 0.185)
		(layer "F.Cu")
		(net 58)
	)
	(segment
		(start 117.26375 141.857965)
		(end 117.26375 141.07)
		(width 0.185)
		(layer "F.Cu")
		(net 58)
	)
	(segment
		(start 117.556651 140.385887)
		(end 117.758758 140.183787)
		(width 0.185)
		(layer "F.Cu")
		(net 58)
	)
	(segment
		(start 117.17875 141.942965)
		(end 117.26375 141.857965)
		(width 0.185)
		(layer "F.Cu")
		(net 58)
	)
	(segment
		(start 117.65 138.600001)
		(end 117.65 138.12)
		(width 0.185)
		(layer "F.Cu")
		(net 58)
	)
	(segment
		(start 117.955 138.905001)
		(end 117.65 138.600001)
		(width 0.185)
		(layer "F.Cu")
		(net 58)
	)
	(segment
		(start 117.955005 139.094118)
		(end 117.955005 139.719995)
		(width 0.185)
		(layer "F.Cu")
		(net 58)
	)
	(segment
		(start 117.955005 139.094118)
		(end 117.955 138.905001)
		(width 0.185)
		(layer "F.Cu")
		(net 58)
	)
	(arc
		(start 117.758758 140.183787)
		(mid 117.904005 139.966413)
		(end 117.955005 139.71)
		(width 0.185)
		(layer "F.Cu")
		(net 58)
	)
	(arc
		(start 117.556651 140.385887)
		(mid 117.339868 140.710317)
		(end 117.263745 141.093011)
		(width 0.185)
		(layer "F.Cu")
		(net 58)
	)
	(segment
		(start 138.802 114.797)
		(end 140.497 114.797)
		(width 0.2)
		(layer "F.Cu")
		(net 59)
	)
	(segment
		(start 122.5 139)
		(end 120.471643 141.028357)
		(width 0.2)
		(layer "F.Cu")
		(net 59)
	)
	(segment
		(start 120.17875 141.735464)
		(end 120.17875 142.625466)
		(width 0.2)
		(layer "F.Cu")
		(net 59)
	)
	(segment
		(start 140.497 114.797)
		(end 140.5 114.8)
		(width 0.2)
		(layer "F.Cu")
		(net 59)
	)
	(via
		(at 122.5 139)
		(size 0.45)
		(drill 0.1)
		(layers "F.Cu" "B.Cu")
		(net 59)
	)
	(via
		(at 140.5 114.8)
		(size 0.45)
		(drill 0.1)
		(layers "F.Cu" "B.Cu")
		(net 59)
	)
	(arc
		(start 120.471643 141.028357)
		(mid 120.25487 141.35278)
		(end 120.17875 141.735464)
		(width 0.2)
		(layer "F.Cu")
		(net 59)
	)
	(segment
		(start 132.43579 137.600004)
		(end 124.314215 137.600004)
		(width 0.2)
		(layer "B.Cu")
		(net 59)
	)
	(segment
		(start 144.507103 136.79289)
		(end 144.355012 136.944981)
		(width 0.2)
		(layer "B.Cu")
		(net 59)
	)
	(segment
		(start 138.82 116.588427)
		(end 138.82 118.271573)
		(width 0.2)
		(layer "B.Cu")
		(net 59)
	)
	(segment
		(start 140.5 114.8)
		(end 139.987107 114.8)
		(width 0.2)
		(layer "B.Cu")
		(net 59)
	)
	(segment
		(start 139.405787 119.685787)
		(end 139.535534 119.815534)
		(width 0.2)
		(layer "B.Cu")
		(net 59)
	)
	(segment
		(start 133.837107 138.587107)
		(end 133.142897 137.892897)
		(width 0.2)
		(layer "B.Cu")
		(net 59)
	)
	(segment
		(start 142.464466 127.364466)
		(end 143.33553 128.23553)
		(width 0.2)
		(layer "B.Cu")
		(net 59)
	)
	(segment
		(start 139.633553 114.946447)
		(end 139.405786 115.174214)
		(width 0.2)
		(layer "B.Cu")
		(net 59)
	)
	(segment
		(start 143.647911 137.237873)
		(end 140.996319 137.237889)
		(width 0.2)
		(layer "B.Cu")
		(net 59)
	)
	(segment
		(start 123.60711 137.892896)
		(end 122.5 139)
		(width 0.2)
		(layer "B.Cu")
		(net 59)
	)
	(segment
		(start 141 123.351068)
		(end 141 123.828932)
		(width 0.2)
		(layer "B.Cu")
		(net 59)
	)
	(segment
		(start 140.289218 137.530782)
		(end 139.232893 138.587107)
		(width 0.2)
		(layer "B.Cu")
		(net 59)
	)
	(segment
		(start 144.799996 131.771064)
		(end 144.799996 136.085784)
		(width 0.2)
		(layer "B.Cu")
		(net 59)
	)
	(segment
		(start 138.525786 138.88)
		(end 134.544214 138.88)
		(width 0.2)
		(layer "B.Cu")
		(net 59)
	)
	(arc
		(start 144.799996 131.771064)
		(mid 144.419394 129.857647)
		(end 143.33553 128.23553)
		(width 0.2)
		(layer "B.Cu")
		(net 59)
	)
	(arc
		(start 142.464466 127.364466)
		(mid 141.380602 125.742349)
		(end 141 123.828932)
		(width 0.2)
		(layer "B.Cu")
		(net 59)
	)
	(arc
		(start 139.535534 119.815534)
		(mid 140.619398 121.437651)
		(end 141 123.351068)
		(width 0.2)
		(layer "B.Cu")
		(net 59)
	)
	(arc
		(start 124.314215 137.600004)
		(mid 123.931533 137.676124)
		(end 123.60711 137.892896)
		(width 0.2)
		(layer "B.Cu")
		(net 59)
	)
	(arc
		(start 139.987107 114.8)
		(mid 139.795765 114.83806)
		(end 139.633553 114.946447)
		(width 0.2)
		(layer "B.Cu")
		(net 59)
	)
	(arc
		(start 133.142897 137.892897)
		(mid 132.818474 137.676124)
		(end 132.43579 137.600004)
		(width 0.2)
		(layer "B.Cu")
		(net 59)
	)
	(arc
		(start 139.405786 115.174214)
		(mid 138.972241 115.82306)
		(end 138.82 116.588427)
		(width 0.2)
		(layer "B.Cu")
		(net 59)
	)
	(arc
		(start 140.996319 137.237889)
		(mid 140.613639 137.314011)
		(end 140.289218 137.530782)
		(width 0.2)
		(layer "B.Cu")
		(net 59)
	)
	(arc
		(start 134.544214 138.88)
		(mid 134.16153 138.80388)
		(end 133.837107 138.587107)
		(width 0.2)
		(layer "B.Cu")
		(net 59)
	)
	(arc
		(start 144.355012 136.944981)
		(mid 144.030591 137.161752)
		(end 143.647911 137.237873)
		(width 0.2)
		(layer "B.Cu")
		(net 59)
	)
	(arc
		(start 144.799996 136.085784)
		(mid 144.723876 136.468467)
		(end 144.507103 136.79289)
		(width 0.2)
		(layer "B.Cu")
		(net 59)
	)
	(arc
		(start 139.232893 138.587107)
		(mid 138.908469 138.80388)
		(end 138.525786 138.88)
		(width 0.2)
		(layer "B.Cu")
		(net 59)
	)
	(arc
		(start 138.82 118.271573)
		(mid 138.972241 119.03694)
		(end 139.405787 119.685787)
		(width 0.2)
		(layer "B.Cu")
		(net 59)
	)
	(segment
		(start 118.59 136.679999)
		(end 118.285 136.374999)
		(width 0.185)
		(layer "F.Cu")
		(net 60)
	)
	(segment
		(start 118.285 136.374999)
		(end 118.284995 136.205877)
		(width 0.185)
		(layer "F.Cu")
		(net 60)
	)
	(segment
		(start 118.59 137.16)
		(end 118.59 136.679999)
		(width 0.185)
		(layer "F.Cu")
		(net 60)
	)
	(segment
		(start 118.481235 135.732096)
		(end 123.397111 130.816246)
		(width 0.185)
		(layer "F.Cu")
		(net 60)
	)
	(segment
		(start 123.69 129.282251)
		(end 123.775 129.197251)
		(width 0.185)
		(layer "F.Cu")
		(net 60)
	)
	(segment
		(start 123.690006 130.10913)
		(end 123.69 129.282251)
		(width 0.185)
		(layer "F.Cu")
		(net 60)
	)
	(segment
		(start 123.775 129.197251)
		(end 123.775 128.541)
		(width 0.185)
		(layer "F.Cu")
		(net 60)
	)
	(arc
		(start 123.690006 130.10913)
		(mid 123.613886 130.491819)
		(end 123.397111 130.816246)
		(width 0.185)
		(layer "F.Cu")
		(net 60)
	)
	(arc
		(start 118.284995 136.205877)
		(mid 118.335993 135.949468)
		(end 118.481235 135.732096)
		(width 0.185)
		(layer "F.Cu")
		(net 60)
	)
	(segment
		(start 132.775004 125.935789)
		(end 132.775002 117.792106)
		(width 0.2)
		(layer "F.Cu")
		(net 61)
	)
	(segment
		(start 138.802 129.197)
		(end 140.007893 129.197)
		(width 0.2)
		(layer "F.Cu")
		(net 61)
	)
	(segment
		(start 132.152893 117.169999)
		(end 131.93 117.17)
		(width 0.2)
		(layer "F.Cu")
		(net 61)
	)
	(segment
		(start 133.1321 126.7071)
		(end 133.06789 126.642889)
		(width 0.2)
		(layer "F.Cu")
		(net 61)
	)
	(segment
		(start 123.12 135.09)
		(end 121.73 136.48)
		(width 0.2)
		(layer "F.Cu")
		(net 61)
	)
	(segment
		(start 133.875 127)
		(end 133.839225 127)
		(width 0.2)
		(layer "F.Cu")
		(net 61)
	)
	(segment
		(start 132.628555 117.438552)
		(end 132.506448 117.316445)
		(width 0.2)
		(layer "F.Cu")
		(net 61)
	)
	(segment
		(start 140.361447 129.050553)
		(end 140.475 128.937)
		(width 0.2)
		(layer "F.Cu")
		(net 61)
	)
	(via
		(at 133.875 127)
		(size 0.45)
		(drill 0.1)
		(layers "F.Cu" "B.Cu")
		(net 61)
	)
	(via
		(at 140.475 128.937)
		(size 0.45)
		(drill 0.1)
		(layers "F.Cu" "B.Cu")
		(net 61)
	)
	(via
		(at 123.12 135.091158)
		(size 0.45)
		(drill 0.1)
		(layers "F.Cu" "B.Cu")
		(net 61)
	)
	(arc
		(start 140.007893 129.197)
		(mid 140.199235 129.15894)
		(end 140.361447 129.050553)
		(width 0.2)
		(layer "F.Cu")
		(net 61)
	)
	(arc
		(start 132.152893 117.169999)
		(mid 132.344235 117.208059)
		(end 132.506448 117.316445)
		(width 0.2)
		(layer "F.Cu")
		(net 61)
	)
	(arc
		(start 132.775002 117.792106)
		(mid 132.736942 117.600764)
		(end 132.628555 117.438552)
		(width 0.2)
		(layer "F.Cu")
		(net 61)
	)
	(arc
		(start 132.775004 125.935789)
		(mid 132.851123 126.318468)
		(end 133.06789 126.642889)
		(width 0.2)
		(layer "F.Cu")
		(net 61)
	)
	(arc
		(start 133.839225 127)
		(mid 133.456531 126.92388)
		(end 133.1321 126.7071)
		(width 0.2)
		(layer "F.Cu")
		(net 61)
	)
	(segment
		(start 140.9 128.014204)
		(end 140.900001 128.097777)
		(width 0.2)
		(layer "B.Cu")
		(net 61)
	)
	(segment
		(start 114.022893 131.772893)
		(end 116.755372 134.505372)
		(width 0.2)
		(layer "B.Cu")
		(net 61)
	)
	(segment
		(start 129.780415 135.091158)
		(end 126.45 135.091158)
		(width 0.2)
		(layer "B.Cu")
		(net 61)
	)
	(segment
		(start 118.169585 135.091158)
		(end 123.12 135.091158)
		(width 0.2)
		(layer "B.Cu")
		(net 61)
	)
	(segment
		(start 133.121322 127.292893)
		(end 132.842893 127.571322)
		(width 0.2)
		(layer "B.Cu")
		(net 61)
	)
	(segment
		(start 131.964213 133.735787)
		(end 131.194628 134.505372)
		(width 0.2)
		(layer "B.Cu")
		(net 61)
	)
	(segment
		(start 139.88578 126.999995)
		(end 133.875 127)
		(width 0.2)
		(layer "B.Cu")
		(net 61)
	)
	(segment
		(start 140.607103 128.804899)
		(end 140.475 128.937)
		(width 0.2)
		(layer "B.Cu")
		(net 61)
	)
	(segment
		(start 140.607114 127.307115)
		(end 140.592896 127.292896)
		(width 0.2)
		(layer "B.Cu")
		(net 61)
	)
	(segment
		(start 126.45 136.3)
		(end 126.45 135.091158)
		(width 0.2)
		(layer "B.Cu")
		(net 61)
	)
	(segment
		(start 132.55 128.278429)
		(end 132.55 132.321573)
		(width 0.2)
		(layer "B.Cu")
		(net 61)
	)
	(segment
		(start 123.12 135.091158)
		(end 126.45 135.091158)
		(width 0.2)
		(layer "B.Cu")
		(net 61)
	)
	(segment
		(start 113.73 130.76)
		(end 113.73 131.065786)
		(width 0.2)
		(layer "B.Cu")
		(net 61)
	)
	(segment
		(start 133.875 127)
		(end 133.828424 127)
		(width 0.2)
		(layer "B.Cu")
		(net 61)
	)
	(arc
		(start 140.9 128.014204)
		(mid 140.82388 127.631531)
		(end 140.607114 127.307115)
		(width 0.2)
		(layer "B.Cu")
		(net 61)
	)
	(arc
		(start 131.964213 133.735787)
		(mid 132.397759 133.08694)
		(end 132.55 132.321573)
		(width 0.2)
		(layer "B.Cu")
		(net 61)
	)
	(arc
		(start 113.73 131.065786)
		(mid 113.80612 131.448469)
		(end 114.022893 131.772893)
		(width 0.2)
		(layer "B.Cu")
		(net 61)
	)
	(arc
		(start 116.755372 134.505372)
		(mid 117.404218 134.938917)
		(end 118.169585 135.091158)
		(width 0.2)
		(layer "B.Cu")
		(net 61)
	)
	(arc
		(start 132.842893 127.571322)
		(mid 132.62612 127.895745)
		(end 132.55 128.278429)
		(width 0.2)
		(layer "B.Cu")
		(net 61)
	)
	(arc
		(start 139.88578 126.999995)
		(mid 140.268469 127.076117)
		(end 140.592896 127.292896)
		(width 0.2)
		(layer "B.Cu")
		(net 61)
	)
	(arc
		(start 140.900001 128.097777)
		(mid 140.823881 128.480469)
		(end 140.607103 128.804899)
		(width 0.2)
		(layer "B.Cu")
		(net 61)
	)
	(arc
		(start 129.780415 135.091158)
		(mid 130.545782 134.938917)
		(end 131.194628 134.505372)
		(width 0.2)
		(layer "B.Cu")
		(net 61)
	)
	(arc
		(start 133.828424 127)
		(mid 133.445743 127.076121)
		(end 133.121322 127.292893)
		(width 0.2)
		(layer "B.Cu")
		(net 61)
	)
	(segment
		(start 117.67875 142.625466)
		(end 117.67875 141.942965)
		(width 0.185)
		(layer "F.Cu")
		(net 62)
	)
	(segment
		(start 117.67875 141.942965)
		(end 117.59375 141.857965)
		(width 0.185)
		(layer "F.Cu")
		(net 62)
	)
	(segment
		(start 118.284996 139.094146)
		(end 118.284996 139.719996)
		(width 0.185)
		(layer "F.Cu")
		(net 62)
	)
	(segment
		(start 117.78998 140.619239)
		(end 117.99211 140.417104)
		(width 0.185)
		(layer "F.Cu")
		(net 62)
	)
	(segment
		(start 118.59 138.600001)
		(end 118.59 138.12)
		(width 0.185)
		(layer "F.Cu")
		(net 62)
	)
	(segment
		(start 118.285 138.905001)
		(end 118.59 138.600001)
		(width 0.185)
		(layer "F.Cu")
		(net 62)
	)
	(segment
		(start 117.59375 141.857965)
		(end 117.59375 141.07)
		(width 0.185)
		(layer "F.Cu")
		(net 62)
	)
	(segment
		(start 118.284996 139.094146)
		(end 118.285 138.905001)
		(width 0.185)
		(layer "F.Cu")
		(net 62)
	)
	(arc
		(start 117.593747 141.092997)
		(mid 117.644746 140.836602)
		(end 117.78998 140.619239)
		(width 0.185)
		(layer "F.Cu")
		(net 62)
	)
	(arc
		(start 118.284996 139.710028)
		(mid 118.208873 140.092694)
		(end 117.99211 140.417104)
		(width 0.185)
		(layer "F.Cu")
		(net 62)
	)
	(segment
		(start 115.76375 136.364999)
		(end 115.763749 136.187119)
		(width 0.185)
		(layer "F.Cu")
		(net 63)
	)
	(segment
		(start 121.86 129.282251)
		(end 121.775 129.197251)
		(width 0.185)
		(layer "F.Cu")
		(net 63)
	)
	(segment
		(start 121.775 129.197251)
		(end 121.775 128.541)
		(width 0.185)
		(layer "F.Cu")
		(net 63)
	)
	(segment
		(start 115.43875 137.17)
		(end 115.43875 136.689999)
		(width 0.185)
		(layer "F.Cu")
		(net 63)
	)
	(segment
		(start 115.43875 136.689999)
		(end 115.76375 136.364999)
		(width 0.185)
		(layer "F.Cu")
		(net 63)
	)
	(segment
		(start 121.859994 129.399143)
		(end 121.86 129.282251)
		(width 0.185)
		(layer "F.Cu")
		(net 63)
	)
	(segment
		(start 116.056641 135.480006)
		(end 121.663756 129.872869)
		(width 0.185)
		(layer "F.Cu")
		(net 63)
	)
	(arc
		(start 121.663756 129.872869)
		(mid 121.808986 129.655522)
		(end 121.859994 129.399143)
		(width 0.185)
		(layer "F.Cu")
		(net 63)
	)
	(arc
		(start 115.763749 136.187119)
		(mid 115.839868 135.804432)
		(end 116.056641 135.480006)
		(width 0.185)
		(layer "F.Cu")
		(net 63)
	)
	(segment
		(start 140.576442 129.851553)
		(end 140.856 129.572)
		(width 0.2)
		(layer "F.Cu")
		(net 64)
	)
	(segment
		(start 132.952888 116.522895)
		(end 133.007103 116.57711)
		(width 0.2)
		(layer "F.Cu")
		(net 64)
	)
	(segment
		(start 138.802 129.998)
		(end 140.222893 129.997997)
		(width 0.2)
		(layer "F.Cu")
		(net 64)
	)
	(segment
		(start 133.299996 117.284217)
		(end 133.299995 125.010784)
		(width 0.2)
		(layer "F.Cu")
		(net 64)
	)
	(segment
		(start 120.79 136.48)
		(end 123.12 134.15)
		(width 0.2)
		(layer "F.Cu")
		(net 64)
	)
	(segment
		(start 133.592892 125.717895)
		(end 133.875 126)
		(width 0.2)
		(layer "F.Cu")
		(net 64)
	)
	(segment
		(start 131.94 116.23)
		(end 132.245787 116.230002)
		(width 0.2)
		(layer "F.Cu")
		(net 64)
	)
	(via
		(at 123.12 134.15)
		(size 0.45)
		(drill 0.1)
		(layers "F.Cu" "B.Cu")
		(net 64)
	)
	(via
		(at 133.871 126)
		(size 0.45)
		(drill 0.1)
		(layers "F.Cu" "B.Cu")
		(net 64)
	)
	(via
		(at 140.856 129.572)
		(size 0.45)
		(drill 0.1)
		(layers "F.Cu" "B.Cu")
		(net 64)
	)
	(arc
		(start 133.592892 125.717895)
		(mid 133.376116 125.39347)
		(end 133.299995 125.010784)
		(width 0.2)
		(layer "F.Cu")
		(net 64)
	)
	(arc
		(start 132.245787 116.230002)
		(mid 132.628467 116.306124)
		(end 132.952888 116.522895)
		(width 0.2)
		(layer "F.Cu")
		(net 64)
	)
	(arc
		(start 133.007103 116.57711)
		(mid 133.223876 116.901533)
		(end 133.299996 117.284217)
		(width 0.2)
		(layer "F.Cu")
		(net 64)
	)
	(arc
		(start 140.576442 129.851553)
		(mid 140.414232 129.959937)
		(end 140.222893 129.997997)
		(width 0.2)
		(layer "F.Cu")
		(net 64)
	)
	(segment
		(start 133.871004 126.000004)
		(end 133.871 126)
		(width 0.2)
		(layer "B.Cu")
		(net 64)
	)
	(segment
		(start 130.882893 133.857107)
		(end 131.667107 133.072893)
		(width 0.2)
		(layer "B.Cu")
		(net 64)
	)
	(segment
		(start 123.12 134.15)
		(end 126.45 134.15)
		(width 0.2)
		(layer "B.Cu")
		(net 64)
	)
	(segment
		(start 141.599996 128.18843)
		(end 141.599996 128.413786)
		(width 0.2)
		(layer "B.Cu")
		(net 64)
	)
	(segment
		(start 126.45 132.7)
		(end 126.45 134.15)
		(width 0.2)
		(layer "B.Cu")
		(net 64)
	)
	(segment
		(start 139.41157 126.000004)
		(end 133.871004 126.000004)
		(width 0.2)
		(layer "B.Cu")
		(net 64)
	)
	(segment
		(start 132.252893 127.061321)
		(end 133.02132 126.292894)
		(width 0.2)
		(layer "B.Cu")
		(net 64)
	)
	(segment
		(start 140.825784 126.585791)
		(end 141.01421 126.774217)
		(width 0.2)
		(layer "B.Cu")
		(net 64)
	)
	(segment
		(start 131.96 132.365786)
		(end 131.96 127.768428)
		(width 0.2)
		(layer "B.Cu")
		(net 64)
	)
	(segment
		(start 133.728423 126.000001)
		(end 133.875 126)
		(width 0.2)
		(layer "B.Cu")
		(net 64)
	)
	(segment
		(start 114.962893 131.822893)
		(end 116.997107 133.857107)
		(width 0.2)
		(layer "B.Cu")
		(net 64)
	)
	(segment
		(start 141.307106 129.12089)
		(end 140.856 129.572)
		(width 0.2)
		(layer "B.Cu")
		(net 64)
	)
	(segment
		(start 126.45 134.15)
		(end 130.175786 134.15)
		(width 0.2)
		(layer "B.Cu")
		(net 64)
	)
	(segment
		(start 117.704214 134.15)
		(end 123.12 134.15)
		(width 0.2)
		(layer "B.Cu")
		(net 64)
	)
	(segment
		(start 114.67 130.76)
		(end 114.67 131.115786)
		(width 0.2)
		(layer "B.Cu")
		(net 64)
	)
	(arc
		(start 114.67 131.115786)
		(mid 114.74612 131.498469)
		(end 114.962893 131.822893)
		(width 0.2)
		(layer "B.Cu")
		(net 64)
	)
	(arc
		(start 130.175786 134.15)
		(mid 130.558469 134.07388)
		(end 130.882893 133.857107)
		(width 0.2)
		(layer "B.Cu")
		(net 64)
	)
	(arc
		(start 140.825784 126.585791)
		(mid 140.176937 126.152245)
		(end 139.41157 126.000004)
		(width 0.2)
		(layer "B.Cu")
		(net 64)
	)
	(arc
		(start 133.02132 126.292894)
		(mid 133.345742 126.076122)
		(end 133.728423 126.000001)
		(width 0.2)
		(layer "B.Cu")
		(net 64)
	)
	(arc
		(start 131.96 127.768428)
		(mid 132.03612 127.385745)
		(end 132.252893 127.061321)
		(width 0.2)
		(layer "B.Cu")
		(net 64)
	)
	(arc
		(start 141.599996 128.18843)
		(mid 141.447755 127.423063)
		(end 141.01421 126.774217)
		(width 0.2)
		(layer "B.Cu")
		(net 64)
	)
	(arc
		(start 116.997107 133.857107)
		(mid 117.32153 134.07388)
		(end 117.704214 134.15)
		(width 0.2)
		(layer "B.Cu")
		(net 64)
	)
	(arc
		(start 141.599996 128.413786)
		(mid 141.523877 128.796468)
		(end 141.307106 129.12089)
		(width 0.2)
		(layer "B.Cu")
		(net 64)
	)
	(arc
		(start 131.667107 133.072893)
		(mid 131.88388 132.748469)
		(end 131.96 132.365786)
		(width 0.2)
		(layer "B.Cu")
		(net 64)
	)
	(segment
		(start 138.802 117.999)
		(end 140.3 117.999)
		(width 0.2)
		(layer "F.Cu")
		(net 65)
	)
	(segment
		(start 142.799 141.324)
		(end 143.351736 141.324)
		(width 0.2)
		(layer "F.Cu")
		(net 65)
	)
	(segment
		(start 144.052893 139.297107)
		(end 144.1 139.25)
		(width 0.2)
		(layer "F.Cu")
		(net 65)
	)
	(segment
		(start 143.563868 141.236132)
		(end 143.672132 141.127868)
		(width 0.2)
		(layer "F.Cu")
		(net 65)
	)
	(segment
		(start 143.76 140.915736)
		(end 143.76 140.004214)
		(width 0.2)
		(layer "F.Cu")
		(net 65)
	)
	(via
		(at 140.3 117.999)
		(size 0.45)
		(drill 0.1)
		(layers "F.Cu" "B.Cu")
		(net 65)
	)
	(via
		(at 144.1 139.25)
		(size 0.45)
		(drill 0.1)
		(layers "F.Cu" "B.Cu")
		(net 65)
	)
	(arc
		(start 144.052893 139.297107)
		(mid 143.83612 139.62153)
		(end 143.76 140.004214)
		(width 0.2)
		(layer "F.Cu")
		(net 65)
	)
	(arc
		(start 143.76 140.915736)
		(mid 143.737164 141.030541)
		(end 143.672132 141.127868)
		(width 0.2)
		(layer "F.Cu")
		(net 65)
	)
	(arc
		(start 143.563868 141.236132)
		(mid 143.466541 141.301164)
		(end 143.351736 141.324)
		(width 0.2)
		(layer "F.Cu")
		(net 65)
	)
	(segment
		(start 142.05 122.728936)
		(end 142.05 119.064221)
		(width 0.2)
		(layer "B.Cu")
		(net 65)
	)
	(segment
		(start 142.4 139.25)
		(end 144.1 139.25)
		(width 0.2)
		(layer "B.Cu")
		(net 65)
	)
	(segment
		(start 141.757107 118.357114)
		(end 141.691886 118.291893)
		(width 0.2)
		(layer "B.Cu")
		(net 65)
	)
	(segment
		(start 145.749996 137.79579)
		(end 145.749996 130.571068)
		(width 0.2)
		(layer "B.Cu")
		(net 65)
	)
	(segment
		(start 145.002893 138.957107)
		(end 145.457103 138.502897)
		(width 0.2)
		(layer "B.Cu")
		(net 65)
	)
	(segment
		(start 144.28553 127.035534)
		(end 143.514466 126.26447)
		(width 0.2)
		(layer "B.Cu")
		(net 65)
	)
	(segment
		(start 140.984779 117.999)
		(end 140.3 117.999)
		(width 0.2)
		(layer "B.Cu")
		(net 65)
	)
	(segment
		(start 144.1 139.25)
		(end 144.295786 139.25)
		(width 0.2)
		(layer "B.Cu")
		(net 65)
	)
	(arc
		(start 144.28553 127.035534)
		(mid 145.369394 128.657651)
		(end 145.749996 130.571068)
		(width 0.2)
		(layer "B.Cu")
		(net 65)
	)
	(arc
		(start 142.05 119.064221)
		(mid 141.97388 118.681538)
		(end 141.757107 118.357114)
		(width 0.2)
		(layer "B.Cu")
		(net 65)
	)
	(arc
		(start 142.05 122.728936)
		(mid 142.430602 124.642353)
		(end 143.514466 126.26447)
		(width 0.2)
		(layer "B.Cu")
		(net 65)
	)
	(arc
		(start 144.295786 139.25)
		(mid 144.67847 139.17388)
		(end 145.002893 138.957107)
		(width 0.2)
		(layer "B.Cu")
		(net 65)
	)
	(arc
		(start 145.457103 138.502897)
		(mid 145.673876 138.178473)
		(end 145.749996 137.79579)
		(width 0.2)
		(layer "B.Cu")
		(net 65)
	)
	(arc
		(start 141.691886 118.291893)
		(mid 141.367462 118.07512)
		(end 140.984779 117.999)
		(width 0.2)
		(layer "B.Cu")
		(net 65)
	)
	(segment
		(start 121.840796 140.74499)
		(end 121.769197 140.74499)
		(width 0.2)
		(layer "F.Cu")
		(net 66)
	)
	(segment
		(start 121.062098 141.037876)
		(end 120.971635 141.128337)
		(width 0.2)
		(layer "F.Cu")
		(net 66)
	)
	(segment
		(start 122.9 140.1)
		(end 122.547903 140.452097)
		(width 0.2)
		(layer "F.Cu")
		(net 66)
	)
	(segment
		(start 142.3 147)
		(end 142.3 145.88)
		(width 0.2)
		(layer "F.Cu")
		(net 66)
	)
	(segment
		(start 120.678734 141.835473)
		(end 120.67875 142.625466)
		(width 0.2)
		(layer "F.Cu")
		(net 66)
	)
	(via
		(at 142.3 147)
		(size 0.45)
		(drill 0.1)
		(layers "F.Cu" "B.Cu")
		(net 66)
	)
	(via
		(at 122.9 140.1)
		(size 0.45)
		(drill 0.1)
		(layers "F.Cu" "B.Cu")
		(net 66)
	)
	(arc
		(start 121.840796 140.74499)
		(mid 122.223479 140.66887)
		(end 122.547903 140.452097)
		(width 0.2)
		(layer "F.Cu")
		(net 66)
	)
	(arc
		(start 121.769197 140.74499)
		(mid 121.386518 140.821108)
		(end 121.062098 141.037876)
		(width 0.2)
		(layer "F.Cu")
		(net 66)
	)
	(arc
		(start 120.971635 141.128337)
		(mid 120.754852 141.452773)
		(end 120.678734 141.835473)
		(width 0.2)
		(layer "F.Cu")
		(net 66)
	)
	(segment
		(start 133.814219 149.000005)
		(end 140.585784 149.000005)
		(width 0.2)
		(layer "B.Cu")
		(net 66)
	)
	(segment
		(start 132.967107 141.242893)
		(end 131.792889 142.417111)
		(width 0.2)
		(layer "B.Cu")
		(net 66)
	)
	(segment
		(start 131.499996 143.124218)
		(end 131.499996 146.685782)
		(width 0.2)
		(layer "B.Cu")
		(net 66)
	)
	(segment
		(start 122.9 140.1)
		(end 124.10711 138.892896)
		(width 0.2)
		(layer "B.Cu")
		(net 66)
	)
	(segment
		(start 133.26 140.064214)
		(end 133.26 140.535786)
		(width 0.2)
		(layer "B.Cu")
		(net 66)
	)
	(segment
		(start 132.502897 138.892897)
		(end 132.967107 139.357107)
		(width 0.2)
		(layer "B.Cu")
		(net 66)
	)
	(segment
		(start 142.299998 147.28579)
		(end 142.3 147)
		(width 0.2)
		(layer "B.Cu")
		(net 66)
	)
	(segment
		(start 141.292895 148.707108)
		(end 142.007108 147.992887)
		(width 0.2)
		(layer "B.Cu")
		(net 66)
	)
	(segment
		(start 131.792889 147.392889)
		(end 133.107112 148.707112)
		(width 0.2)
		(layer "B.Cu")
		(net 66)
	)
	(segment
		(start 124.814215 138.600004)
		(end 131.79579 138.600004)
		(width 0.2)
		(layer "B.Cu")
		(net 66)
	)
	(arc
		(start 140.585784 149.000005)
		(mid 140.96847 148.923883)
		(end 141.292895 148.707108)
		(width 0.2)
		(layer "B.Cu")
		(net 66)
	)
	(arc
		(start 124.10711 138.892896)
		(mid 124.431533 138.676124)
		(end 124.814215 138.600004)
		(width 0.2)
		(layer "B.Cu")
		(net 66)
	)
	(arc
		(start 131.79579 138.600004)
		(mid 132.178473 138.676124)
		(end 132.502897 138.892897)
		(width 0.2)
		(layer "B.Cu")
		(net 66)
	)
	(arc
		(start 131.499996 146.685782)
		(mid 131.576116 147.068465)
		(end 131.792889 147.392889)
		(width 0.2)
		(layer "B.Cu")
		(net 66)
	)
	(arc
		(start 132.967107 141.242893)
		(mid 133.18388 140.91847)
		(end 133.26 140.535786)
		(width 0.2)
		(layer "B.Cu")
		(net 66)
	)
	(arc
		(start 133.107112 148.707112)
		(mid 133.431536 148.923885)
		(end 133.814219 149.000005)
		(width 0.2)
		(layer "B.Cu")
		(net 66)
	)
	(arc
		(start 131.792889 142.417111)
		(mid 131.576116 142.741534)
		(end 131.499996 143.124218)
		(width 0.2)
		(layer "B.Cu")
		(net 66)
	)
	(arc
		(start 133.26 140.064214)
		(mid 133.18388 139.681531)
		(end 132.967107 139.357107)
		(width 0.2)
		(layer "B.Cu")
		(net 66)
	)
	(arc
		(start 142.007108 147.992887)
		(mid 142.223877 147.668468)
		(end 142.299998 147.28579)
		(width 0.2)
		(layer "B.Cu")
		(net 66)
	)
	(segment
		(start 138.802 117.197)
		(end 140.297 117.197)
		(width 0.2)
		(layer "F.Cu")
		(net 67)
	)
	(segment
		(start 144.866843 141.324)
		(end 145.399 141.324)
		(width 0.2)
		(layer "F.Cu")
		(net 67)
	)
	(segment
		(start 140.297 117.197)
		(end 140.3 117.2)
		(width 0.2)
		(layer "F.Cu")
		(net 67)
	)
	(segment
		(start 144.665 141.122157)
		(end 144.665 140.767843)
		(width 0.2)
		(layer "F.Cu")
		(net 67)
	)
	(segment
		(start 144.723579 141.263579)
		(end 144.725422 141.265422)
		(width 0.2)
		(layer "F.Cu")
		(net 67)
	)
	(segment
		(start 144.723579 140.626421)
		(end 144.85 140.5)
		(width 0.2)
		(layer "F.Cu")
		(net 67)
	)
	(via
		(at 144.85 140.5)
		(size 0.45)
		(drill 0.1)
		(layers "F.Cu" "B.Cu")
		(net 67)
	)
	(via
		(at 140.3 117.2)
		(size 0.45)
		(drill 0.1)
		(layers "F.Cu" "B.Cu")
		(net 67)
	)
	(arc
		(start 144.723579 141.263579)
		(mid 144.680224 141.198694)
		(end 144.665 141.122157)
		(width 0.2)
		(layer "F.Cu")
		(net 67)
	)
	(arc
		(start 144.723579 140.626421)
		(mid 144.680224 140.691306)
		(end 144.665 140.767843)
		(width 0.2)
		(layer "F.Cu")
		(net 67)
	)
	(arc
		(start 144.866843 141.324)
		(mid 144.790307 141.308776)
		(end 144.725422 141.265422)
		(width 0.2)
		(layer "F.Cu")
		(net 67)
	)
	(segment
		(start 144.318893 141.031107)
		(end 144.85 140.5)
		(width 0.2)
		(layer "B.Cu")
		(net 67)
	)
	(segment
		(start 143.611786 141.324)
		(end 142.3 141.324)
		(width 0.2)
		(layer "B.Cu")
		(net 67)
	)
	(segment
		(start 146.699996 138.235791)
		(end 146.699996 129.921064)
		(width 0.2)
		(layer "B.Cu")
		(net 67)
	)
	(segment
		(start 143.024997 122.103929)
		(end 143.024997 119.867644)
		(width 0.2)
		(layer "B.Cu")
		(net 67)
	)
	(segment
		(start 142.146317 117.746323)
		(end 141.892889 117.492895)
		(width 0.2)
		(layer "B.Cu")
		(net 67)
	)
	(segment
		(start 145.23553 126.38553)
		(end 144.489463 125.639463)
		(width 0.2)
		(layer "B.Cu")
		(net 67)
	)
	(segment
		(start 144.85 140.5)
		(end 146.407103 138.942897)
		(width 0.2)
		(layer "B.Cu")
		(net 67)
	)
	(segment
		(start 141.185786 117.200003)
		(end 140.3 117.2)
		(width 0.2)
		(layer "B.Cu")
		(net 67)
	)
	(arc
		(start 141.892889 117.492895)
		(mid 141.568467 117.276124)
		(end 141.185786 117.200003)
		(width 0.2)
		(layer "B.Cu")
		(net 67)
	)
	(arc
		(start 143.024997 122.103929)
		(mid 143.405599 124.017346)
		(end 144.489463 125.639463)
		(width 0.2)
		(layer "B.Cu")
		(net 67)
	)
	(arc
		(start 143.611786 141.324)
		(mid 143.994469 141.24788)
		(end 144.318893 141.031107)
		(width 0.2)
		(layer "B.Cu")
		(net 67)
	)
	(arc
		(start 143.024997 119.867644)
		(mid 142.796635 118.719593)
		(end 142.146317 117.746323)
		(width 0.2)
		(layer "B.Cu")
		(net 67)
	)
	(arc
		(start 146.699996 129.921064)
		(mid 146.319394 128.007647)
		(end 145.23553 126.38553)
		(width 0.2)
		(layer "B.Cu")
		(net 67)
	)
	(arc
		(start 146.407103 138.942897)
		(mid 146.623875 138.618474)
		(end 146.699996 138.235791)
		(width 0.2)
		(layer "B.Cu")
		(net 67)
	)
	(segment
		(start 141.246997 144.454221)
		(end 141.247 144.929)
		(width 0.2)
		(layer "F.Cu")
		(net 69)
	)
	(segment
		(start 141.866559 143.420446)
		(end 141.539897 143.747102)
		(width 0.2)
		(layer "F.Cu")
		(net 69)
	)
	(segment
		(start 142.427214 143.274)
		(end 142.220104 143.274002)
		(width 0.2)
		(layer "F.Cu")
		(net 69)
	)
	(arc
		(start 141.246997 144.454221)
		(mid 141.323118 144.07153)
		(end 141.539897 143.747102)
		(width 0.2)
		(layer "F.Cu")
		(net 69)
	)
	(arc
		(start 141.866559 143.420446)
		(mid 142.028767 143.312063)
		(end 142.220104 143.274002)
		(width 0.2)
		(layer "F.Cu")
		(net 69)
	)
	(segment
		(start 141.881107 141.681107)
		(end 141.872893 141.672893)
		(width 0.2)
		(layer "F.Cu")
		(net 70)
	)
	(segment
		(start 142.799 141.974)
		(end 142.588214 141.974)
		(width 0.2)
		(layer "F.Cu")
		(net 70)
	)
	(segment
		(start 141.58 140.965786)
		(end 141.58 140.5)
		(width 0.2)
		(layer "F.Cu")
		(net 70)
	)
	(arc
		(start 141.881107 141.681107)
		(mid 142.20553 141.89788)
		(end 142.588214 141.974)
		(width 0.2)
		(layer "F.Cu")
		(net 70)
	)
	(arc
		(start 141.872893 141.672893)
		(mid 141.65612 141.34847)
		(end 141.58 140.965786)
		(width 0.2)
		(layer "F.Cu")
		(net 70)
	)
	(segment
		(start 135.7 140.1)
		(end 135.17843 140.1)
		(width 0.2)
		(layer "F.Cu")
		(net 71)
	)
	(segment
		(start 114.447107 128.34)
		(end 114.627893 128.34)
		(width 0.2)
		(layer "F.Cu")
		(net 71)
	)
	(segment
		(start 131.614219 119.584219)
		(end 131.13 119.1)
		(width 0.2)
		(layer "F.Cu")
		(net 71)
	)
	(segment
		(start 132.857109 127.707104)
		(end 132.492898 127.342893)
		(width 0.2)
		(layer "F.Cu")
		(net 71)
	)
	(segment
		(start 133.150002 138.071572)
		(end 133.150002 128.414211)
		(width 0.2)
		(layer "F.Cu")
		(net 71)
	)
	(segment
		(start 142.3 144.92)
		(end 142.585786 144.92)
		(width 0.2)
		(layer "F.Cu")
		(net 71)
	)
	(segment
		(start 143.292893 144.627107)
		(end 144.353107 143.566893)
		(width 0.2)
		(layer "F.Cu")
		(net 71)
	)
	(segment
		(start 146.14 143.715736)
		(end 146.14 143.664264)
		(width 0.2)
		(layer "F.Cu")
		(net 71)
	)
	(segment
		(start 140.292893 146.85289)
		(end 140.847104 147.407107)
		(width 0.2)
		(layer "F.Cu")
		(net 71)
	)
	(segment
		(start 133.764217 139.514214)
		(end 133.735788 139.485785)
		(width 0.2)
		(layer "F.Cu")
		(net 71)
	)
	(segment
		(start 114.981447 128.193553)
		(end 115.924554 127.250446)
		(width 0.2)
		(layer "F.Cu")
		(net 71)
	)
	(segment
		(start 132.200005 126.635786)
		(end 132.200005 120.998432)
		(width 0.2)
		(layer "F.Cu")
		(net 71)
	)
	(segment
		(start 113.88 124.34)
		(end 113.875 124.345)
		(width 0.2)
		(layer "F.Cu")
		(net 71)
	)
	(segment
		(start 142.616447 147.553554)
		(end 142.873553 147.296446)
		(width 0.2)
		(layer "F.Cu")
		(net 71)
	)
	(segment
		(start 114.021447 128.121447)
		(end 114.093554 128.193554)
		(width 0.2)
		(layer "F.Cu")
		(net 71)
	)
	(segment
		(start 129.938251 115.378251)
		(end 129.442 115.378251)
		(width 0.2)
		(layer "F.Cu")
		(net 71)
	)
	(segment
		(start 142.873551 145.493557)
		(end 142.3 144.92)
		(width 0.2)
		(layer "F.Cu")
		(net 71)
	)
	(segment
		(start 116.278107 127.104)
		(end 116.838 127.104)
		(width 0.2)
		(layer "F.Cu")
		(net 71)
	)
	(segment
		(start 130.61 115.48)
		(end 130.04 115.48)
		(width 0.2)
		(layer "F.Cu")
		(net 71)
	)
	(segment
		(start 130.04 115.48)
		(end 129.938251 115.378251)
		(width 0.2)
		(layer "F.Cu")
		(net 71)
	)
	(segment
		(start 143.019998 146.942893)
		(end 143.019996 145.847108)
		(width 0.2)
		(layer "F.Cu")
		(net 71)
	)
	(segment
		(start 113.875 124.345)
		(end 113.875 127.767893)
		(width 0.2)
		(layer "F.Cu")
		(net 71)
	)
	(segment
		(start 146.052132 143.452132)
		(end 145.961868 143.361868)
		(width 0.2)
		(layer "F.Cu")
		(net 71)
	)
	(segment
		(start 145.74 144.66)
		(end 145.74 144.364264)
		(width 0.2)
		(layer "F.Cu")
		(net 71)
	)
	(segment
		(start 145.827868 144.152132)
		(end 146.052132 143.927868)
		(width 0.2)
		(layer "F.Cu")
		(net 71)
	)
	(segment
		(start 141.554217 147.700004)
		(end 142.262893 147.700002)
		(width 0.2)
		(layer "F.Cu")
		(net 71)
	)
	(segment
		(start 140.000004 144.96)
		(end 140.000004 146.145787)
		(width 0.2)
		(layer "F.Cu")
		(net 71)
	)
	(via
		(at 131.13 119.1)
		(size 0.45)
		(drill 0.1)
		(layers "F.Cu" "B.Cu")
		(net 71)
	)
	(via
		(at 130.61 115.48)
		(size 0.45)
		(drill 0.1)
		(layers "F.Cu" "B.Cu")
		(net 71)
	)
	(via
		(at 140.000004 144.96)
		(size 0.45)
		(drill 0.1)
		(layers "F.Cu" "B.Cu")
		(net 71)
	)
	(via
		(at 135.7 140.1)
		(size 0.45)
		(drill 0.1)
		(layers "F.Cu" "B.Cu")
		(net 71)
	)
	(via
		(at 113.88 124.34)
		(size 0.45)
		(drill 0.1)
		(layers "F.Cu" "B.Cu")
		(net 71)
	)
	(arc
		(start 145.060214 143.274)
		(mid 144.677531 143.35012)
		(end 144.353107 143.566893)
		(width 0.2)
		(layer "F.Cu")
		(net 71)
	)
	(arc
		(start 143.019996 145.847108)
		(mid 142.981936 145.655768)
		(end 142.873551 145.493557)
		(width 0.2)
		(layer "F.Cu")
		(net 71)
	)
	(arc
		(start 133.150002 138.071572)
		(mid 133.302243 138.836939)
		(end 133.735788 139.485785)
		(width 0.2)
		(layer "F.Cu")
		(net 71)
	)
	(arc
		(start 142.873553 147.296446)
		(mid 142.981939 147.134234)
		(end 143.019998 146.942893)
		(width 0.2)
		(layer "F.Cu")
		(net 71)
	)
	(arc
		(start 115.924554 127.250446)
		(mid 116.086766 127.14206)
		(end 116.278107 127.104)
		(width 0.2)
		(layer "F.Cu")
		(net 71)
	)
	(arc
		(start 114.021447 128.121447)
		(mid 113.91306 127.959235)
		(end 113.875 127.767893)
		(width 0.2)
		(layer "F.Cu")
		(net 71)
	)
	(arc
		(start 114.447107 128.34)
		(mid 114.255766 128.30194)
		(end 114.093554 128.193554)
		(width 0.2)
		(layer "F.Cu")
		(net 71)
	)
	(arc
		(start 135.17843 140.1)
		(mid 134.413063 139.947759)
		(end 133.764217 139.514214)
		(width 0.2)
		(layer "F.Cu")
		(net 71)
	)
	(arc
		(start 133.150002 128.414211)
		(mid 133.073882 128.031528)
		(end 132.857109 127.707104)
		(width 0.2)
		(layer "F.Cu")
		(net 71)
	)
	(arc
		(start 132.200005 120.998432)
		(mid 132.047764 120.233065)
		(end 131.614219 119.584219)
		(width 0.2)
		(layer "F.Cu")
		(net 71)
	)
	(arc
		(start 143.292893 144.627107)
		(mid 142.96847 144.84388)
		(end 142.585786 144.92)
		(width 0.2)
		(layer "F.Cu")
		(net 71)
	)
	(arc
		(start 145.74 144.364264)
		(mid 145.762836 144.249459)
		(end 145.827868 144.152132)
		(width 0.2)
		(layer "F.Cu")
		(net 71)
	)
	(arc
		(start 142.262893 147.700002)
		(mid 142.454235 147.661941)
		(end 142.616447 147.553554)
		(width 0.2)
		(layer "F.Cu")
		(net 71)
	)
	(arc
		(start 114.627893 128.34)
		(mid 114.819235 128.30194)
		(end 114.981447 128.193553)
		(width 0.2)
		(layer "F.Cu")
		(net 71)
	)
	(arc
		(start 146.14 143.664264)
		(mid 146.117164 143.549459)
		(end 146.052132 143.452132)
		(width 0.2)
		(layer "F.Cu")
		(net 71)
	)
	(arc
		(start 140.847104 147.407107)
		(mid 141.17153 147.623883)
		(end 141.554217 147.700004)
		(width 0.2)
		(layer "F.Cu")
		(net 71)
	)
	(arc
		(start 146.14 143.715736)
		(mid 146.117164 143.830541)
		(end 146.052132 143.927868)
		(width 0.2)
		(layer "F.Cu")
		(net 71)
	)
	(arc
		(start 145.961868 143.361868)
		(mid 145.864541 143.296836)
		(end 145.749736 143.274)
		(width 0.2)
		(layer "F.Cu")
		(net 71)
	)
	(arc
		(start 140.000004 146.145787)
		(mid 140.076123 146.528468)
		(end 140.292893 146.85289)
		(width 0.2)
		(layer "F.Cu")
		(net 71)
	)
	(arc
		(start 132.492898 127.342893)
		(mid 132.276125 127.01847)
		(end 132.200005 126.635786)
		(width 0.2)
		(layer "F.Cu")
		(net 71)
	)
	(segment
		(start 132.038679 114.52)
		(end 131.984214 114.52)
		(width 0.2)
		(layer "B.Cu")
		(net 71)
	)
	(segment
		(start 114.648893 123.576107)
		(end 114.643893 123.576107)
		(width 0.2)
		(layer "B.Cu")
		(net 71)
	)
	(segment
		(start 136.293754 140.1)
		(end 135.7 140.1)
		(width 0.2)
		(layer "B.Cu")
		(net 71)
	)
	(segment
		(start 131.277107 114.812893)
		(end 130.61 115.48)
		(width 0.2)
		(layer "B.Cu")
		(net 71)
	)
	(segment
		(start 140.000004 144.96)
		(end 140.000004 143.392037)
		(width 0.2)
		(layer "B.Cu")
		(net 71)
	)
	(segment
		(start 129.765784 120.464216)
		(end 131.13 119.1)
		(width 0.2)
		(layer "B.Cu")
		(net 71)
	)
	(segment
		(start 133.050004 115.531325)
		(end 133.050004 116.351569)
		(width 0.2)
		(layer "B.Cu")
		(net 71)
	)
	(segment
		(start 114.643893 123.576107)
		(end 113.88 124.34)
		(width 0.2)
		(layer "B.Cu")
		(net 71)
	)
	(segment
		(start 139.707111 142.68493)
		(end 137.707967 140.685786)
		(width 0.2)
		(layer "B.Cu")
		(net 71)
	)
	(segment
		(start 132.464217 117.765783)
		(end 131.13 119.1)
		(width 0.2)
		(layer "B.Cu")
		(net 71)
	)
	(segment
		(start 118.003427 121.050003)
		(end 128.35157 121.050003)
		(width 0.2)
		(layer "B.Cu")
		(net 71)
	)
	(segment
		(start 132.757111 114.824218)
		(end 132.745786 114.812893)
		(width 0.2)
		(layer "B.Cu")
		(net 71)
	)
	(segment
		(start 116.589216 121.635788)
		(end 114.648893 123.576107)
		(width 0.2)
		(layer "B.Cu")
		(net 71)
	)
	(arc
		(start 118.003427 121.050003)
		(mid 117.238062 121.202244)
		(end 116.589216 121.635788)
		(width 0.2)
		(layer "B.Cu")
		(net 71)
	)
	(arc
		(start 136.293754 140.1)
		(mid 137.059121 140.252241)
		(end 137.707967 140.685786)
		(width 0.2)
		(layer "B.Cu")
		(net 71)
	)
	(arc
		(start 132.464217 117.765783)
		(mid 132.897763 117.116936)
		(end 133.050004 116.351569)
		(width 0.2)
		(layer "B.Cu")
		(net 71)
	)
	(arc
		(start 131.984214 114.52)
		(mid 131.60153 114.59612)
		(end 131.277107 114.812893)
		(width 0.2)
		(layer "B.Cu")
		(net 71)
	)
	(arc
		(start 129.765784 120.464216)
		(mid 129.116937 120.897762)
		(end 128.35157 121.050003)
		(width 0.2)
		(layer "B.Cu")
		(net 71)
	)
	(arc
		(start 140.000004 143.392037)
		(mid 139.923884 143.009354)
		(end 139.707111 142.68493)
		(width 0.2)
		(layer "B.Cu")
		(net 71)
	)
	(arc
		(start 132.745786 114.812893)
		(mid 132.421363 114.59612)
		(end 132.038679 114.52)
		(width 0.2)
		(layer "B.Cu")
		(net 71)
	)
	(arc
		(start 133.050004 115.531325)
		(mid 132.973884 115.148642)
		(end 132.757111 114.824218)
		(width 0.2)
		(layer "B.Cu")
		(net 71)
	)
	(segment
		(start 115.43875 138.610001)
		(end 115.43875 138.13)
		(width 0.185)
		(layer "F.Cu")
		(net 72)
	)
	(segment
		(start 115.67875 141.942965)
		(end 115.76375 141.857965)
		(width 0.185)
		(layer "F.Cu")
		(net 72)
	)
	(segment
		(start 115.76375 141.857965)
		(end 115.76375 138.935001)
		(width 0.185)
		(layer "F.Cu")
		(net 72)
	)
	(segment
		(start 115.76375 138.935001)
		(end 115.43875 138.610001)
		(width 0.185)
		(layer "F.Cu")
		(net 72)
	)
	(segment
		(start 115.67875 142.625466)
		(end 115.67875 141.942965)
		(width 0.185)
		(layer "F.Cu")
		(net 72)
	)
	(segment
		(start 124.089991 111.626651)
		(end 124.089991 111.220877)
		(width 0.185)
		(layer "F.Cu")
		(net 73)
	)
	(segment
		(start 126.676877 108.633991)
		(end 127.082651 108.633991)
		(width 0.185)
		(layer "F.Cu")
		(net 73)
	)
	(segment
		(start 127.082651 108.633991)
		(end 127.08266 108.634)
		(width 0.185)
		(layer "F.Cu")
		(net 73)
	)
	(segment
		(start 124.382884 110.51377)
		(end 125.96977 108.926884)
		(width 0.185)
		(layer "F.Cu")
		(net 73)
	)
	(segment
		(start 127.925999 108.634)
		(end 128.239999 108.32)
		(width 0.185)
		(layer "F.Cu")
		(net 73)
	)
	(segment
		(start 127.08266 108.634)
		(end 127.925999 108.634)
		(width 0.185)
		(layer "F.Cu")
		(net 73)
	)
	(segment
		(start 124.09 113.2)
		(end 124.089991 111.626651)
		(width 0.185)
		(layer "F.Cu")
		(net 73)
	)
	(segment
		(start 124.005 113.285)
		(end 124.09 113.2)
		(width 0.185)
		(layer "F.Cu")
		(net 73)
	)
	(segment
		(start 128.239999 108.32)
		(end 128.72 108.32)
		(width 0.185)
		(layer "F.Cu")
		(net 73)
	)
	(segment
		(start 124.005 113.941251)
		(end 124.005 113.285)
		(width 0.185)
		(layer "F.Cu")
		(net 73)
	)
	(arc
		(start 124.382884 110.51377)
		(mid 124.166111 110.838193)
		(end 124.089991 111.220877)
		(width 0.185)
		(layer "F.Cu")
		(net 73)
	)
	(arc
		(start 125.96977 108.926884)
		(mid 126.294193 108.710111)
		(end 126.676877 108.633991)
		(width 0.185)
		(layer "F.Cu")
		(net 73)
	)
	(segment
		(start 133.943999 108.634)
		(end 130.474001 108.634)
		(width 0.185)
		(layer "F.Cu")
		(net 74)
	)
	(segment
		(start 130.474001 108.634)
		(end 130.160001 108.32)
		(width 0.185)
		(layer "F.Cu")
		(net 74)
	)
	(segment
		(start 134.177999 108.4)
		(end 133.943999 108.634)
		(width 0.185)
		(layer "F.Cu")
		(net 74)
	)
	(segment
		(start 130.160001 108.32)
		(end 129.68 108.32)
		(width 0.185)
		(layer "F.Cu")
		(net 74)
	)
	(segment
		(start 135.003 108.4)
		(end 134.177999 108.4)
		(width 0.185)
		(layer "F.Cu")
		(net 74)
	)
	(segment
		(start 133.943999 106.233)
		(end 130.474001 106.233)
		(width 0.185)
		(layer "F.Cu")
		(net 75)
	)
	(segment
		(start 135.003 105.999)
		(end 134.177999 105.999)
		(width 0.185)
		(layer "F.Cu")
		(net 75)
	)
	(segment
		(start 130.474001 106.233)
		(end 130.160001 105.919)
		(width 0.185)
		(layer "F.Cu")
		(net 75)
	)
	(segment
		(start 130.160001 105.919)
		(end 129.68 105.919)
		(width 0.185)
		(layer "F.Cu")
		(net 75)
	)
	(segment
		(start 134.177999 105.999)
		(end 133.943999 106.233)
		(width 0.185)
		(layer "F.Cu")
		(net 75)
	)
	(segment
		(start 128.239999 105.919)
		(end 128.72 105.919)
		(width 0.185)
		(layer "F.Cu")
		(net 76)
	)
	(segment
		(start 127.925999 106.233)
		(end 128.239999 105.919)
		(width 0.185)
		(layer "F.Cu")
		(net 76)
	)
	(segment
		(start 122.505 113.941251)
		(end 122.505 113.285)
		(width 0.185)
		(layer "F.Cu")
		(net 76)
	)
	(segment
		(start 122.882884 108.89377)
		(end 125.250747 106.525907)
		(width 0.185)
		(layer "F.Cu")
		(net 76)
	)
	(segment
		(start 122.589991 109.600877)
		(end 122.59 113.2)
		(width 0.185)
		(layer "F.Cu")
		(net 76)
	)
	(segment
		(start 126.31366 106.233014)
		(end 127.925999 106.233)
		(width 0.185)
		(layer "F.Cu")
		(net 76)
	)
	(segment
		(start 125.957854 106.233014)
		(end 126.31366 106.233014)
		(width 0.185)
		(layer "F.Cu")
		(net 76)
	)
	(segment
		(start 122.505 113.285)
		(end 122.59 113.2)
		(width 0.185)
		(layer "F.Cu")
		(net 76)
	)
	(arc
		(start 122.589991 109.600877)
		(mid 122.666111 109.218194)
		(end 122.882884 108.89377)
		(width 0.185)
		(layer "F.Cu")
		(net 76)
	)
	(arc
		(start 125.250747 106.525907)
		(mid 125.57517 106.309134)
		(end 125.957854 106.233014)
		(width 0.185)
		(layer "F.Cu")
		(net 76)
	)
	(segment
		(start 125.908859 110.06383)
		(end 125.979569 109.993119)
		(width 0.185)
		(layer "F.Cu")
		(net 77)
	)
	(segment
		(start 124.505 113.941251)
		(end 124.505 113.285)
		(width 0.185)
		(layer "F.Cu")
		(net 77)
	)
	(segment
		(start 125.957739 109.405603)
		(end 126.028451 109.334894)
		(width 0.185)
		(layer "F.Cu")
		(net 77)
	)
	(segment
		(start 128.399062 109.278)
		(end 128.72 109.278)
		(width 0.185)
		(layer "F.Cu")
		(net 77)
	)
	(segment
		(start 124.616256 110.74709)
		(end 125.321345 110.042001)
		(width 0.185)
		(layer "F.Cu")
		(net 77)
	)
	(segment
		(start 125.604187 110.042001)
		(end 125.626016 110.06383)
		(width 0.185)
		(layer "F.Cu")
		(net 77)
	)
	(segment
		(start 124.42 113.2)
		(end 124.420017 111.763354)
		(width 0.185)
		(layer "F.Cu")
		(net 77)
	)
	(segment
		(start 126.028451 109.334894)
		(end 126.203108 109.160238)
		(width 0.185)
		(layer "F.Cu")
		(net 77)
	)
	(segment
		(start 124.505 113.285)
		(end 124.42 113.2)
		(width 0.185)
		(layer "F.Cu")
		(net 77)
	)
	(segment
		(start 127.925999 108.964)
		(end 128.239999 109.278)
		(width 0.185)
		(layer "F.Cu")
		(net 77)
	)
	(segment
		(start 126.676869 108.964)
		(end 127.925999 108.964)
		(width 0.185)
		(layer "F.Cu")
		(net 77)
	)
	(segment
		(start 125.979569 109.710276)
		(end 125.957739 109.688446)
		(width 0.185)
		(layer "F.Cu")
		(net 77)
	)
	(segment
		(start 128.239999 109.278)
		(end 128.399062 109.278)
		(width 0.185)
		(layer "F.Cu")
		(net 77)
	)
	(segment
		(start 124.420017 111.763354)
		(end 124.420017 111.220852)
		(width 0.185)
		(layer "F.Cu")
		(net 77)
	)
	(arc
		(start 125.979569 109.993119)
		(mid 126.038148 109.851697)
		(end 125.979569 109.710276)
		(width 0.185)
		(layer "F.Cu")
		(net 77)
	)
	(arc
		(start 126.203108 109.160238)
		(mid 126.420471 109.015001)
		(end 126.676869 108.964)
		(width 0.185)
		(layer "F.Cu")
		(net 77)
	)
	(arc
		(start 125.321345 110.042001)
		(mid 125.462766 109.983423)
		(end 125.604187 110.042001)
		(width 0.185)
		(layer "F.Cu")
		(net 77)
	)
	(arc
		(start 125.626016 110.06383)
		(mid 125.767438 110.122408)
		(end 125.908859 110.06383)
		(width 0.185)
		(layer "F.Cu")
		(net 77)
	)
	(arc
		(start 125.957739 109.688446)
		(mid 125.89916 109.547025)
		(end 125.957739 109.405603)
		(width 0.185)
		(layer "F.Cu")
		(net 77)
	)
	(arc
		(start 124.420017 111.220852)
		(mid 124.471018 110.964454)
		(end 124.616256 110.74709)
		(width 0.185)
		(layer "F.Cu")
		(net 77)
	)
	(segment
		(start 133.943999 108.964)
		(end 130.474001 108.964)
		(width 0.185)
		(layer "F.Cu")
		(net 78)
	)
	(segment
		(start 135.003 109.198)
		(end 134.177999 109.198)
		(width 0.185)
		(layer "F.Cu")
		(net 78)
	)
	(segment
		(start 130.160001 109.278)
		(end 129.68 109.278)
		(width 0.185)
		(layer "F.Cu")
		(net 78)
	)
	(segment
		(start 130.474001 108.964)
		(end 130.160001 109.278)
		(width 0.185)
		(layer "F.Cu")
		(net 78)
	)
	(segment
		(start 134.177999 109.198)
		(end 133.943999 108.964)
		(width 0.185)
		(layer "F.Cu")
		(net 78)
	)
	(segment
		(start 133.943999 106.563)
		(end 130.474001 106.563)
		(width 0.185)
		(layer "F.Cu")
		(net 79)
	)
	(segment
		(start 130.160001 106.877)
		(end 129.68 106.877)
		(width 0.185)
		(layer "F.Cu")
		(net 79)
	)
	(segment
		(start 134.177999 106.797)
		(end 133.943999 106.563)
		(width 0.185)
		(layer "F.Cu")
		(net 79)
	)
	(segment
		(start 135.003 106.797)
		(end 134.177999 106.797)
		(width 0.185)
		(layer "F.Cu")
		(net 79)
	)
	(segment
		(start 130.474001 106.563)
		(end 130.160001 106.877)
		(width 0.185)
		(layer "F.Cu")
		(net 79)
	)
	(segment
		(start 128.239999 106.877)
		(end 128.72 106.877)
		(width 0.185)
		(layer "F.Cu")
		(net 80)
	)
	(segment
		(start 125.957869 106.563)
		(end 127.925999 106.563)
		(width 0.185)
		(layer "F.Cu")
		(net 80)
	)
	(segment
		(start 123.116254 109.127092)
		(end 124.254052 107.989294)
		(width 0.185)
		(layer "F.Cu")
		(net 80)
	)
	(segment
		(start 127.925999 106.563)
		(end 128.239999 106.877)
		(width 0.185)
		(layer "F.Cu")
		(net 80)
	)
	(segment
		(start 122.92 113.2)
		(end 122.920015 110.370875)
		(width 0.185)
		(layer "F.Cu")
		(net 80)
	)
	(segment
		(start 124.961158 107.282187)
		(end 125.484108 106.759238)
		(width 0.185)
		(layer "F.Cu")
		(net 80)
	)
	(segment
		(start 122.920015 110.370875)
		(end 122.920015 109.600854)
		(width 0.185)
		(layer "F.Cu")
		(net 80)
	)
	(segment
		(start 123.005 113.285)
		(end 122.92 113.2)
		(width 0.185)
		(layer "F.Cu")
		(net 80)
	)
	(segment
		(start 124.84157 108.011127)
		(end 124.91228 107.940416)
		(width 0.185)
		(layer "F.Cu")
		(net 80)
	)
	(segment
		(start 124.890446 107.352896)
		(end 124.961158 107.282187)
		(width 0.185)
		(layer "F.Cu")
		(net 80)
	)
	(segment
		(start 124.91228 107.657573)
		(end 124.890446 107.635739)
		(width 0.185)
		(layer "F.Cu")
		(net 80)
	)
	(segment
		(start 123.005 113.941251)
		(end 123.005 113.285)
		(width 0.185)
		(layer "F.Cu")
		(net 80)
	)
	(segment
		(start 124.536894 107.989294)
		(end 124.558727 108.011127)
		(width 0.185)
		(layer "F.Cu")
		(net 80)
	)
	(arc
		(start 124.254052 107.989294)
		(mid 124.395473 107.930716)
		(end 124.536894 107.989294)
		(width 0.185)
		(layer "F.Cu")
		(net 80)
	)
	(arc
		(start 122.920015 109.600854)
		(mid 122.971016 109.344456)
		(end 123.116254 109.127092)
		(width 0.185)
		(layer "F.Cu")
		(net 80)
	)
	(arc
		(start 124.890446 107.635739)
		(mid 124.831867 107.494318)
		(end 124.890446 107.352896)
		(width 0.185)
		(layer "F.Cu")
		(net 80)
	)
	(arc
		(start 124.91228 107.940416)
		(mid 124.970859 107.798994)
		(end 124.91228 107.657573)
		(width 0.185)
		(layer "F.Cu")
		(net 80)
	)
	(arc
		(start 124.558727 108.011127)
		(mid 124.700149 108.069705)
		(end 124.84157 108.011127)
		(width 0.185)
		(layer "F.Cu")
		(net 80)
	)
	(arc
		(start 125.484108 106.759238)
		(mid 125.701471 106.614001)
		(end 125.957869 106.563)
		(width 0.185)
		(layer "F.Cu")
		(net 80)
	)
	(segment
		(start 116.26375 145.582967)
		(end 116.17875 145.497967)
		(width 0.185)
		(layer "F.Cu")
		(net 81)
	)
	(segment
		(start 131.344608 122.461262)
		(end 129.481239 120.597893)
		(width 0.185)
		(layer "F.Cu")
		(net 81)
	)
	(segment
		(start 131.637501 139.62)
		(end 131.637501 123.168369)
		(width 0.185)
		(layer "F.Cu")
		(net 81)
	)
	(segment
		(start 131.795 139.777499)
		(end 131.637501 139.62)
		(width 0.185)
		(layer "F.Cu")
		(net 81)
	)
	(segment
		(start 124.42 119.079131)
		(end 124.42 118.057502)
		(width 0.185)
		(layer "F.Cu")
		(net 81)
	)
	(segment
		(start 116.26375 145.78375)
		(end 116.26375 145.582967)
		(width 0.185)
		(layer "F.Cu")
		(net 81)
	)
	(segment
		(start 116.17875 145.497967)
		(end 116.17875 144.815466)
		(width 0.185)
		(layer "F.Cu")
		(net 81)
	)
	(segment
		(start 124.42 118.057502)
		(end 124.505 117.972502)
		(width 0.185)
		(layer "F.Cu")
		(net 81)
	)
	(segment
		(start 124.505 117.972502)
		(end 124.505 117.316251)
		(width 0.185)
		(layer "F.Cu")
		(net 81)
	)
	(segment
		(start 125.172107 120.108761)
		(end 124.616238 119.552892)
		(width 0.185)
		(layer "F.Cu")
		(net 81)
	)
	(segment
		(start 128.774132 120.305)
		(end 125.645869 120.305)
		(width 0.185)
		(layer "F.Cu")
		(net 81)
	)
	(segment
		(start 116.10625 145.94125)
		(end 116.26375 145.78375)
		(width 0.185)
		(layer "F.Cu")
		(net 81)
	)
	(via
		(at 131.795 139.777499)
		(size 0.45)
		(drill 0.1)
		(layers "F.Cu" "B.Cu")
		(free yes)
		(net 81)
	)
	(via
		(at 116.10625 145.94125)
		(size 0.45)
		(drill 0.1)
		(layers "F.Cu" "B.Cu")
		(free yes)
		(net 81)
	)
	(arc
		(start 124.616238 119.552892)
		(mid 124.471001 119.335529)
		(end 124.42 119.079131)
		(width 0.185)
		(layer "F.Cu")
		(net 81)
	)
	(arc
		(start 131.344608 122.461262)
		(mid 131.561381 122.785685)
		(end 131.637501 123.168369)
		(width 0.185)
		(layer "F.Cu")
		(net 81)
	)
	(arc
		(start 125.645869 120.305)
		(mid 125.389471 120.253999)
		(end 125.172107 120.108761)
		(width 0.185)
		(layer "F.Cu")
		(net 81)
	)
	(arc
		(start 129.481239 120.597893)
		(mid 129.156816 120.38112)
		(end 128.774132 120.305)
		(width 0.185)
		(layer "F.Cu")
		(net 81)
	)
	(segment
		(start 116.10625 145.94125)
		(end 116.263749 146.098749)
		(width 0.185)
		(layer "B.Cu")
		(net 81)
	)
	(segment
		(start 118.145868 148.465)
		(end 122.304132 148.465)
		(width 0.185)
		(layer "B.Cu")
		(net 81)
	)
	(segment
		(start 126.561239 146.672107)
		(end 131.344608 141.888738)
		(width 0.185)
		(layer "B.Cu")
		(net 81)
	)
	(segment
		(start 123.011239 148.172107)
		(end 124.022108 147.161238)
		(width 0.185)
		(layer "B.Cu")
		(net 81)
	)
	(segment
		(start 116.263749 146.098749)
		(end 116.263749 146.582881)
		(width 0.185)
		(layer "B.Cu")
		(net 81)
	)
	(segment
		(start 131.637501 141.181631)
		(end 131.637501 139.934998)
		(width 0.185)
		(layer "B.Cu")
		(net 81)
	)
	(segment
		(start 131.637501 139.934998)
		(end 131.795 139.777499)
		(width 0.185)
		(layer "B.Cu")
		(net 81)
	)
	(segment
		(start 116.556642 147.289988)
		(end 117.438761 148.172107)
		(width 0.185)
		(layer "B.Cu")
		(net 81)
	)
	(segment
		(start 124.495869 146.965)
		(end 125.854132 146.965)
		(width 0.185)
		(layer "B.Cu")
		(net 81)
	)
	(arc
		(start 116.556642 147.289988)
		(mid 116.339869 146.965565)
		(end 116.263749 146.582881)
		(width 0.185)
		(layer "B.Cu")
		(net 81)
	)
	(arc
		(start 117.438761 148.172107)
		(mid 117.763184 148.38888)
		(end 118.145868 148.465)
		(width 0.185)
		(layer "B.Cu")
		(net 81)
	)
	(arc
		(start 131.344608 141.888738)
		(mid 131.561381 141.564315)
		(end 131.637501 141.181631)
		(width 0.185)
		(layer "B.Cu")
		(net 81)
	)
	(arc
		(start 122.304132 148.465)
		(mid 122.686815 148.38888)
		(end 123.011239 148.172107)
		(width 0.185)
		(layer "B.Cu")
		(net 81)
	)
	(arc
		(start 124.495869 146.965)
		(mid 124.239471 147.016001)
		(end 124.022108 147.161238)
		(width 0.185)
		(layer "B.Cu")
		(net 81)
	)
	(arc
		(start 126.561239 146.672107)
		(mid 126.236816 146.88888)
		(end 125.854132 146.965)
		(width 0.185)
		(layer "B.Cu")
		(net 81)
	)
	(segment
		(start 117.76375 145.805553)
		(end 117.606249 145.963054)
		(width 0.185)
		(layer "F.Cu")
		(net 82)
	)
	(segment
		(start 117.67875 145.497967)
		(end 117.67875 144.815466)
		(width 0.185)
		(layer "F.Cu")
		(net 82)
	)
	(segment
		(start 129.564608 122.931262)
		(end 128.411239 121.777893)
		(width 0.185)
		(layer "F.Cu")
		(net 82)
	)
	(segment
		(start 124.532107 121.288761)
		(end 123.116238 119.872892)
		(width 0.185)
		(layer "F.Cu")
		(net 82)
	)
	(segment
		(start 117.76375 145.582967)
		(end 117.76375 145.805553)
		(width 0.185)
		(layer "F.Cu")
		(net 82)
	)
	(segment
		(start 127.704132 121.485)
		(end 125.005869 121.485)
		(width 0.185)
		(layer "F.Cu")
		(net 82)
	)
	(segment
		(start 122.92 118.057502)
		(end 123.005 117.972502)
		(width 0.185)
		(layer "F.Cu")
		(net 82)
	)
	(segment
		(start 123.005 117.972502)
		(end 123.005 117.316251)
		(width 0.185)
		(layer "F.Cu")
		(net 82)
	)
	(segment
		(start 122.92 119.399131)
		(end 122.92 118.057502)
		(width 0.185)
		(layer "F.Cu")
		(net 82)
	)
	(segment
		(start 117.67875 145.497967)
		(end 117.76375 145.582967)
		(width 0.185)
		(layer "F.Cu")
		(net 82)
	)
	(segment
		(start 130.015 139.765422)
		(end 129.857501 139.607923)
		(width 0.185)
		(layer "F.Cu")
		(net 82)
	)
	(segment
		(start 129.857501 139.607923)
		(end 129.857501 123.638369)
		(width 0.185)
		(layer "F.Cu")
		(net 82)
	)
	(via
		(at 117.606249 145.963054)
		(size 0.45)
		(drill 0.1)
		(layers "F.Cu" "B.Cu")
		(free yes)
		(net 82)
	)
	(via
		(at 130.015 139.765422)
		(size 0.45)
		(drill 0.1)
		(layers "F.Cu" "B.Cu")
		(free yes)
		(net 82)
	)
	(arc
		(start 129.857501 123.638369)
		(mid 129.781381 123.255686)
		(end 129.564608 122.931262)
		(width 0.185)
		(layer "F.Cu")
		(net 82)
	)
	(arc
		(start 127.704132 121.485)
		(mid 128.086815 121.56112)
		(end 128.411239 121.777893)
		(width 0.185)
		(layer "F.Cu")
		(net 82)
	)
	(arc
		(start 125.005869 121.485)
		(mid 124.749471 121.433999)
		(end 124.532107 121.288761)
		(width 0.185)
		(layer "F.Cu")
		(net 82)
	)
	(arc
		(start 123.116238 119.872892)
		(mid 122.971001 119.655529)
		(end 122.92 119.399131)
		(width 0.185)
		(layer "F.Cu")
		(net 82)
	)
	(segment
		(start 128.984585 141.828761)
		(end 129.661263 141.152083)
		(width 0.185)
		(layer "B.Cu")
		(net 82)
	)
	(segment
		(start 119.009177 147.265)
		(end 121.390823 147.265)
		(width 0.185)
		(layer "B.Cu")
		(net 82)
	)
	(segment
		(start 129.857501 140.678322)
		(end 129.857501 139.922921)
		(width 0.185)
		(layer "B.Cu")
		(net 82)
	)
	(segment
		(start 127.185869 142.025)
		(end 128.510823 142.025)
		(width 0.185)
		(layer "B.Cu")
		(net 82)
	)
	(segment
		(start 117.763748 146.297094)
		(end 118.535416 147.068762)
		(width 0.185)
		(layer "B.Cu")
		(net 82)
	)
	(segment
		(start 117.606249 145.963054)
		(end 117.763748 146.120553)
		(width 0.185)
		(layer "B.Cu")
		(net 82)
	)
	(segment
		(start 129.857501 139.922921)
		(end 130.015 139.765422)
		(width 0.185)
		(layer "B.Cu")
		(net 82)
	)
	(segment
		(start 121.864585 147.068761)
		(end 126.712108 142.221238)
		(width 0.185)
		(layer "B.Cu")
		(net 82)
	)
	(segment
		(start 117.763748 146.120553)
		(end 117.763748 146.297094)
		(width 0.185)
		(layer "B.Cu")
		(net 82)
	)
	(arc
		(start 128.510823 142.025)
		(mid 128.767221 141.973999)
		(end 128.984585 141.828761)
		(width 0.185)
		(layer "B.Cu")
		(net 82)
	)
	(arc
		(start 126.712108 142.221238)
		(mid 126.929471 142.076001)
		(end 127.185869 142.025)
		(width 0.185)
		(layer "B.Cu")
		(net 82)
	)
	(arc
		(start 129.661263 141.152083)
		(mid 129.8065 140.93472)
		(end 129.857501 140.678322)
		(width 0.185)
		(layer "B.Cu")
		(net 82)
	)
	(arc
		(start 121.390823 147.265)
		(mid 121.647221 147.213999)
		(end 121.864585 147.068761)
		(width 0.185)
		(layer "B.Cu")
		(net 82)
	)
	(arc
		(start 119.009177 147.265)
		(mid 118.752779 147.213999)
		(end 118.535416 147.068762)
		(width 0.185)
		(layer "B.Cu")
		(net 82)
	)
	(segment
		(start 124.09 119.079132)
		(end 124.09 118.057502)
		(width 0.185)
		(layer "F.Cu")
		(net 83)
	)
	(segment
		(start 131.15 139.777499)
		(end 131.307499 139.62)
		(width 0.185)
		(layer "F.Cu")
		(net 83)
	)
	(segment
		(start 124.09 118.057502)
		(end 124.005 117.972502)
		(width 0.185)
		(layer "F.Cu")
		(net 83)
	)
	(segment
		(start 131.11126 122.694606)
		(end 129.247892 120.831238)
		(width 0.185)
		(layer "F.Cu")
		(net 83)
	)
	(segment
		(start 116.75125 145.94125)
		(end 116.59375 145.78375)
		(width 0.185)
		(layer "F.Cu")
		(net 83)
	)
	(segment
		(start 116.67875 145.497967)
		(end 116.67875 144.815466)
		(width 0.185)
		(layer "F.Cu")
		(net 83)
	)
	(segment
		(start 124.938761 120.342107)
		(end 124.382893 119.786239)
		(width 0.185)
		(layer "F.Cu")
		(net 83)
	)
	(segment
		(start 116.59375 145.582967)
		(end 116.67875 145.497967)
		(width 0.185)
		(layer "F.Cu")
		(net 83)
	)
	(segment
		(start 128.774131 120.635)
		(end 125.645868 120.635)
		(width 0.185)
		(layer "F.Cu")
		(net 83)
	)
	(segment
		(start 116.59375 145.78375)
		(end 116.59375 145.582967)
		(width 0.185)
		(layer "F.Cu")
		(net 83)
	)
	(segment
		(start 124.005 117.972502)
		(end 124.005 117.316251)
		(width 0.185)
		(layer "F.Cu")
		(net 83)
	)
	(segment
		(start 131.307499 139.62)
		(end 131.307499 123.168368)
		(width 0.185)
		(layer "F.Cu")
		(net 83)
	)
	(via
		(at 131.15 139.777499)
		(size 0.45)
		(drill 0.1)
		(layers "F.Cu" "B.Cu")
		(free yes)
		(net 83)
	)
	(via
		(at 116.75125 145.94125)
		(size 0.45)
		(drill 0.1)
		(layers "F.Cu" "B.Cu")
		(free yes)
		(net 83)
	)
	(arc
		(start 129.247892 120.831238)
		(mid 129.030529 120.686001)
		(end 128.774131 120.635)
		(width 0.185)
		(layer "F.Cu")
		(net 83)
	)
	(arc
		(start 124.382893 119.786239)
		(mid 124.16612 119.461816)
		(end 124.09 119.079132)
		(width 0.185)
		(layer "F.Cu")
		(net 83)
	)
	(arc
		(start 131.307499 123.168368)
		(mid 131.256498 122.91197)
		(end 131.11126 122.694606)
		(width 0.185)
		(layer "F.Cu")
		(net 83)
	)
	(arc
		(start 124.938761 120.342107)
		(mid 125.263184 120.55888)
		(end 125.645868 120.635)
		(width 0.185)
		(layer "F.Cu")
		(net 83)
	)
	(segment
		(start 131.307499 139.934998)
		(end 131.15 139.777499)
		(width 0.185)
		(layer "B.Cu")
		(net 83)
	)
	(segment
		(start 131.307499 141.181632)
		(end 131.307499 139.934998)
		(width 0.185)
		(layer "B.Cu")
		(net 83)
	)
	(segment
		(start 116.593751 146.098749)
		(end 116.593751 146.582882)
		(width 0.185)
		(layer "B.Cu")
		(net 83)
	)
	(segment
		(start 116.78999 147.056644)
		(end 117.672108 147.938762)
		(width 0.185)
		(layer "B.Cu")
		(net 83)
	)
	(segment
		(start 126.327893 146.438761)
		(end 131.111261 141.655393)
		(width 0.185)
		(layer "B.Cu")
		(net 83)
	)
	(segment
		(start 118.145869 148.135)
		(end 122.304131 148.135)
		(width 0.185)
		(layer "B.Cu")
		(net 83)
	)
	(segment
		(start 116.75125 145.94125)
		(end 116.593751 146.098749)
		(width 0.185)
		(layer "B.Cu")
		(net 83)
	)
	(segment
		(start 122.777893 147.938761)
		(end 123.788761 146.927893)
		(width 0.185)
		(layer "B.Cu")
		(net 83)
	)
	(segment
		(start 124.495868 146.635)
		(end 125.854131 146.635)
		(width 0.185)
		(layer "B.Cu")
		(net 83)
	)
	(arc
		(start 118.145869 148.135)
		(mid 117.889471 148.083999)
		(end 117.672108 147.938762)
		(width 0.185)
		(layer "B.Cu")
		(net 83)
	)
	(arc
		(start 131.307499 141.181632)
		(mid 131.256498 141.43803)
		(end 131.111261 141.655393)
		(width 0.185)
		(layer "B.Cu")
		(net 83)
	)
	(arc
		(start 122.304131 148.135)
		(mid 122.560529 148.083999)
		(end 122.777893 147.938761)
		(width 0.185)
		(layer "B.Cu")
		(net 83)
	)
	(arc
		(start 124.495868 146.635)
		(mid 124.113185 146.71112)
		(end 123.788761 146.927893)
		(width 0.185)
		(layer "B.Cu")
		(net 83)
	)
	(arc
		(start 126.327893 146.438761)
		(mid 126.110529 146.583999)
		(end 125.854131 146.635)
		(width 0.185)
		(layer "B.Cu")
		(net 83)
	)
	(arc
		(start 116.78999 147.056644)
		(mid 116.644752 146.83928)
		(end 116.593751 146.582882)
		(width 0.185)
		(layer "B.Cu")
		(net 83)
	)
	(segment
		(start 129.327499 136.615184)
		(end 129.285957 136.615184)
		(width 0.185)
		(layer "F.Cu")
		(net 84)
	)
	(segment
		(start 129.527499 134.915184)
		(end 129.527499 123.638368)
		(width 0.185)
		(layer "F.Cu")
		(net 84)
	)
	(segment
		(start 129.33126 123.164606)
		(end 128.177892 122.011238)
		(width 0.185)
		(layer "F.Cu")
		(net 84)
	)
	(segment
		(start 127.704131 121.815)
		(end 125.005868 121.815)
		(width 0.185)
		(layer "F.Cu")
		(net 84)
	)
	(segment
		(start 118.17875 145.497967)
		(end 118.17875 144.815466)
		(width 0.185)
		(layer "F.Cu")
		(net 84)
	)
	(segment
		(start 129.327499 135.615184)
		(end 129.285952 135.615184)
		(width 0.185)
		(layer "F.Cu")
		(net 84)
	)
	(segment
		(start 118.09375 145.582967)
		(end 118.09375 145.805555)
		(width 0.185)
		(layer "F.Cu")
		(net 84)
	)
	(segment
		(start 122.59 118.057502)
		(end 122.505 117.972502)
		(width 0.185)
		(layer "F.Cu")
		(net 84)
	)
	(segment
		(start 118.09375 145.805555)
		(end 118.251249 145.963054)
		(width 0.185)
		(layer "F.Cu")
		(net 84)
	)
	(segment
		(start 124.298761 121.522107)
		(end 122.882893 120.106239)
		(width 0.185)
		(layer "F.Cu")
		(net 84)
	)
	(segment
		(start 129.285957 136.115184)
		(end 129.327499 136.115184)
		(width 0.185)
		(layer "F.Cu")
		(net 84)
	)
	(segment
		(start 118.17875 145.497967)
		(end 118.09375 145.582967)
		(width 0.185)
		(layer "F.Cu")
		(net 84)
	)
	(segment
		(start 129.527499 139.607923)
		(end 129.527499 136.815184)
		(width 0.185)
		(layer "F.Cu")
		(net 84)
	)
	(segment
		(start 122.59 119.399132)
		(end 122.59 118.057502)
		(width 0.185)
		(layer "F.Cu")
		(net 84)
	)
	(segment
		(start 129.527499 135.915184)
		(end 129.527499 135.815184)
		(width 0.185)
		(layer "F.Cu")
		(net 84)
	)
	(segment
		(start 129.37 139.765422)
		(end 129.527499 139.607923)
		(width 0.185)
		(layer "F.Cu")
		(net 84)
	)
	(segment
		(start 122.505 117.972502)
		(end 122.505 117.316251)
		(width 0.185)
		(layer "F.Cu")
		(net 84)
	)
	(segment
		(start 129.085952 135.415184)
		(end 129.085952 135.315184)
		(width 0.185)
		(layer "F.Cu")
		(net 84)
	)
	(segment
		(start 129.085957 136.415184)
		(end 129.085957 136.315184)
		(width 0.185)
		(layer "F.Cu")
		(net 84)
	)
	(segment
		(start 129.285952 135.115184)
		(end 129.327499 135.115184)
		(width 0.185)
		(layer "F.Cu")
		(net 84)
	)
	(via
		(at 118.251249 145.963054)
		(size 0.45)
		(drill 0.1)
		(layers "F.Cu" "B.Cu")
		(free yes)
		(net 84)
	)
	(via
		(at 129.37 139.765422)
		(size 0.45)
		(drill 0.1)
		(layers "F.Cu" "B.Cu")
		(free yes)
		(net 84)
	)
	(arc
		(start 125.005868 121.815)
		(mid 124.623185 121.73888)
		(end 124.298761 121.522107)
		(width 0.185)
		(layer "F.Cu")
		(net 84)
	)
	(arc
		(start 129.327499 135.115184)
		(mid 129.46892 135.056605)
		(end 129.527499 134.915184)
		(width 0.185)
		(layer "F.Cu")
		(net 84)
	)
	(arc
		(start 122.882893 120.106239)
		(mid 122.66612 119.781815)
		(end 122.59 119.399132)
		(width 0.185)
		(layer "F.Cu")
		(net 84)
	)
	(arc
		(start 129.285952 135.615184)
		(mid 129.144531 135.556605)
		(end 129.085952 135.415184)
		(width 0.185)
		(layer "F.Cu")
		(net 84)
	)
	(arc
		(start 128.177892 122.011238)
		(mid 127.960529 121.866001)
		(end 127.704131 121.815)
		(width 0.185)
		(layer "F.Cu")
		(net 84)
	)
	(arc
		(start 129.527499 136.815184)
		(mid 129.46892 136.673763)
		(end 129.327499 136.615184)
		(width 0.185)
		(layer "F.Cu")
		(net 84)
	)
	(arc
		(start 129.327499 136.115184)
		(mid 129.46892 136.056605)
		(end 129.527499 135.915184)
		(width 0.185)
		(layer "F.Cu")
		(net 84)
	)
	(arc
		(start 129.527499 123.638368)
		(mid 129.476498 123.38197)
		(end 129.33126 123.164606)
		(width 0.185)
		(layer "F.Cu")
		(net 84)
	)
	(arc
		(start 129.085952 135.315184)
		(mid 129.144531 135.173763)
		(end 129.285952 135.115184)
		(width 0.185)
		(layer "F.Cu")
		(net 84)
	)
	(arc
		(start 129.085957 136.315184)
		(mid 129.144536 136.173763)
		(end 129.285957 136.115184)
		(width 0.185)
		(layer "F.Cu")
		(net 84)
	)
	(arc
		(start 129.527499 135.815184)
		(mid 129.46892 135.673763)
		(end 129.327499 135.615184)
		(width 0.185)
		(layer "F.Cu")
		(net 84)
	)
	(arc
		(start 129.285957 136.615184)
		(mid 129.144536 136.556605)
		(end 129.085957 136.415184)
		(width 0.185)
		(layer "F.Cu")
		(net 84)
	)
	(segment
		(start 118.251249 145.963054)
		(end 118.09375 146.120553)
		(width 0.185)
		(layer "B.Cu")
		(net 84)
	)
	(segment
		(start 127.185868 141.695)
		(end 128.374131 141.695)
		(width 0.185)
		(layer "B.Cu")
		(net 84)
	)
	(segment
		(start 129.527499 140.541632)
		(end 129.527499 139.922921)
		(width 0.185)
		(layer "B.Cu")
		(net 84)
	)
	(segment
		(start 128.847893 141.498761)
		(end 129.331261 141.015393)
		(width 0.185)
		(layer "B.Cu")
		(net 84)
	)
	(segment
		(start 119.145869 146.935)
		(end 121.254131 146.935)
		(width 0.185)
		(layer "B.Cu")
		(net 84)
	)
	(segment
		(start 129.527499 139.922921)
		(end 129.37 139.765422)
		(width 0.185)
		(layer "B.Cu")
		(net 84)
	)
	(segment
		(start 118.09375 146.120553)
		(end 118.09375 146.160404)
		(width 0.185)
		(layer "B.Cu")
		(net 84)
	)
	(segment
		(start 118.09375 146.160404)
		(end 118.672108 146.738762)
		(width 0.185)
		(layer "B.Cu")
		(net 84)
	)
	(segment
		(start 121.727893 146.738761)
		(end 126.478761 141.987893)
		(width 0.185)
		(layer "B.Cu")
		(net 84)
	)
	(arc
		(start 129.331261 141.015393)
		(mid 129.476498 140.79803)
		(end 129.527499 140.541632)
		(width 0.185)
		(layer "B.Cu")
		(net 84)
	)
	(arc
		(start 121.727893 146.738761)
		(mid 121.510529 146.883999)
		(end 121.254131 146.935)
		(width 0.185)
		(layer "B.Cu")
		(net 84)
	)
	(arc
		(start 128.374131 141.695)
		(mid 128.630529 141.643999)
		(end 128.847893 141.498761)
		(width 0.185)
		(layer "B.Cu")
		(net 84)
	)
	(arc
		(start 118.672108 146.738762)
		(mid 118.889471 146.883999)
		(end 119.145869 146.935)
		(width 0.185)
		(layer "B.Cu")
		(net 84)
	)
	(arc
		(start 127.185868 141.695)
		(mid 126.803185 141.77112)
		(end 126.478761 141.987893)
		(width 0.185)
		(layer "B.Cu")
		(net 84)
	)
	(segment
		(start 127.345869 98.165)
		(end 140.774131 98.165)
		(width 0.185)
		(layer "F.Cu")
		(net 85)
	)
	(segment
		(start 122.403945 103.43484)
		(end 122.474655 103.364129)
		(width 0.185)
		(layer "F.Cu")
		(net 85)
	)
	(segment
		(start 123.111058 102.727739)
		(end 123.181768 102.657028)
		(width 0.185)
		(layer "F.Cu")
		(net 85)
	)
	(segment
		(start 122.808332 102.707856)
		(end 122.828215 102.727739)
		(width 0.185)
		(layer "F.Cu")
		(net 85)
	)
	(segment
		(start 122.101225 103.414963)
		(end 122.121102 103.43484)
		(width 0.185)
		(layer "F.Cu")
		(net 85)
	)
	(segment
		(start 122.275 124.509749)
		(end 122.19 124.424749)
		(width 0.185)
		(layer "F.Cu")
		(net 85)
	)
	(segment
		(start 120.754128 122.260013)
		(end 118.677522 122.260006)
		(width 0.185)
		(layer "F.Cu")
		(net 85)
	)
	(segment
		(start 140.685131 107.834)
		(end 139.863001 107.834)
		(width 0.185)
		(layer "F.Cu")
		(net 85)
	)
	(segment
		(start 143.458762 105.337892)
		(end 141.158893 107.637761)
		(width 0.185)
		(layer "F.Cu")
		(net 85)
	)
	(segment
		(start 122.275 125.166)
		(end 122.275 124.509749)
		(width 0.185)
		(layer "F.Cu")
		(net 85)
	)
	(segment
		(start 139.627001 107.598)
		(end 138.802 107.598)
		(width 0.185)
		(layer "F.Cu")
		(net 85)
	)
	(segment
		(start 121.818382 103.414963)
		(end 121.818383 103.414963)
		(width 0.185)
		(layer "F.Cu")
		(net 85)
	)
	(segment
		(start 119.275438 105.957908)
		(end 121.111276 104.12207)
		(width 0.185)
		(layer "F.Cu")
		(net 85)
	)
	(segment
		(start 122.474655 103.081286)
		(end 122.454777 103.061408)
		(width 0.185)
		(layer "F.Cu")
		(net 85)
	)
	(segment
		(start 121.897098 122.988772)
		(end 121.461232 122.552906)
		(width 0.185)
		(layer "F.Cu")
		(net 85)
	)
	(segment
		(start 121.74767 103.485672)
		(end 121.818382 103.414963)
		(width 0.185)
		(layer "F.Cu")
		(net 85)
	)
	(segment
		(start 143.655 101.045869)
		(end 143.655 104.864131)
		(width 0.185)
		(layer "F.Cu")
		(net 85)
	)
	(segment
		(start 122.454777 102.778565)
		(end 122.525489 102.707856)
		(width 0.185)
		(layer "F.Cu")
		(net 85)
	)
	(segment
		(start 121.394118 104.12207)
		(end 121.413995 104.141947)
		(width 0.185)
		(layer "F.Cu")
		(net 85)
	)
	(segment
		(start 141.247892 98.361238)
		(end 143.458761 100.572107)
		(width 0.185)
		(layer "F.Cu")
		(net 85)
	)
	(segment
		(start 122.19 124.424749)
		(end 122.189991 123.695867)
		(width 0.185)
		(layer "F.Cu")
		(net 85)
	)
	(segment
		(start 121.767548 103.788393)
		(end 121.74767 103.768515)
		(width 0.185)
		(layer "F.Cu")
		(net 85)
	)
	(segment
		(start 123.161884 102.071458)
		(end 123.232596 102.000749)
		(width 0.185)
		(layer "F.Cu")
		(net 85)
	)
	(segment
		(start 114.330003 117.912475)
		(end 114.329989 111.180866)
		(width 0.185)
		(layer "F.Cu")
		(net 85)
	)
	(segment
		(start 118.203762 122.063767)
		(end 114.526241 118.386235)
		(width 0.185)
		(layer "F.Cu")
		(net 85)
	)
	(segment
		(start 121.696838 104.141947)
		(end 121.767548 104.071236)
		(width 0.185)
		(layer "F.Cu")
		(net 85)
	)
	(segment
		(start 123.232596 102.000749)
		(end 126.872107 98.361239)
		(width 0.185)
		(layer "F.Cu")
		(net 85)
	)
	(segment
		(start 119.275439 105.957909)
		(end 119.275438 105.957908)
		(width 0.185)
		(layer "F.Cu")
		(net 85)
	)
	(segment
		(start 123.181768 102.374185)
		(end 123.161884 102.354301)
		(width 0.185)
		(layer "F.Cu")
		(net 85)
	)
	(segment
		(start 139.863001 107.834)
		(end 139.627001 107.598)
		(width 0.185)
		(layer "F.Cu")
		(net 85)
	)
	(segment
		(start 114.526228 110.707102)
		(end 119.275439 105.957909)
		(width 0.185)
		(layer "F.Cu")
		(net 85)
	)
	(segment
		(start 122.525489 102.707856)
		(end 122.52549 102.707856)
		(width 0.185)
		(layer "F.Cu")
		(net 85)
	)
	(arc
		(start 121.461232 122.552906)
		(mid 121.13681 122.336134)
		(end 120.754128 122.260013)
		(width 0.185)
		(layer "F.Cu")
		(net 85)
	)
	(arc
		(start 121.818383 103.414963)
		(mid 121.959804 103.356385)
		(end 122.101225 103.414963)
		(width 0.185)
		(layer "F.Cu")
		(net 85)
	)
	(arc
		(start 114.526241 118.386235)
		(mid 114.381004 118.168872)
		(end 114.330003 117.912475)
		(width 0.185)
		(layer "F.Cu")
		(net 85)
	)
	(arc
		(start 141.158893 107.637761)
		(mid 140.941529 107.782999)
		(end 140.685131 107.834)
		(width 0.185)
		(layer "F.Cu")
		(net 85)
	)
	(arc
		(start 123.181768 102.657028)
		(mid 123.240347 102.515606)
		(end 123.181768 102.374185)
		(width 0.185)
		(layer "F.Cu")
		(net 85)
	)
	(arc
		(start 143.655 104.864131)
		(mid 143.603999 105.120529)
		(end 143.458762 105.337892)
		(width 0.185)
		(layer "F.Cu")
		(net 85)
	)
	(arc
		(start 140.774131 98.165)
		(mid 141.030529 98.216001)
		(end 141.247892 98.361238)
		(width 0.185)
		(layer "F.Cu")
		(net 85)
	)
	(arc
		(start 122.454777 103.061408)
		(mid 122.396198 102.919987)
		(end 122.454777 102.778565)
		(width 0.185)
		(layer "F.Cu")
		(net 85)
	)
	(arc
		(start 121.767548 104.071236)
		(mid 121.826127 103.929814)
		(end 121.767548 103.788393)
		(width 0.185)
		(layer "F.Cu")
		(net 85)
	)
	(arc
		(start 123.161884 102.354301)
		(mid 123.103305 102.21288)
		(end 123.161884 102.071458)
		(width 0.185)
		(layer "F.Cu")
		(net 85)
	)
	(arc
		(start 122.121102 103.43484)
		(mid 122.262524 103.493418)
		(end 122.403945 103.43484)
		(width 0.185)
		(layer "F.Cu")
		(net 85)
	)
	(arc
		(start 121.74767 103.768515)
		(mid 121.689091 103.627094)
		(end 121.74767 103.485672)
		(width 0.185)
		(layer "F.Cu")
		(net 85)
	)
	(arc
		(start 121.413995 104.141947)
		(mid 121.555417 104.200525)
		(end 121.696838 104.141947)
		(width 0.185)
		(layer "F.Cu")
		(net 85)
	)
	(arc
		(start 122.52549 102.707856)
		(mid 122.666911 102.649278)
		(end 122.808332 102.707856)
		(width 0.185)
		(layer "F.Cu")
		(net 85)
	)
	(arc
		(start 122.474655 103.364129)
		(mid 122.533234 103.222707)
		(end 122.474655 103.081286)
		(width 0.185)
		(layer "F.Cu")
		(net 85)
	)
	(arc
		(start 126.872107 98.361239)
		(mid 127.089471 98.216001)
		(end 127.345869 98.165)
		(width 0.185)
		(layer "F.Cu")
		(net 85)
	)
	(arc
		(start 122.828215 102.727739)
		(mid 122.969637 102.786317)
		(end 123.111058 102.727739)
		(width 0.185)
		(layer "F.Cu")
		(net 85)
	)
	(arc
		(start 143.458761 100.572107)
		(mid 143.603999 100.789471)
		(end 143.655 101.045869)
		(width 0.185)
		(layer "F.Cu")
		(net 85)
	)
	(arc
		(start 114.329989 111.180866)
		(mid 114.380989 110.924467)
		(end 114.526228 110.707102)
		(width 0.185)
		(layer "F.Cu")
		(net 85)
	)
	(arc
		(start 122.189991 123.695867)
		(mid 122.113869 123.31319)
		(end 121.897098 122.988772)
		(width 0.185)
		(layer "F.Cu")
		(net 85)
	)
	(arc
		(start 118.677522 122.260006)
		(mid 118.421125 122.209005)
		(end 118.203762 122.063767)
		(width 0.185)
		(layer "F.Cu")
		(net 85)
	)
	(arc
		(start 121.111276 104.12207)
		(mid 121.252697 104.063492)
		(end 121.394118 104.12207)
		(width 0.185)
		(layer "F.Cu")
		(net 85)
	)
	(segment
		(start 138.802 105.999)
		(end 139.627001 105.999)
		(width 0.185)
		(layer "F.Cu")
		(net 86)
	)
	(segment
		(start 141.612107 101.148761)
		(end 140.331239 99.867893)
		(width 0.185)
		(layer "F.Cu")
		(net 86)
	)
	(segment
		(start 118.898755 120.722113)
		(end 117.267893 119.091251)
		(width 0.185)
		(layer "F.Cu")
		(net 86)
	)
	(segment
		(start 116.975 111.925868)
		(end 116.975 118.384144)
		(width 0.185)
		(layer "F.Cu")
		(net 86)
	)
	(segment
		(start 122.127899 121.211229)
		(end 123.163772 122.247102)
		(width 0.185)
		(layer "F.Cu")
		(net 86)
	)
	(segment
		(start 141.905 104.044132)
		(end 141.905 101.855868)
		(width 0.185)
		(layer "F.Cu")
		(net 86)
	)
	(segment
		(start 123.275 124.509749)
		(end 123.275 125.166)
		(width 0.185)
		(layer "F.Cu")
		(net 86)
	)
	(segment
		(start 139.862501 105.7635)
		(end 140.185632 105.7635)
		(width 0.185)
		(layer "F.Cu")
		(net 86)
	)
	(segment
		(start 139.627001 105.999)
		(end 139.862501 105.7635)
		(width 0.185)
		(layer "F.Cu")
		(net 86)
	)
	(segment
		(start 123.36 124.424749)
		(end 123.275 124.509749)
		(width 0.185)
		(layer "F.Cu")
		(net 86)
	)
	(segment
		(start 128.618761 99.867893)
		(end 117.267893 111.218761)
		(width 0.185)
		(layer "F.Cu")
		(net 86)
	)
	(segment
		(start 140.892739 105.470607)
		(end 141.612107 104.751239)
		(width 0.185)
		(layer "F.Cu")
		(net 86)
	)
	(segment
		(start 119.605873 121.015006)
		(end 121.654132 121.01499)
		(width 0.185)
		(layer "F.Cu")
		(net 86)
	)
	(segment
		(start 119.605865 121.015006)
		(end 119.605862 121.015006)
		(width 0.185)
		(layer "F.Cu")
		(net 86)
	)
	(segment
		(start 123.36001 122.720867)
		(end 123.36 124.424749)
		(width 0.185)
		(layer "F.Cu")
		(net 86)
	)
	(segment
		(start 139.624132 99.575)
		(end 129.325868 99.575)
		(width 0.185)
		(layer "F.Cu")
		(net 86)
	)
	(arc
		(start 118.898755 120.722113)
		(mid 119.223178 120.938886)
		(end 119.605862 121.015006)
		(width 0.185)
		(layer "F.Cu")
		(net 86)
	)
	(arc
		(start 139.624132 99.575)
		(mid 140.006815 99.65112)
		(end 140.331239 99.867893)
		(width 0.185)
		(layer "F.Cu")
		(net 86)
	)
	(arc
		(start 116.975 118.384144)
		(mid 117.05112 118.766827)
		(end 117.267893 119.091251)
		(width 0.185)
		(layer "F.Cu")
		(net 86)
	)
	(arc
		(start 141.905 104.044132)
		(mid 141.82888 104.426815)
		(end 141.612107 104.751239)
		(width 0.185)
		(layer "F.Cu")
		(net 86)
	)
	(arc
		(start 116.975 111.925868)
		(mid 117.05112 111.543185)
		(end 117.267893 111.218761)
		(width 0.185)
		(layer "F.Cu")
		(net 86)
	)
	(arc
		(start 141.905 101.855868)
		(mid 141.82888 101.473185)
		(end 141.612107 101.148761)
		(width 0.185)
		(layer "F.Cu")
		(net 86)
	)
	(arc
		(start 121.654132 121.01499)
		(mid 121.910533 121.06599)
		(end 122.127899 121.211229)
		(width 0.185)
		(layer "F.Cu")
		(net 86)
	)
	(arc
		(start 119.605873 121.015006)
		(mid 119.605869 121.015006)
		(end 119.605865 121.015006)
		(width 0.185)
		(layer "F.Cu")
		(net 86)
	)
	(arc
		(start 123.163772 122.247102)
		(mid 123.30901 122.464467)
		(end 123.36001 122.720867)
		(width 0.185)
		(layer "F.Cu")
		(net 86)
	)
	(arc
		(start 140.892739 105.470607)
		(mid 140.568316 105.68738)
		(end 140.185632 105.7635)
		(width 0.185)
		(layer "F.Cu")
		(net 86)
	)
	(arc
		(start 128.618761 99.867893)
		(mid 128.943184 99.65112)
		(end 129.325868 99.575)
		(width 0.185)
		(layer "F.Cu")
		(net 86)
	)
	(segment
		(start 123.775 124.509749)
		(end 123.69 124.424749)
		(width 0.185)
		(layer "F.Cu")
		(net 87)
	)
	(segment
		(start 123.175208 105.778134)
		(end 123.24592 105.707425)
		(width 0.185)
		(layer "F.Cu")
		(net 87)
	)
	(segment
		(start 139.862501 105.4335)
		(end 139.627001 105.198)
		(width 0.185)
		(layer "F.Cu")
		(net 87)
	)
	(segment
		(start 129.325869 99.905)
		(end 139.624131 99.905)
		(width 0.185)
		(layer "F.Cu")
		(net 87)
	)
	(segment
		(start 123.528763 105.707425)
		(end 123.550576 105.729238)
		(width 0.185)
		(layer "F.Cu")
		(net 87)
	)
	(segment
		(start 117.501239 111.452107)
		(end 122.538814 106.414532)
		(width 0.185)
		(layer "F.Cu")
		(net 87)
	)
	(segment
		(start 123.197022 106.082791)
		(end 123.175208 106.060977)
		(width 0.185)
		(layer "F.Cu")
		(net 87)
	)
	(segment
		(start 124.660134 104.293211)
		(end 128.852108 100.101238)
		(width 0.185)
		(layer "F.Cu")
		(net 87)
	)
	(segment
		(start 123.882315 105.071027)
		(end 123.953027 105.000318)
		(width 0.185)
		(layer "F.Cu")
		(net 87)
	)
	(segment
		(start 123.24592 105.707425)
		(end 123.245921 105.707425)
		(width 0.185)
		(layer "F.Cu")
		(net 87)
	)
	(segment
		(start 117.305 118.384143)
		(end 117.305 111.925869)
		(width 0.185)
		(layer "F.Cu")
		(net 87)
	)
	(segment
		(start 123.833419 105.729238)
		(end 123.904129 105.658527)
		(width 0.185)
		(layer "F.Cu")
		(net 87)
	)
	(segment
		(start 141.378761 104.517893)
		(end 140.659392 105.237262)
		(width 0.185)
		(layer "F.Cu")
		(net 87)
	)
	(segment
		(start 123.775 125.166)
		(end 123.775 124.509749)
		(width 0.185)
		(layer "F.Cu")
		(net 87)
	)
	(segment
		(start 140.185631 105.4335)
		(end 139.862501 105.4335)
		(width 0.185)
		(layer "F.Cu")
		(net 87)
	)
	(segment
		(start 123.397114 122.013756)
		(end 122.361241 120.977883)
		(width 0.185)
		(layer "F.Cu")
		(net 87)
	)
	(segment
		(start 123.953027 105.000318)
		(end 123.953028 105.000318)
		(width 0.185)
		(layer "F.Cu")
		(net 87)
	)
	(segment
		(start 124.589421 104.363921)
		(end 124.660134 104.293211)
		(width 0.185)
		(layer "F.Cu")
		(net 87)
	)
	(segment
		(start 119.132079 120.488745)
		(end 117.501238 118.857904)
		(width 0.185)
		(layer "F.Cu")
		(net 87)
	)
	(segment
		(start 122.821656 106.414532)
		(end 122.843469 106.436345)
		(width 0.185)
		(layer "F.Cu")
		(net 87)
	)
	(segment
		(start 124.540519 105.022125)
		(end 124.611229 104.951414)
		(width 0.185)
		(layer "F.Cu")
		(net 87)
	)
	(segment
		(start 141.575 101.855869)
		(end 141.575 104.044131)
		(width 0.185)
		(layer "F.Cu")
		(net 87)
	)
	(segment
		(start 140.097893 100.101239)
		(end 141.378762 101.382108)
		(width 0.185)
		(layer "F.Cu")
		(net 87)
	)
	(segment
		(start 124.611229 104.668571)
		(end 124.589421 104.646763)
		(width 0.185)
		(layer "F.Cu")
		(net 87)
	)
	(segment
		(start 124.23587 105.000318)
		(end 124.257677 105.022125)
		(width 0.185)
		(layer "F.Cu")
		(net 87)
	)
	(segment
		(start 121.654137 120.68499)
		(end 119.605872 120.684984)
		(width 0.185)
		(layer "F.Cu")
		(net 87)
	)
	(segment
		(start 123.126312 106.436345)
		(end 123.197022 106.365634)
		(width 0.185)
		(layer "F.Cu")
		(net 87)
	)
	(segment
		(start 123.904129 105.375684)
		(end 123.882315 105.35387)
		(width 0.185)
		(layer "F.Cu")
		(net 87)
	)
	(segment
		(start 139.627001 105.198)
		(end 138.802 105.198)
		(width 0.185)
		(layer "F.Cu")
		(net 87)
	)
	(segment
		(start 123.69 124.424749)
		(end 123.690007 122.720867)
		(width 0.185)
		(layer "F.Cu")
		(net 87)
	)
	(segment
		(start 119.605872 120.684984)
		(end 119.605841 120.684984)
		(width 0.185)
		(layer "F.Cu")
		(net 87)
	)
	(arc
		(start 122.361241 120.977883)
		(mid 122.036819 120.761111)
		(end 121.654137 120.68499)
		(width 0.185)
		(layer "F.Cu")
		(net 87)
	)
	(arc
		(start 117.501238 118.857904)
		(mid 117.356001 118.640541)
		(end 117.305 118.384143)
		(width 0.185)
		(layer "F.Cu")
		(net 87)
	)
	(arc
		(start 124.589421 104.646763)
		(mid 124.530843 104.505342)
		(end 124.589421 104.363921)
		(width 0.185)
		(layer "F.Cu")
		(net 87)
	)
	(arc
		(start 119.605841 120.684984)
		(mid 119.349443 120.633983)
		(end 119.132079 120.488745)
		(width 0.185)
		(layer "F.Cu")
		(net 87)
	)
	(arc
		(start 141.378762 101.382108)
		(mid 141.523999 101.599471)
		(end 141.575 101.855869)
		(width 0.185)
		(layer "F.Cu")
		(net 87)
	)
	(arc
		(start 122.538814 106.414532)
		(mid 122.680235 106.355954)
		(end 122.821656 106.414532)
		(width 0.185)
		(layer "F.Cu")
		(net 87)
	)
	(arc
		(start 139.624131 99.905)
		(mid 139.880529 99.956001)
		(end 140.097893 100.101239)
		(width 0.185)
		(layer "F.Cu")
		(net 87)
	)
	(arc
		(start 123.690007 122.720867)
		(mid 123.613888 122.338181)
		(end 123.397114 122.013756)
		(width 0.185)
		(layer "F.Cu")
		(net 87)
	)
	(arc
		(start 123.245921 105.707425)
		(mid 123.387342 105.648847)
		(end 123.528763 105.707425)
		(width 0.185)
		(layer "F.Cu")
		(net 87)
	)
	(arc
		(start 124.611229 104.951414)
		(mid 124.669808 104.809992)
		(end 124.611229 104.668571)
		(width 0.185)
		(layer "F.Cu")
		(net 87)
	)
	(arc
		(start 123.953028 105.000318)
		(mid 124.094449 104.94174)
		(end 124.23587 105.000318)
		(width 0.185)
		(layer "F.Cu")
		(net 87)
	)
	(arc
		(start 123.904129 105.658527)
		(mid 123.962708 105.517105)
		(end 123.904129 105.375684)
		(width 0.185)
		(layer "F.Cu")
		(net 87)
	)
	(arc
		(start 123.882315 105.35387)
		(mid 123.823736 105.212449)
		(end 123.882315 105.071027)
		(width 0.185)
		(layer "F.Cu")
		(net 87)
	)
	(arc
		(start 141.575 104.044131)
		(mid 141.523999 104.300529)
		(end 141.378761 104.517893)
		(width 0.185)
		(layer "F.Cu")
		(net 87)
	)
	(arc
		(start 117.305 111.925869)
		(mid 117.356001 111.669471)
		(end 117.501239 111.452107)
		(width 0.185)
		(layer "F.Cu")
		(net 87)
	)
	(arc
		(start 122.843469 106.436345)
		(mid 122.984891 106.494923)
		(end 123.126312 106.436345)
		(width 0.185)
		(layer "F.Cu")
		(net 87)
	)
	(arc
		(start 128.852108 100.101238)
		(mid 129.069471 99.956001)
		(end 129.325869 99.905)
		(width 0.185)
		(layer "F.Cu")
		(net 87)
	)
	(arc
		(start 123.175208 106.060977)
		(mid 123.116629 105.919556)
		(end 123.175208 105.778134)
		(width 0.185)
		(layer "F.Cu")
		(net 87)
	)
	(arc
		(start 140.659392 105.237262)
		(mid 140.442029 105.382499)
		(end 140.185631 105.4335)
		(width 0.185)
		(layer "F.Cu")
		(net 87)
	)
	(arc
		(start 124.257677 105.022125)
		(mid 124.399098 105.080703)
		(end 124.540519 105.022125)
		(width 0.185)
		(layer "F.Cu")
		(net 87)
	)
	(arc
		(start 123.197022 106.365634)
		(mid 123.255601 106.224212)
		(end 123.197022 106.082791)
		(width 0.185)
		(layer "F.Cu")
		(net 87)
	)
	(arc
		(start 123.550576 105.729238)
		(mid 123.691998 105.787816)
		(end 123.833419 105.729238)
		(width 0.185)
		(layer "F.Cu")
		(net 87)
	)
	(segment
		(start 121.775 124.509749)
		(end 121.775 125.166)
		(width 0.185)
		(layer "F.Cu")
		(net 88)
	)
	(segment
		(start 126.63879 98.127884)
		(end 114.312906 110.453768)
		(width 0.185)
		(layer "F.Cu")
		(net 88)
	)
	(segment
		(start 143.692107 100.338761)
		(end 141.48123 98.127884)
		(width 0.185)
		(layer "F.Cu")
		(net 88)
	)
	(segment
		(start 121.86 124.424749)
		(end 121.775 124.509749)
		(width 0.185)
		(layer "F.Cu")
		(net 88)
	)
	(segment
		(start 143.985 104.864132)
		(end 143.985 101.045868)
		(width 0.185)
		(layer "F.Cu")
		(net 88)
	)
	(segment
		(start 114.020013 111.160872)
		(end 114.019992 117.93248)
		(width 0.185)
		(layer "F.Cu")
		(net 88)
	)
	(segment
		(start 139.863001 108.164)
		(end 140.685132 108.164)
		(width 0.185)
		(layer "F.Cu")
		(net 88)
	)
	(segment
		(start 138.802 108.4)
		(end 139.627001 108.4)
		(width 0.185)
		(layer "F.Cu")
		(net 88)
	)
	(segment
		(start 121.860009 123.695879)
		(end 121.86 124.424749)
		(width 0.185)
		(layer "F.Cu")
		(net 88)
	)
	(segment
		(start 121.227882 122.786243)
		(end 121.663759 123.222098)
		(width 0.185)
		(layer "F.Cu")
		(net 88)
	)
	(segment
		(start 114.312886 118.63959)
		(end 117.970413 122.297117)
		(width 0.185)
		(layer "F.Cu")
		(net 88)
	)
	(segment
		(start 139.627001 108.4)
		(end 139.863001 108.164)
		(width 0.185)
		(layer "F.Cu")
		(net 88)
	)
	(segment
		(start 118.677517 122.59001)
		(end 120.754134 122.590016)
		(width 0.185)
		(layer "F.Cu")
		(net 88)
	)
	(segment
		(start 140.774123 97.834991)
		(end 127.345897 97.834991)
		(width 0.185)
		(layer "F.Cu")
		(net 88)
	)
	(segment
		(start 141.392239 107.871107)
		(end 143.692107 105.571239)
		(width 0.185)
		(layer "F.Cu")
		(net 88)
	)
	(arc
		(start 126.63879 98.127884)
		(mid 126.963213 97.911111)
		(end 127.345897 97.834991)
		(width 0.185)
		(layer "F.Cu")
		(net 88)
	)
	(arc
		(start 120.754134 122.590016)
		(mid 121.010523 122.641014)
		(end 121.227882 122.786243)
		(width 0.185)
		(layer "F.Cu")
		(net 88)
	)
	(arc
		(start 121.663759 123.222098)
		(mid 121.809007 123.439469)
		(end 121.860009 123.695879)
		(width 0.185)
		(layer "F.Cu")
		(net 88)
	)
	(arc
		(start 114.020013 111.160872)
		(mid 114.096134 110.77819)
		(end 114.312906 110.453768)
		(width 0.185)
		(layer "F.Cu")
		(net 88)
	)
	(arc
		(start 140.685132 108.164)
		(mid 141.067815 108.08788)
		(end 141.392239 107.871107)
		(width 0.185)
		(layer "F.Cu")
		(net 88)
	)
	(arc
		(start 143.985 101.045868)
		(mid 143.90888 100.663185)
		(end 143.692107 100.338761)
		(width 0.185)
		(layer "F.Cu")
		(net 88)
	)
	(arc
		(start 141.48123 98.127884)
		(mid 141.156807 97.911111)
		(end 140.774123 97.834991)
		(width 0.185)
		(layer "F.Cu")
		(net 88)
	)
	(arc
		(start 114.019992 117.93248)
		(mid 114.096112 118.315165)
		(end 114.312886 118.63959)
		(width 0.185)
		(layer "F.Cu")
		(net 88)
	)
	(arc
		(start 118.677517 122.59001)
		(mid 118.294835 122.513889)
		(end 117.970413 122.297117)
		(width 0.185)
		(layer "F.Cu")
		(net 88)
	)
	(arc
		(start 143.692107 105.571239)
		(mid 143.90888 105.246816)
		(end 143.985 104.864132)
		(width 0.185)
		(layer "F.Cu")
		(net 88)
	)
	(segment
		(start 119.743751 114.643751)
		(end 119.555 114.643751)
		(width 0.2)
		(layer "F.Cu")
		(net 89)
	)
	(segment
		(start 119.978251 114.878251)
		(end 119.743751 114.643751)
		(width 0.2)
		(layer "F.Cu")
		(net 89)
	)
	(segment
		(start 120.567 114.878251)
		(end 119.978251 114.878251)
		(width 0.2)
		(layer "F.Cu")
		(net 89)
	)
	(via
		(at 119.555 114.643751)
		(size 0.45)
		(drill 0.1)
		(layers "F.Cu" "B.Cu")
		(net 89)
	)
	(segment
		(start 116.955 113.973751)
		(end 117.845 113.973751)
		(width 0.2)
		(layer "B.Cu")
		(net 89)
	)
	(segment
		(start 118.929214 114.643751)
		(end 119.555 114.643751)
		(width 0.2)
		(layer "B.Cu")
		(net 89)
	)
	(segment
		(start 117.845 113.973751)
		(end 118.222107 114.350858)
		(width 0.2)
		(layer "B.Cu")
		(net 89)
	)
	(arc
		(start 118.222107 114.350858)
		(mid 118.54653 114.567631)
		(end 118.929214 114.643751)
		(width 0.2)
		(layer "B.Cu")
		(net 89)
	)
	(segment
		(start 119.8 115.8)
		(end 119.616249 115.983751)
		(width 0.2)
		(layer "F.Cu")
		(net 90)
	)
	(segment
		(start 119.8 115.54)
		(end 119.8 115.8)
		(width 0.2)
		(layer "F.Cu")
		(net 90)
	)
	(segment
		(start 120.567 115.378251)
		(end 119.961749 115.378251)
		(width 0.2)
		(layer "F.Cu")
		(net 90)
	)
	(segment
		(start 119.961749 115.378251)
		(end 119.8 115.54)
		(width 0.2)
		(layer "F.Cu")
		(net 90)
	)
	(via
		(at 119.555 115.983751)
		(size 0.45)
		(drill 0.1)
		(layers "F.Cu" "B.Cu")
		(net 90)
	)
	(segment
		(start 116.955 115.313751)
		(end 117.845 115.313751)
		(width 0.2)
		(layer "B.Cu")
		(net 90)
	)
	(segment
		(start 119.305 115.983751)
		(end 118.929214 115.983751)
		(width 0.2)
		(layer "B.Cu")
		(net 90)
	)
	(segment
		(start 118.222107 115.690858)
		(end 117.845 115.313751)
		(width 0.2)
		(layer "B.Cu")
		(net 90)
	)
	(arc
		(start 118.929214 115.983751)
		(mid 118.546531 115.907631)
		(end 118.222107 115.690858)
		(width 0.2)
		(layer "B.Cu")
		(net 90)
	)
	(segment
		(start 121.005 117.316251)
		(end 121.005 118.153751)
		(width 0.2)
		(layer "F.Cu")
		(net 91)
	)
	(via
		(at 121.005 118.153751)
		(size 0.45)
		(drill 0.1)
		(layers "F.Cu" "B.Cu")
		(free yes)
		(net 91)
	)
	(segment
		(start 117.844 116.653751)
		(end 118.223107 117.032858)
		(width 0.2)
		(layer "B.Cu")
		(net 91)
	)
	(segment
		(start 119.742909 117.442909)
		(end 119.862843 117.562843)
		(width 0.2)
		(layer "B.Cu")
		(net 91)
	)
	(segment
		(start 116.955 116.653751)
		(end 117.844 116.653751)
		(width 0.2)
		(layer "B.Cu")
		(net 91)
	)
	(segment
		(start 119.98 117.845685)
		(end 119.98 117.924315)
		(width 0.2)
		(layer "B.Cu")
		(net 91)
	)
	(segment
		(start 120.097158 118.207158)
		(end 120.202843 118.312843)
		(width 0.2)
		(layer "B.Cu")
		(net 91)
	)
	(segment
		(start 118.930214 117.325751)
		(end 119.460066 117.325751)
		(width 0.2)
		(layer "B.Cu")
		(net 91)
	)
	(segment
		(start 120.845909 118.312842)
		(end 121.005 118.153751)
		(width 0.2)
		(layer "B.Cu")
		(net 91)
	)
	(segment
		(start 120.485685 118.43)
		(end 120.563066 118.43)
		(width 0.2)
		(layer "B.Cu")
		(net 91)
	)
	(arc
		(start 120.485685 118.43)
		(mid 120.332612 118.399552)
		(end 120.202843 118.312843)
		(width 0.2)
		(layer "B.Cu")
		(net 91)
	)
	(arc
		(start 120.097158 118.207158)
		(mid 120.010449 118.077389)
		(end 119.98 117.924315)
		(width 0.2)
		(layer "B.Cu")
		(net 91)
	)
	(arc
		(start 118.930214 117.325751)
		(mid 118.547531 117.249631)
		(end 118.223107 117.032858)
		(width 0.2)
		(layer "B.Cu")
		(net 91)
	)
	(arc
		(start 120.563066 118.43)
		(mid 120.71614 118.399552)
		(end 120.845909 118.312842)
		(width 0.2)
		(layer "B.Cu")
		(net 91)
	)
	(arc
		(start 119.742909 117.442909)
		(mid 119.61314 117.3562)
		(end 119.460066 117.325751)
		(width 0.2)
		(layer "B.Cu")
		(net 91)
	)
	(arc
		(start 119.862843 117.562843)
		(mid 119.949552 117.692612)
		(end 119.98 117.845685)
		(width 0.2)
		(layer "B.Cu")
		(net 91)
	)
	(segment
		(start 121.505 113.941251)
		(end 121.505 112.66)
		(width 0.2)
		(layer "F.Cu")
		(net 92)
	)
	(via
		(at 121.505 112.66)
		(size 0.45)
		(drill 0.1)
		(layers "F.Cu" "B.Cu")
		(free yes)
		(net 92)
	)
	(segment
		(start 121.505 112.66)
		(end 120.907893 112.062893)
		(width 0.2)
		(layer "B.Cu")
		(net 92)
	)
	(segment
		(start 118.228356 111.477107)
		(end 117.845 111.093751)
		(width 0.2)
		(layer "B.Cu")
		(net 92)
	)
	(segment
		(start 120.200786 111.77)
		(end 118.935463 111.77)
		(width 0.2)
		(layer "B.Cu")
		(net 92)
	)
	(segment
		(start 116.955 111.093751)
		(end 117.845 111.093751)
		(width 0.2)
		(layer "B.Cu")
		(net 92)
	)
	(arc
		(start 118.228356 111.477107)
		(mid 118.552779 111.69388)
		(end 118.935463 111.77)
		(width 0.2)
		(layer "B.Cu")
		(net 92)
	)
	(arc
		(start 120.200786 111.77)
		(mid 120.583469 111.84612)
		(end 120.907893 112.062893)
		(width 0.2)
		(layer "B.Cu")
		(net 92)
	)
	(segment
		(start 121.005 113.941251)
		(end 121.005 113.083751)
		(width 0.2)
		(layer "F.Cu")
		(net 93)
	)
	(via
		(at 121.005 113.083751)
		(size 0.45)
		(drill 0.1)
		(layers "F.Cu" "B.Cu")
		(net 93)
	)
	(segment
		(start 121.005 113.083751)
		(end 118.909214 113.083751)
		(width 0.2)
		(layer "B.Cu")
		(net 93)
	)
	(segment
		(start 116.955 112.433751)
		(end 117.845 112.433751)
		(width 0.2)
		(layer "B.Cu")
		(net 93)
	)
	(segment
		(start 118.202107 112.790858)
		(end 117.845 112.433751)
		(width 0.2)
		(layer "B.Cu")
		(net 93)
	)
	(arc
		(start 118.909214 113.083751)
		(mid 118.526531 113.007631)
		(end 118.202107 112.790858)
		(width 0.2)
		(layer "B.Cu")
		(net 93)
	)
	(segment
		(start 121.505 117.316251)
		(end 121.505 118.158644)
		(width 0.2)
		(layer "F.Cu")
		(net 94)
	)
	(segment
		(start 121.358553 118.512198)
		(end 121.005 118.865751)
		(width 0.2)
		(layer "F.Cu")
		(net 94)
	)
	(via
		(at 121.005 118.865751)
		(size 0.45)
		(drill 0.1)
		(layers "F.Cu" "B.Cu")
		(net 94)
	)
	(arc
		(start 121.358553 118.512198)
		(mid 121.46694 118.349986)
		(end 121.505 118.158644)
		(width 0.2)
		(layer "F.Cu")
		(net 94)
	)
	(segment
		(start 116.955 118.193751)
		(end 117.844 118.193751)
		(width 0.2)
		(layer "B.Cu")
		(net 94)
	)
	(segment
		(start 118.223107 118.572858)
		(end 117.844 118.193751)
		(width 0.2)
		(layer "B.Cu")
		(net 94)
	)
	(segment
		(start 118.83391 118.865751)
		(end 118.831919 118.86376)
		(width 0.2)
		(layer "B.Cu")
		(net 94)
	)
	(segment
		(start 121.005 118.865751)
		(end 118.83391 118.865751)
		(width 0.2)
		(layer "B.Cu")
		(net 94)
	)
	(arc
		(start 118.831919 118.86376)
		(mid 118.502657 118.769746)
		(end 118.223107 118.572858)
		(width 0.2)
		(layer "B.Cu")
		(net 94)
	)
	(segment
		(start 131.4 117.938)
		(end 131.194446 118.143554)
		(width 0.2)
		(layer "F.Cu")
		(net 95)
	)
	(segment
		(start 130.840893 118.29)
		(end 130.45 118.29)
		(width 0.2)
		(layer "F.Cu")
		(net 95)
	)
	(segment
		(start 130.23 116.845736)
		(end 130.23 116.704264)
		(width 0.2)
		(layer "F.Cu")
		(net 95)
	)
	(segment
		(start 130.97 117.17)
		(end 130.554264 117.17)
		(width 0.2)
		(layer "F.Cu")
		(net 95)
	)
	(segment
		(start 130.142132 116.492132)
		(end 130.116119 116.466119)
		(width 0.2)
		(layer "F.Cu")
		(net 95)
	)
	(segment
		(start 130.342132 117.082132)
		(end 130.317868 117.057868)
		(width 0.2)
		(layer "F.Cu")
		(net 95)
	)
	(segment
		(start 131.126447 117.664447)
		(end 131.4 117.938)
		(width 0.2)
		(layer "F.Cu")
		(net 95)
	)
	(segment
		(start 129.903987 116.378251)
		(end 129.442 116.378251)
		(width 0.2)
		(layer "F.Cu")
		(net 95)
	)
	(via
		(at 131.4 117.938)
		(size 0.45)
		(drill 0.1)
		(layers "F.Cu" "B.Cu")
		(free yes)
		(net 95)
	)
	(arc
		(start 130.23 116.704264)
		(mid 130.207164 116.589459)
		(end 130.142132 116.492132)
		(width 0.2)
		(layer "F.Cu")
		(net 95)
	)
	(arc
		(start 131.126447 117.664447)
		(mid 131.01806 117.502235)
		(end 130.98 117.310893)
		(width 0.2)
		(layer "F.Cu")
		(net 95)
	)
	(arc
		(start 130.317868 117.057868)
		(mid 130.252836 116.960541)
		(end 130.23 116.845736)
		(width 0.2)
		(layer "F.Cu")
		(net 95)
	)
	(arc
		(start 130.116119 116.466119)
		(mid 130.018792 116.401087)
		(end 129.903987 116.378251)
		(width 0.2)
		(layer "F.Cu")
		(net 95)
	)
	(arc
		(start 130.554264 117.17)
		(mid 130.439459 117.147164)
		(end 130.342132 117.082132)
		(width 0.2)
		(layer "F.Cu")
		(net 95)
	)
	(arc
		(start 131.194446 118.143554)
		(mid 131.032234 118.25194)
		(end 130.840893 118.29)
		(width 0.2)
		(layer "F.Cu")
		(net 95)
	)
	(segment
		(start 131.126447 117.664447)
		(end 131.4 117.938)
		(width 0.2)
		(layer "B.Cu")
		(net 95)
	)
	(arc
		(start 130.98 117.310893)
		(mid 131.01806 117.502235)
		(end 131.126447 117.664447)
		(width 0.2)
		(layer "B.Cu")
		(net 95)
	)
	(segment
		(start 125.713 127.604)
		(end 126.314315 127.604)
		(width 0.2)
		(layer "F.Cu")
		(net 96)
	)
	(segment
		(start 126.631092 127.452908)
		(end 126.597157 127.486843)
		(width 0.2)
		(layer "F.Cu")
		(net 96)
	)
	(via
		(at 126.714 127.33575)
		(size 0.45)
		(drill 0.1)
		(layers "F.Cu" "B.Cu")
		(net 96)
	)
	(arc
		(start 126.314315 127.604)
		(mid 126.467388 127.573552)
		(end 126.597157 127.486843)
		(width 0.2)
		(layer "F.Cu")
		(net 96)
	)
	(segment
		(start 126.714 127.33575)
		(end 127.337786 127.33575)
		(width 0.2)
		(layer "B.Cu")
		(net 96)
	)
	(segment
		(start 128.424 128.00775)
		(end 129.314 128.00775)
		(width 0.2)
		(layer "B.Cu")
		(net 96)
	)
	(segment
		(start 128.044893 127.628643)
		(end 128.424 128.00775)
		(width 0.2)
		(layer "B.Cu")
		(net 96)
	)
	(arc
		(start 127.337786 127.33575)
		(mid 127.720469 127.41187)
		(end 128.044893 127.628643)
		(width 0.2)
		(layer "B.Cu")
		(net 96)
	)
	(segment
		(start 128.651447 113.168555)
		(end 128.813555 113.006447)
		(width 0.185)
		(layer "F.Cu")
		(net 97)
	)
	(segment
		(start 128.960001 112.652892)
		(end 128.96 112.36)
		(width 0.185)
		(layer "F.Cu")
		(net 97)
	)
	(segment
		(start 128.505 113.941251)
		(end 128.505001 113.522106)
		(width 0.185)
		(layer "F.Cu")
		(net 97)
	)
	(arc
		(start 128.813555 113.006447)
		(mid 128.921941 112.844235)
		(end 128.960001 112.652892)
		(width 0.185)
		(layer "F.Cu")
		(net 97)
	)
	(arc
		(start 128.651447 113.168555)
		(mid 128.543061 113.330766)
		(end 128.505001 113.522106)
		(width 0.185)
		(layer "F.Cu")
		(net 97)
	)
	(segment
		(start 125.713 127.104)
		(end 126.226 127.104)
		(width 0.2)
		(layer "F.Cu")
		(net 98)
	)
	(segment
		(start 126.226 127.104)
		(end 126.4 126.93)
		(width 0.2)
		(layer "F.Cu")
		(net 98)
	)
	(segment
		(start 126.4 126.93)
		(end 126.4 126.30975)
		(width 0.2)
		(layer "F.Cu")
		(net 98)
	)
	(segment
		(start 126.4 126.30975)
		(end 126.714 125.99575)
		(width 0.2)
		(layer "F.Cu")
		(net 98)
	)
	(via
		(at 126.714 125.99575)
		(size 0.45)
		(drill 0.1)
		(layers "F.Cu" "B.Cu")
		(net 98)
	)
	(segment
		(start 126.714 125.99575)
		(end 127.337786 125.99575)
		(width 0.2)
		(layer "B.Cu")
		(net 98)
	)
	(segment
		(start 128.424 126.66775)
		(end 129.314 126.66775)
		(width 0.2)
		(layer "B.Cu")
		(net 98)
	)
	(segment
		(start 128.044893 126.288643)
		(end 128.424 126.66775)
		(width 0.2)
		(layer "B.Cu")
		(net 98)
	)
	(arc
		(start 128.044893 126.288643)
		(mid 127.72047 126.07187)
		(end 127.337786 125.99575)
		(width 0.2)
		(layer "B.Cu")
		(net 98)
	)
	(segment
		(start 125.275 124.695)
		(end 125.275 125.166)
		(width 0.2)
		(layer "F.Cu")
		(net 99)
	)
	(segment
		(start 125.83 124.56)
		(end 125.41 124.56)
		(width 0.2)
		(layer "F.Cu")
		(net 99)
	)
	(segment
		(start 125.41 124.56)
		(end 125.275 124.695)
		(width 0.2)
		(layer "F.Cu")
		(net 99)
	)
	(via
		(at 125.83 124.56)
		(size 0.45)
		(drill 0.1)
		(layers "F.Cu" "B.Cu")
		(free yes)
		(net 99)
	)
	(segment
		(start 125.83 124.56)
		(end 127.242036 124.56)
		(width 0.2)
		(layer "B.Cu")
		(net 99)
	)
	(segment
		(start 127.949143 124.852893)
		(end 128.424 125.32775)
		(width 0.2)
		(layer "B.Cu")
		(net 99)
	)
	(segment
		(start 128.424 125.32775)
		(end 129.314 125.32775)
		(width 0.2)
		(layer "B.Cu")
		(net 99)
	)
	(arc
		(start 127.242036 124.56)
		(mid 127.624719 124.63612)
		(end 127.949143 124.852893)
		(width 0.2)
		(layer "B.Cu")
		(net 99)
	)
	(segment
		(start 124.775 129.301536)
		(end 124.775 128.541)
		(width 0.2)
		(layer "F.Cu")
		(net 100)
	)
	(segment
		(start 125.275 130.21575)
		(end 125.067893 130.008643)
		(width 0.2)
		(layer "F.Cu")
		(net 100)
	)
	(via
		(at 125.275 130.21575)
		(size 0.45)
		(drill 0.1)
		(layers "F.Cu" "B.Cu")
		(net 100)
	)
	(arc
		(start 124.775 129.301536)
		(mid 124.85112 129.684219)
		(end 125.067893 130.008643)
		(width 0.2)
		(layer "F.Cu")
		(net 100)
	)
	(segment
		(start 128.045893 130.508643)
		(end 128.425 130.88775)
		(width 0.2)
		(layer "B.Cu")
		(net 100)
	)
	(segment
		(start 128.425 130.88775)
		(end 129.314 130.88775)
		(width 0.2)
		(layer "B.Cu")
		(net 100)
	)
	(segment
		(start 125.28 130.21575)
		(end 127.338786 130.21575)
		(width 0.2)
		(layer "B.Cu")
		(net 100)
	)
	(arc
		(start 127.338786 130.21575)
		(mid 127.721469 130.29187)
		(end 128.045893 130.508643)
		(width 0.2)
		(layer "B.Cu")
		(net 100)
	)
	(segment
		(start 125.275 128.541)
		(end 125.275 129.381)
		(width 0.2)
		(layer "F.Cu")
		(net 101)
	)
	(via
		(at 125.275 129.381)
		(size 0.45)
		(drill 0.1)
		(layers "F.Cu" "B.Cu")
		(net 101)
	)
	(segment
		(start 125.275 129.381)
		(end 125.397554 129.503554)
		(width 0.2)
		(layer "B.Cu")
		(net 101)
	)
	(segment
		(start 128.425 129.54775)
		(end 129.314 129.54775)
		(width 0.2)
		(layer "B.Cu")
		(net 101)
	)
	(segment
		(start 127.158464 128.87575)
		(end 127.338786 128.87575)
		(width 0.2)
		(layer "B.Cu")
		(net 101)
	)
	(segment
		(start 126.116447 129.503553)
		(end 126.451357 129.168643)
		(width 0.2)
		(layer "B.Cu")
		(net 101)
	)
	(segment
		(start 125.751107 129.65)
		(end 125.762893 129.65)
		(width 0.2)
		(layer "B.Cu")
		(net 101)
	)
	(segment
		(start 128.045893 129.168643)
		(end 128.425 129.54775)
		(width 0.2)
		(layer "B.Cu")
		(net 101)
	)
	(arc
		(start 125.751107 129.65)
		(mid 125.559766 129.61194)
		(end 125.397554 129.503554)
		(width 0.2)
		(layer "B.Cu")
		(net 101)
	)
	(arc
		(start 126.451357 129.168643)
		(mid 126.77578 128.95187)
		(end 127.158464 128.87575)
		(width 0.2)
		(layer "B.Cu")
		(net 101)
	)
	(arc
		(start 128.045893 129.168643)
		(mid 127.72147 128.95187)
		(end 127.338786 128.87575)
		(width 0.2)
		(layer "B.Cu")
		(net 101)
	)
	(arc
		(start 126.116447 129.503553)
		(mid 125.954235 129.61194)
		(end 125.762893 129.65)
		(width 0.2)
		(layer "B.Cu")
		(net 101)
	)
	(segment
		(start 124.775 125.166)
		(end 124.775 123.92)
		(width 0.2)
		(layer "F.Cu")
		(net 102)
	)
	(via
		(at 124.775 123.92)
		(size 0.45)
		(drill 0.1)
		(layers "F.Cu" "B.Cu")
		(free yes)
		(net 102)
	)
	(segment
		(start 127.194214 123.06)
		(end 127.292036 123.06)
		(width 0.2)
		(layer "B.Cu")
		(net 102)
	)
	(segment
		(start 127.999143 123.352893)
		(end 128.434 123.78775)
		(width 0.2)
		(layer "B.Cu")
		(net 102)
	)
	(segment
		(start 124.775 123.92)
		(end 125.505786 123.92)
		(width 0.2)
		(layer "B.Cu")
		(net 102)
	)
	(segment
		(start 126.212893 123.627107)
		(end 126.487107 123.352893)
		(width 0.2)
		(layer "B.Cu")
		(net 102)
	)
	(segment
		(start 128.434 123.78775)
		(end 129.324 123.78775)
		(width 0.2)
		(layer "B.Cu")
		(net 102)
	)
	(arc
		(start 126.487107 123.352893)
		(mid 126.81153 123.13612)
		(end 127.194214 123.06)
		(width 0.2)
		(layer "B.Cu")
		(net 102)
	)
	(arc
		(start 127.999143 123.352893)
		(mid 127.67472 123.13612)
		(end 127.292036 123.06)
		(width 0.2)
		(layer "B.Cu")
		(net 102)
	)
	(arc
		(start 126.212893 123.627107)
		(mid 125.88847 123.84388)
		(end 125.505786 123.92)
		(width 0.2)
		(layer "B.Cu")
		(net 102)
	)
	(segment
		(start 130.221749 114.878251)
		(end 129.442 114.878251)
		(width 0.2)
		(layer "F.Cu")
		(net 103)
	)
	(via
		(at 130.221749 114.878251)
		(size 0.45)
		(drill 0.1)
		(layers "F.Cu" "B.Cu")
		(net 103)
	)
	(segment
		(start 130.2 112.85)
		(end 130.2 113.79)
		(width 0.2)
		(layer "B.Cu")
		(net 103)
	)
	(segment
		(start 130.221749 114.878251)
		(end 130.221749 113.811749)
		(width 0.2)
		(layer "B.Cu")
		(net 103)
	)
	(segment
		(start 117.775 128.541)
		(end 117.774999 128.992895)
		(width 0.185)
		(layer "F.Cu")
		(net 104)
	)
	(segment
		(start 117.456445 129.518556)
		(end 117.628555 129.346443)
		(width 0.185)
		(layer "F.Cu")
		(net 104)
	)
	(segment
		(start 117.31 130.14)
		(end 117.310001 129.872104)
		(width 0.185)
		(layer "F.Cu")
		(net 104)
	)
	(arc
		(start 117.456445 129.518556)
		(mid 117.348061 129.680766)
		(end 117.310001 129.872104)
		(width 0.185)
		(layer "F.Cu")
		(net 104)
	)
	(arc
		(start 117.774999 128.992895)
		(mid 117.736939 129.184234)
		(end 117.628555 129.346443)
		(width 0.185)
		(layer "F.Cu")
		(net 104)
	)
	(segment
		(start 116.172342 127.721158)
		(end 116.075 127.8185)
		(width 0.2)
		(layer "F.Cu")
		(net 105)
	)
	(segment
		(start 116.838 127.604)
		(end 116.455185 127.604)
		(width 0.2)
		(layer "F.Cu")
		(net 105)
	)
	(via
		(at 116.075 127.8185)
		(size 0.45)
		(drill 0.1)
		(layers "F.Cu" "B.Cu")
		(net 105)
	)
	(arc
		(start 116.172342 127.721158)
		(mid 116.302111 127.634449)
		(end 116.455185 127.604)
		(width 0.2)
		(layer "F.Cu")
		(net 105)
	)
	(segment
		(start 116.07 128.28)
		(end 116.07 129.22)
		(width 0.2)
		(layer "B.Cu")
		(net 105)
	)
	(segment
		(start 129.881144 115.878251)
		(end 129.442 115.878251)
		(width 0.2)
		(layer "F.Cu")
		(net 106)
	)
	(segment
		(start 130.293553 116.083553)
		(end 130.234697 116.024697)
		(width 0.2)
		(layer "F.Cu")
		(net 106)
	)
	(segment
		(start 130.98 116.23)
		(end 130.647107 116.23)
		(width 0.2)
		(layer "F.Cu")
		(net 106)
	)
	(segment
		(start 131.4 115.37)
		(end 131.4 115.237107)
		(width 0.2)
		(layer "F.Cu")
		(net 106)
	)
	(segment
		(start 131.4 115.37)
		(end 131.4 115.81)
		(width 0.2)
		(layer "F.Cu")
		(net 106)
	)
	(segment
		(start 131.4 115.81)
		(end 130.98 116.23)
		(width 0.2)
		(layer "F.Cu")
		(net 106)
	)
	(segment
		(start 131.253553 114.883553)
		(end 131.01 114.64)
		(width 0.2)
		(layer "F.Cu")
		(net 106)
	)
	(via
		(at 131.4 115.462499)
		(size 0.45)
		(drill 0.1)
		(layers "F.Cu" "B.Cu")
		(net 106)
	)
	(arc
		(start 130.234697 116.024697)
		(mid 130.072485 115.916311)
		(end 129.881144 115.878251)
		(width 0.2)
		(layer "F.Cu")
		(net 106)
	)
	(arc
		(start 131.253553 114.883553)
		(mid 131.36194 115.045765)
		(end 131.4 115.237107)
		(width 0.2)
		(layer "F.Cu")
		(net 106)
	)
	(arc
		(start 130.293553 116.083553)
		(mid 130.455765 116.19194)
		(end 130.647107 116.23)
		(width 0.2)
		(layer "F.Cu")
		(net 106)
	)
	(segment
		(start 131.4 115.462499)
		(end 131.4 115.602893)
		(width 0.2)
		(layer "B.Cu")
		(net 106)
	)
	(segment
		(start 131.253553 115.956447)
		(end 130.98 116.23)
		(width 0.2)
		(layer "B.Cu")
		(net 106)
	)
	(arc
		(start 131.4 115.602893)
		(mid 131.36194 115.794235)
		(end 131.253553 115.956447)
		(width 0.2)
		(layer "B.Cu")
		(net 106)
	)
	(segment
		(start 114.81 126.104)
		(end 114.58 125.874)
		(width 0.2)
		(layer "F.Cu")
		(net 107)
	)
	(segment
		(start 116.838 126.104)
		(end 114.81 126.104)
		(width 0.2)
		(layer "F.Cu")
		(net 107)
	)
	(segment
		(start 114.58 125.2)
		(end 114.58 125.874)
		(width 0.2)
		(layer "F.Cu")
		(net 107)
	)
	(via
		(at 114.58 125.874)
		(size 0.45)
		(drill 0.1)
		(layers "F.Cu" "B.Cu")
		(net 107)
	)
	(segment
		(start 113.73 129.8)
		(end 113.729998 126.427106)
		(width 0.2)
		(layer "B.Cu")
		(net 107)
	)
	(segment
		(start 114.283107 125.873998)
		(end 115.29 125.874)
		(width 0.2)
		(layer "B.Cu")
		(net 107)
	)
	(segment
		(start 113.876445 126.073552)
		(end 113.929553 126.020444)
		(width 0.2)
		(layer "B.Cu")
		(net 107)
	)
	(arc
		(start 114.283107 125.873998)
		(mid 114.091765 125.912058)
		(end 113.929553 126.020444)
		(width 0.2)
		(layer "B.Cu")
		(net 107)
	)
	(arc
		(start 113.876445 126.073552)
		(mid 113.768058 126.235764)
		(end 113.729998 126.427106)
		(width 0.2)
		(layer "B.Cu")
		(net 107)
	)
	(segment
		(start 114.58 126.834)
		(end 114.58 127.488)
		(width 0.2)
		(layer "F.Cu")
		(net 108)
	)
	(segment
		(start 115.211107 126.896893)
		(end 114.6 127.508)
		(width 0.2)
		(layer "F.Cu")
		(net 108)
	)
	(segment
		(start 116.838 126.604)
		(end 115.918214 126.604)
		(width 0.2)
		(layer "F.Cu")
		(net 108)
	)
	(via
		(at 114.58 126.834)
		(size 0.45)
		(drill 0.1)
		(layers "F.Cu" "B.Cu")
		(net 108)
	)
	(arc
		(start 115.211107 126.896893)
		(mid 115.53553 126.68012)
		(end 115.918214 126.604)
		(width 0.2)
		(layer "F.Cu")
		(net 108)
	)
	(segment
		(start 114.523553 127.933553)
		(end 114.456447 127.866448)
		(width 0.2)
		(layer "B.Cu")
		(net 108)
	)
	(segment
		(start 114.309998 127.512892)
		(end 114.309998 127.311109)
		(width 0.2)
		(layer "B.Cu")
		(net 108)
	)
	(segment
		(start 114.456445 126.957555)
		(end 114.58 126.834)
		(width 0.2)
		(layer "B.Cu")
		(net 108)
	)
	(segment
		(start 115.296 126.834)
		(end 114.58 126.834)
		(width 0.2)
		(layer "B.Cu")
		(net 108)
	)
	(segment
		(start 114.67 129.8)
		(end 114.670002 128.28711)
		(width 0.2)
		(layer "B.Cu")
		(net 108)
	)
	(arc
		(start 114.670002 128.28711)
		(mid 114.631941 128.095766)
		(end 114.523553 127.933553)
		(width 0.2)
		(layer "B.Cu")
		(net 108)
	)
	(arc
		(start 114.309998 127.311109)
		(mid 114.348058 127.119767)
		(end 114.456445 126.957555)
		(width 0.2)
		(layer "B.Cu")
		(net 108)
	)
	(arc
		(start 114.456447 127.866448)
		(mid 114.348059 127.704235)
		(end 114.309998 127.512892)
		(width 0.2)
		(layer "B.Cu")
		(net 108)
	)
	(segment
		(start 129.005 113.532107)
		(end 129.005 113.637107)
		(width 0.2)
		(layer "F.Cu")
		(net 109)
	)
	(segment
		(start 129.279802 113.050198)
		(end 129.151446 113.178554)
		(width 0.2)
		(layer "F.Cu")
		(net 109)
	)
	(segment
		(start 129.738356 112.903751)
		(end 129.633356 112.903751)
		(width 0.2)
		(layer "F.Cu")
		(net 109)
	)
	(arc
		(start 129.279802 113.050198)
		(mid 129.442014 112.941811)
		(end 129.633356 112.903751)
		(width 0.2)
		(layer "F.Cu")
		(net 109)
	)
	(arc
		(start 129.005 113.532107)
		(mid 129.04306 113.340766)
		(end 129.151446 113.178554)
		(width 0.2)
		(layer "F.Cu")
		(net 109)
	)
	(segment
		(start 128.505 117.316251)
		(end 128.505 118.804751)
		(width 0.2)
		(layer "F.Cu")
		(net 110)
	)
	(segment
		(start 117.275 128.541)
		(end 117.275 128.937893)
		(width 0.2)
		(layer "F.Cu")
		(net 111)
	)
	(segment
		(start 116.634393 129.5785)
		(end 116.275 129.5785)
		(width 0.2)
		(layer "F.Cu")
		(net 111)
	)
	(segment
		(start 117.128553 129.291447)
		(end 116.987946 129.432054)
		(width 0.2)
		(layer "F.Cu")
		(net 111)
	)
	(arc
		(start 117.128553 129.291447)
		(mid 117.23694 129.129235)
		(end 117.275 128.937893)
		(width 0.2)
		(layer "F.Cu")
		(net 111)
	)
	(arc
		(start 116.634393 129.5785)
		(mid 116.825734 129.54044)
		(end 116.987946 129.432054)
		(width 0.2)
		(layer "F.Cu")
		(net 111)
	)
	(segment
		(start 117.775 125.166)
		(end 117.775 123.6775)
		(width 0.2)
		(layer "F.Cu")
		(net 112)
	)
	(segment
		(start 119.471643 140.618363)
		(end 121.43711 138.652896)
		(width 0.2)
		(layer "F.Cu")
		(net 125)
	)
	(segment
		(start 121.730003 137.945785)
		(end 121.73 137.44)
		(width 0.2)
		(layer "F.Cu")
		(net 125)
	)
	(segment
		(start 119.17875 142.625466)
		(end 119.17875 141.32547)
		(width 0.2)
		(layer "F.Cu")
		(net 125)
	)
	(arc
		(start 121.730003 137.945785)
		(mid 121.653884 138.328471)
		(end 121.43711 138.652896)
		(width 0.2)
		(layer "F.Cu")
		(net 125)
	)
	(arc
		(start 119.17875 141.32547)
		(mid 119.25487 140.942787)
		(end 119.471643 140.618363)
		(width 0.2)
		(layer "F.Cu")
		(net 125)
	)
	(segment
		(start 120.790003 138.15578)
		(end 120.79 137.44)
		(width 0.2)
		(layer "F.Cu")
		(net 126)
	)
	(segment
		(start 118.97163 140.38834)
		(end 120.497103 138.862898)
		(width 0.2)
		(layer "F.Cu")
		(net 126)
	)
	(segment
		(start 118.67875 142.625466)
		(end 118.67873 141.095467)
		(width 0.2)
		(layer "F.Cu")
		(net 126)
	)
	(arc
		(start 118.97163 140.38834)
		(mid 118.75485 140.712772)
		(end 118.67873 141.095467)
		(width 0.2)
		(layer "F.Cu")
		(net 126)
	)
	(arc
		(start 120.790003 138.15578)
		(mid 120.713881 138.53847)
		(end 120.497103 138.862898)
		(width 0.2)
		(layer "F.Cu")
		(net 126)
	)
	(segment
		(start 123.95 143.75)
		(end 124.001472 143.75)
		(width 0.2)
		(layer "F.Cu")
		(net 132)
	)
	(segment
		(start 124.503014 143.496986)
		(end 124.425736 143.574264)
		(width 0.2)
		(layer "F.Cu")
		(net 132)
	)
	(segment
		(start 115.17875 144.07875)
		(end 115.17875 144.815466)
		(width 0.2)
		(layer "F.Cu")
		(net 132)
	)
	(segment
		(start 111.133 145.2)
		(end 111.133 145.793)
		(width 0.4)
		(layer "F.Cu")
		(net 132)
	)
	(segment
		(start 124.67875 142.625466)
		(end 124.67875 143.072722)
		(width 0.2)
		(layer "F.Cu")
		(net 132)
	)
	(segment
		(start 124.67875 142.625466)
		(end 124.67875 141.10125)
		(width 0.2)
		(layer "F.Cu")
		(net 132)
	)
	(via
		(at 147 118.5)
		(size 0.45)
		(drill 0.1)
		(layers "F.Cu" "B.Cu")
		(net 132)
	)
	(via
		(at 147 120.5)
		(size 0.45)
		(drill 0.1)
		(layers "F.Cu" "B.Cu")
		(free yes)
		(net 132)
	)
	(via
		(at 115.17875 144.07875)
		(size 0.45)
		(drill 0.1)
		(layers "F.Cu" "B.Cu")
		(net 132)
	)
	(via
		(at 111.133 145.2)
		(size 0.45)
		(drill 0.1)
		(layers "F.Cu" "B.Cu")
		(net 132)
	)
	(via
		(at 146 119.5)
		(size 0.45)
		(drill 0.1)
		(layers "F.Cu" "B.Cu")
		(free yes)
		(net 132)
	)
	(via
		(at 123.95 143.75)
		(size 0.45)
		(drill 0.1)
		(layers "F.Cu" "B.Cu")
		(net 132)
	)
	(arc
		(start 124.001472 143.75)
		(mid 124.231082 143.704328)
		(end 124.425736 143.574264)
		(width 0.2)
		(layer "F.Cu")
		(net 132)
	)
	(arc
		(start 124.503014 143.496986)
		(mid 124.633078 143.302332)
		(end 124.67875 143.072722)
		(width 0.2)
		(layer "F.Cu")
		(net 132)
	)
	(segment
		(start 144.7 116.499)
		(end 146.2 116.499)
		(width 0.4)
		(layer "F.Cu")
		(net 134)
	)
	(segment
		(start 144.407107 115.357107)
		(end 143.945893 114.895893)
		(width 0.4)
		(layer "F.Cu")
		(net 134)
	)
	(segment
		(start 144.7 116.499)
		(end 144.7 116.064214)
		(width 0.4)
		(layer "F.Cu")
		(net 134)
	)
	(segment
		(start 143.653 114.188786)
		(end 143.653 114.08)
		(width 0.4)
		(layer "F.Cu")
		(net 134)
	)
	(segment
		(start 143.653 112.851)
		(end 143.653 114.08)
		(width 0.4)
		(layer "F.Cu")
		(net 134)
	)
	(arc
		(start 144.407107 115.357107)
		(mid 144.62388 115.68153)
		(end 144.7 116.064214)
		(width 0.4)
		(layer "F.Cu")
		(net 134)
	)
	(arc
		(start 143.945893 114.895893)
		(mid 143.72912 114.57147)
		(end 143.653 114.188786)
		(width 0.4)
		(layer "F.Cu")
		(net 134)
	)
	(segment
		(start 144.844487 120.694487)
		(end 144.802512 120.652512)
		(width 0.4)
		(layer "F.Cu")
		(net 135)
	)
	(segment
		(start 144.947 121.671)
		(end 146.199 121.671)
		(width 0.4)
		(layer "F.Cu")
		(net 135)
	)
	(segment
		(start 144.947 121.671)
		(end 144.947 122.9)
		(width 0.4)
		(layer "F.Cu")
		(net 135)
	)
	(segment
		(start 144.7 120.405025)
		(end 144.7 119.25)
		(width 0.4)
		(layer "F.Cu")
		(net 135)
	)
	(segment
		(start 144.947 121.671)
		(end 144.947 120.941975)
		(width 0.4)
		(layer "F.Cu")
		(net 135)
	)
	(arc
		(start 144.802512 120.652512)
		(mid 144.726642 120.538964)
		(end 144.7 120.405025)
		(width 0.4)
		(layer "F.Cu")
		(net 135)
	)
	(arc
		(start 144.844487 120.694487)
		(mid 144.920358 120.808035)
		(end 144.947 120.941975)
		(width 0.4)
		(layer "F.Cu")
		(net 135)
	)
	(segment
		(start 145.554 112.851)
		(end 145.554 114.08)
		(width 0.2)
		(layer "F.Cu")
		(net 136)
	)
	(segment
		(start 144.604 110.251)
		(end 144.604 109.084)
		(width 0.2)
		(layer "F.Cu")
		(net 137)
	)
	(segment
		(start 143.046 122.9)
		(end 143.046 121.671)
		(width 0.2)
		(layer "F.Cu")
		(net 138)
	)
	(segment
		(start 143.996 125.5)
		(end 143.996 126.667)
		(width 0.2)
		(layer "F.Cu")
		(net 139)
	)
	(zone
		(net 52)
		(net_name "+5V")
		(layer "F.Cu")
		(hatch edge 0.5)
		(priority 6)
		(connect_pads
			(clearance 0.2)
		)
		(min_thickness 0.25)
		(filled_areas_thickness no)
		(fill yes
			(thermal_gap 0.25)
			(thermal_bridge_width 0.25)
			(smoothing fillet)
			(radius 1)
		)
		(polygon
			(pts
				(xy 144.8 137.5) (xy 137 137.5) (xy 137 134) (xy 142 134) (xy 142 124.75) (xy 145.5 124.75) (xy 145.5 136.8)
			)
		)
	)
	(zone
		(net 132)
		(net_name "+3V3_OCU")
		(layer "F.Cu")
		(hatch edge 0.5)
		(priority 9)
		(connect_pads
			(clearance 0.2)
		)
		(min_thickness 0.25)
		(filled_areas_thickness no)
		(fill yes
			(thermal_gap 0.5)
			(thermal_bridge_width 0.5)
		)
		(polygon
			(pts
				(xy 145.55 117.5) (xy 146.6 117.5) (xy 148 118.9) (xy 148 120.95) (xy 145.55 120.95)
			)
		)
	)
	(zone
		(net 23)
		(net_name "+3V3")
		(layer "F.Cu")
		(hatch edge 0.5)
		(priority 2)
		(connect_pads
			(clearance 0.2)
		)
		(min_thickness 0.15)
		(filled_areas_thickness no)
		(fill yes
			(thermal_gap 0.25)
			(thermal_bridge_width 0.25)
			(smoothing fillet)
			(radius 0.2)
		)
		(polygon
			(pts
				(xy 139.6 130.1) (xy 139.6 132.3) (xy 142 132.3) (xy 142 130.1)
			)
		)
	)
	(zone
		(net 133)
		(net_name "+5V_OCU")
		(layer "F.Cu")
		(hatch edge 0.5)
		(priority 4)
		(connect_pads
			(clearance 0.2)
		)
		(min_thickness 0.25)
		(filled_areas_thickness no)
		(fill yes
			(thermal_gap 0.25)
			(thermal_bridge_width 0.25)
			(smoothing fillet)
			(radius 1)
		)
		(polygon
			(pts
				(xy 148 122) (xy 145.5 121.991) (xy 145.5 136.8) (xy 144.8 137.5) (xy 140.5 137.5) (xy 136.5 141)
				(xy 134.5 141) (xy 132 143.5) (xy 115 143.5) (xy 115 140) (xy 110 140) (xy 110 150) (xy 148 150)
			)
		)
	)
	(zone
		(net 23)
		(net_name "+3V3")
		(layer "In1.Cu")
		(hatch edge 0.5)
		(priority 7)
		(connect_pads
			(clearance 0.2)
		)
		(min_thickness 0.15)
		(filled_areas_thickness no)
		(fill yes
			(thermal_gap 0.25)
			(thermal_bridge_width 0.25)
			(smoothing fillet)
			(radius 1)
		)
		(polygon
			(pts
				(xy 143 110) (xy 148 110) (xy 148 117.15) (xy 145.5 117.15) (xy 145.5 134.5) (xy 142.5 134.5) (xy 142.5 144)
				(xy 140.5 144) (xy 137.5 141) (xy 137.5 130) (xy 143 130)
			)
		)
	)
	(zone
		(net 132)
		(net_name "+3V3_OCU")
		(layer "In1.Cu")
		(hatch edge 0.5)
		(priority 1)
		(connect_pads
			(clearance 0.2)
		)
		(min_thickness 0.15)
		(filled_areas_thickness no)
		(fill yes
			(thermal_gap 0.25)
			(thermal_bridge_width 0.25)
			(smoothing fillet)
			(radius 1)
		)
		(polygon
			(pts
				(xy 148 117.15) (xy 145.5 117.15) (xy 145.5 134.5) (xy 142.5 134.5) (xy 142.5 144) (xy 140.5 144)
				(xy 137.5 141) (xy 134.5 141) (xy 132.5 143) (xy 124 143) (xy 121.001527 146.5) (xy 116 146.5) (xy 115.5 146)
				(xy 115.5 143.5) (xy 110 143.5) (xy 109.997325 146.899991) (xy 109.987108 149.998213) (xy 148 149.968098)
			)
		)
	)
	(zone
		(net 51)
		(net_name "GND")
		(layers "In1.Cu" "In2.Cu")
		(hatch edge 0.5)
		(connect_pads
			(clearance 0.2)
		)
		(min_thickness 0.15)
		(filled_areas_thickness no)
		(fill yes
			(thermal_gap 0.5)
			(thermal_bridge_width 0.5)
		)
		(polygon
			(pts
				(xy 148 149.968098) (xy 110 150) (xy 110.009704 90.009845) (xy 148 89.968699)
			)
		)
	)
	(zone
		(net 20)
		(net_name "+1V8")
		(layer "In2.Cu")
		(hatch edge 0.5)
		(priority 3)
		(connect_pads
			(clearance 0.2)
		)
		(min_thickness 0.15)
		(filled_areas_thickness no)
		(fill yes
			(thermal_gap 0.25)
			(thermal_bridge_width 0.25)
			(smoothing fillet)
			(radius 1)
		)
		(polygon
			(pts
				(xy 143 132.8) (xy 143 133.6) (xy 146.1 133.6) (xy 146.699998 134.2) (xy 146.7 142.3) (xy 148.073759 142.300186)
				(xy 147.999994 132.799298)
			)
		)
	)
	(zone
		(net 23)
		(net_name "+3V3")
		(layer "In2.Cu")
		(hatch edge 0.5)
		(priority 8)
		(connect_pads
			(clearance 0.15)
		)
		(min_thickness 0.25)
		(filled_areas_thickness no)
		(fill yes
			(thermal_gap 0.5)
			(thermal_bridge_width 0.5)
		)
		(polygon
			(pts
				(xy 118.4 110.4) (xy 120.1 110.4) (xy 120.1 112.3) (xy 129.4 112.3) (xy 129.4 121.7) (xy 142 121.7)
				(xy 142.042856 130.999803) (xy 140.5 132.5) (xy 126.1 132.5) (xy 126.1 129.9) (xy 117.7 129.9) (xy 117.7 123.5)
				(xy 118.4 123.5)
			)
		)
	)
	(zone
		(net 51)
		(net_name "GND")
		(layer "B.Cu")
		(hatch edge 0.5)
		(priority 5)
		(connect_pads
			(clearance 0.15)
		)
		(min_thickness 0.25)
		(filled_areas_thickness no)
		(fill yes
			(thermal_gap 0.5)
			(thermal_bridge_width 0.5)
		)
		(polygon
			(pts
				(xy 121.685 114.753251) (xy 128.325 114.753251) (xy 128.325 116.503251) (xy 121.685 116.503251)
			)
		)
	)
	(zone
		(net 51)
		(net_name "GND")
		(layer "B.Cu")
		(hatch edge 0.5)
		(priority 5)
		(connect_pads
			(clearance 0.15)
		)
		(min_thickness 0.25)
		(filled_areas_thickness no)
		(fill yes
			(thermal_gap 0.5)
			(thermal_bridge_width 0.5)
		)
		(polygon
			(pts
				(xy 124.595 127.729) (xy 117.955 127.729) (xy 117.955 125.979) (xy 124.595 125.979)
			)
		)
	)
)
